(kicad_pcb
	(version 20241229)
	(generator "pcbnew")
	(generator_version "9.0")
	(general
		(thickness 1.62)
		(legacy_teardrops no)
	)
	(paper "A3")
	(title_block
		(title "COM Express 7 Baseboard")
		(date "2025-02-04")
		(rev "1.1.2")
		(company "Antmicro Ltd")
		(comment 1 "www.antmicro.com")
	)
	(layers
		(0 "F.Cu" signal)
		(4 "In1.Cu" signal)
		(6 "In2.Cu" signal)
		(8 "In3.Cu" signal)
		(10 "In4.Cu" signal)
		(12 "In5.Cu" signal)
		(14 "In6.Cu" signal)
		(2 "B.Cu" signal)
		(9 "F.Adhes" user "F.Adhesive")
		(11 "B.Adhes" user "B.Adhesive")
		(13 "F.Paste" user)
		(15 "B.Paste" user)
		(5 "F.SilkS" user "F.Silkscreen")
		(7 "B.SilkS" user "B.Silkscreen")
		(1 "F.Mask" user)
		(3 "B.Mask" user)
		(17 "Dwgs.User" user "User.Drawings")
		(19 "Cmts.User" user "User.Comments")
		(21 "Eco1.User" user "User.Eco1")
		(23 "Eco2.User" user "User.Eco2")
		(25 "Edge.Cuts" user)
		(27 "Margin" user)
		(31 "F.CrtYd" user "F.Courtyard")
		(29 "B.CrtYd" user "B.Courtyard")
		(35 "F.Fab" user)
		(33 "B.Fab" user)
	)
	(setup
		(stackup
			(layer "F.SilkS"
				(type "Top Silk Screen")
				(color "White")
			)
			(layer "F.Paste"
				(type "Top Solder Paste")
			)
			(layer "F.Mask"
				(type "Top Solder Mask")
				(color "Black")
				(thickness 0.01)
			)
			(layer "F.Cu"
				(type "copper")
				(thickness 0.035)
			)
			(layer "dielectric 1"
				(type "prepreg")
				(thickness 0.12)
				(material "PR2116")
				(epsilon_r 4.2)
				(loss_tangent 0.02)
			)
			(layer "In1.Cu"
				(type "copper")
				(thickness 0.035)
			)
			(layer "dielectric 2"
				(type "core")
				(thickness 0.2)
				(material "FR4-Improved")
				(epsilon_r 4.3)
				(loss_tangent 0.02)
			)
			(layer "In2.Cu"
				(type "copper")
				(thickness 0.035)
			)
			(layer "dielectric 3"
				(type "prepreg")
				(thickness 0.12)
				(material "PR2116")
				(epsilon_r 4.2)
				(loss_tangent 0.02) addsublayer
				(thickness 0.12)
				(material "PR2116")
				(epsilon_r 4.2)
				(loss_tangent 0.02)
			)
			(layer "In3.Cu"
				(type "copper")
				(thickness 0.035)
			)
			(layer "dielectric 4"
				(type "core")
				(thickness 0.2)
				(material "FR4-Improved")
				(epsilon_r 4.3)
				(loss_tangent 0.02)
			)
			(layer "In4.Cu"
				(type "copper")
				(thickness 0.035)
			)
			(layer "dielectric 5"
				(type "prepreg")
				(thickness 0.12)
				(material "PR2116")
				(epsilon_r 4.2)
				(loss_tangent 0.02) addsublayer
				(thickness 0.12)
				(material "PR2116")
				(epsilon_r 4.2)
				(loss_tangent 0.02)
			)
			(layer "In5.Cu"
				(type "copper")
				(thickness 0.035)
			)
			(layer "dielectric 6"
				(type "core")
				(thickness 0.2)
				(material "FR4-Improved")
				(epsilon_r 4.3)
				(loss_tangent 0.02)
			)
			(layer "In6.Cu"
				(type "copper")
				(thickness 0.035)
			)
			(layer "dielectric 7"
				(type "prepreg")
				(thickness 0.12)
				(material "PR2116")
				(epsilon_r 4.2)
				(loss_tangent 0.02)
			)
			(layer "B.Cu"
				(type "copper")
				(thickness 0.035)
			)
			(layer "B.Mask"
				(type "Bottom Solder Mask")
				(color "Black")
				(thickness 0.01)
			)
			(layer "B.Paste"
				(type "Bottom Solder Paste")
			)
			(layer "B.SilkS"
				(type "Bottom Silk Screen")
				(color "White")
			)
			(copper_finish "None")
			(dielectric_constraints yes)
		)
		(pad_to_mask_clearance 0)
		(allow_soldermask_bridges_in_footprints no)
		(tenting front back)
		(aux_axis_origin 94.49 171.81)
		(grid_origin 161.93 167.8)
		(pcbplotparams
			(layerselection 0x00000000_00000000_55555555_5755f5ff)
			(plot_on_all_layers_selection 0x00000000_00000000_00000000_00000000)
			(disableapertmacros no)
			(usegerberextensions no)
			(usegerberattributes yes)
			(usegerberadvancedattributes yes)
			(creategerberjobfile yes)
			(dashed_line_dash_ratio 12.000000)
			(dashed_line_gap_ratio 3.000000)
			(svgprecision 4)
			(plotframeref no)
			(mode 1)
			(useauxorigin no)
			(hpglpennumber 1)
			(hpglpenspeed 20)
			(hpglpendiameter 15.000000)
			(pdf_front_fp_property_popups yes)
			(pdf_back_fp_property_popups yes)
			(pdf_metadata yes)
			(pdf_single_document no)
			(dxfpolygonmode yes)
			(dxfimperialunits yes)
			(dxfusepcbnewfont yes)
			(psnegative no)
			(psa4output no)
			(plot_black_and_white yes)
			(sketchpadsonfab no)
			(plotpadnumbers no)
			(hidednponfab no)
			(sketchdnponfab yes)
			(crossoutdnponfab yes)
			(subtractmaskfromsilk no)
			(outputformat 1)
			(mirror no)
			(drillshape 1)
			(scaleselection 1)
			(outputdirectory "")
		)
	)
	(net 0 "")
	(net 1 "GND")
	(net 2 "+3V3")
	(net 3 "/M.2 key E/WIFI_BT_USB_D_P")
	(net 4 "/M.2 key E/WIFI_BT_USB_D_N")
	(net 5 "/M.2 key E/~{LED_1}")
	(net 6 "/M.2 key E/~{LED_2}")
	(net 7 "unconnected-(J100-PCM_CLK-Pad8)")
	(net 8 "unconnected-(J100-SDIO_CLK-Pad9)")
	(net 9 "/Com Express 7 Interfaces/PCIe_{B1x2}.TX0+")
	(net 10 "unconnected-(J100-PCM_SYNC-Pad10)")
	(net 11 "/Com Express 7 Interfaces/PCIe_{B1x2}.TX0-")
	(net 12 "unconnected-(J100-SDIO_CMD-Pad11)")
	(net 13 "unconnected-(J100-PCM_IN-Pad12)")
	(net 14 "/Com Express 7 Interfaces/PCIe_{B1x2}.RX0+")
	(net 15 "unconnected-(J100-SDIO_D0-Pad13)")
	(net 16 "/Com Express 7 Interfaces/PCIe_{B1x2}.RX0-")
	(net 17 "unconnected-(J100-PCM_OUT-Pad14)")
	(net 18 "unconnected-(J100-SDIO_D1-Pad15)")
	(net 19 "/M.2 key E/PCIE_{REF}.CK+")
	(net 20 "unconnected-(J100-SDIO_D2-Pad17)")
	(net 21 "/M.2 key E/PCIE_{REF}.CK-")
	(net 22 "unconnected-(J100-SDIO_D3-Pad19)")
	(net 23 "/M.2 key E/~{PERST_D}")
	(net 24 "/M.2 key E/~{CLKREQ}")
	(net 25 "unconnected-(J100-~{UART_WAKE}-Pad20)")
	(net 26 "unconnected-(J100-SDIO_~{WAKE}-Pad21)")
	(net 27 "unconnected-(J100-UART_RXD-Pad22)")
	(net 28 "unconnected-(J100-SDIO_~{RESET}-Pad23)")
	(net 29 "unconnected-(J100-UART_TXD-Pad32)")
	(net 30 "unconnected-(J100-UART_CTS-Pad34)")
	(net 31 "unconnected-(J100-UART_RTS-Pad36)")
	(net 32 "unconnected-(J100-VENDOR_1-Pad38)")
	(net 33 "unconnected-(J100-VENDOR_2-Pad40)")
	(net 34 "unconnected-(J100-VENDOR_3-Pad42)")
	(net 35 "unconnected-(J100-COEX3-Pad44)")
	(net 36 "unconnected-(J100-COEX_TXD-Pad46)")
	(net 37 "unconnected-(J100-COEX_RXD-Pad48)")
	(net 38 "Net-(J100-SUSCLK)")
	(net 39 "unconnected-(J100-W_DISABLE2-Pad54)")
	(net 40 "unconnected-(J100-~{PEWAKE0}-Pad55)")
	(net 41 "Net-(BT1-+)")
	(net 42 "/2xUSB3.0+RJ45/P1_VBUS")
	(net 43 "/2xUSB3.0+RJ45/P2_VBUS")
	(net 44 "/2xUSB3.0+RJ45/USBSS_1.TX+")
	(net 45 "/2xUSB3.0+RJ45/USBSS_2.TX+")
	(net 46 "Net-(U34-OFFT)")
	(net 47 "/2xUSB3.0+RJ45/USBSS_1.TX-")
	(net 48 "Net-(U34-ONT)")
	(net 49 "/2xUSB3.0+RJ45/USBSS_2.TX-")
	(net 50 "Net-(C12-Pad2)")
	(net 51 "Net-(C13-Pad1)")
	(net 52 "+5V")
	(net 53 "/2xSFP+/SH")
	(net 54 "/USB-C console/SH")
	(net 55 "/USB-C console/USB_D+")
	(net 56 "/USB-C console/USB_D-")
	(net 57 "/USB-C console/FTDI_VCCIO")
	(net 58 "/USB-C console/VBUS_FTDI")
	(net 59 "/OCuLink/V_{ACT_TX}0")
	(net 60 "/OCuLink/V_{ACT_RX}0")
	(net 61 "/OCuLink/5V_CONN0")
	(net 62 "+12V_AON")
	(net 63 "Net-(U18-V_{CC})")
	(net 64 "Net-(U19-V_{CC})")
	(net 65 "+12V")
	(net 66 "Net-(U18-BST)")
	(net 67 "Net-(C47-Pad2)")
	(net 68 "Net-(U19-BST)")
	(net 69 "Net-(C48-Pad2)")
	(net 70 "Net-(C49-Pad2)")
	(net 71 "Net-(U49-IN+)")
	(net 72 "Net-(U20-CT)")
	(net 73 "+3V3_AON")
	(net 74 "+1V0")
	(net 75 "Net-(U50-IN+)")
	(net 76 "Net-(C63-Pad2)")
	(net 77 "+5V_AON")
	(net 78 "+1V8")
	(net 79 "Net-(U23-VOUT)")
	(net 80 "Net-(Q6-D)")
	(net 81 "/Misc/FAN_12V")
	(net 82 "Net-(U32-CT)")
	(net 83 "Net-(Q11-D)")
	(net 84 "/Com Express 7 MGMT/PWRBTN")
	(net 85 "/Com Express 7 MGMT/MAFS_POWER")
	(net 86 "/Com Express 7 Interfaces/PCIe_{B2Ax4}.RX0-")
	(net 87 "/Com Express 7 Interfaces/PCIe_{B2Ax4}.RX1-")
	(net 88 "/Com Express 7 Interfaces/PCIe_{B2Ax4}.RX2-")
	(net 89 "/Com Express 7 Interfaces/PCIe_{B2Ax4}.RX3-")
	(net 90 "/Com Express 7 Interfaces/PCIe_{B2Ax4}.RX0+")
	(net 91 "/Com Express 7 Interfaces/PCIe_{B2Ax4}.RX1+")
	(net 92 "/Com Express 7 Interfaces/PCIe_{B2Ax4}.RX2+")
	(net 93 "/Com Express 7 Interfaces/PCIe_{B2Ax4}.RX3+")
	(net 94 "/PCIe redriver/PCIe_{O}_C.TX3+")
	(net 95 "/OCuLink/PCIe_{x4}.TX0-")
	(net 96 "/OCuLink/PCIe_{x4}.TX1-")
	(net 97 "/OCuLink/PCIe_{x4}.TX2-")
	(net 98 "/OCuLink/PCIe_{x4}.TX3-")
	(net 99 "/PCIe redriver/PCIe_{O}_C.TX3-")
	(net 100 "/OCuLink/PCIe_{x4}.TX0+")
	(net 101 "/PCIe redriver/PCIe_{I}_C.RX0-")
	(net 102 "/OCuLink/PCIe_{x4}.TX1+")
	(net 103 "/PCIe redriver/PCIe_{I}_C.RX1-")
	(net 104 "/OCuLink/PCIe_{x4}.TX2+")
	(net 105 "/PCIe redriver/PCIe_{I}_C.RX2-")
	(net 106 "/OCuLink/PCIe_{x4}.TX3+")
	(net 107 "/2xSFP+/KR to SFI #1/CLK+")
	(net 108 "/2xSFP+/KR to SFI #1/REFCLK+")
	(net 109 "/2xSFP+/KR to SFI #1/CLK-")
	(net 110 "/2xSFP+/KR to SFI #1/REFCLK-")
	(net 111 "/2xSFP+/10GKR_SFP0.TX+")
	(net 112 "/2xSFP+/KR to SFI #1/KR_C.TX+")
	(net 113 "/2xSFP+/10GKR_SFP0.TX-")
	(net 114 "/2xSFP+/KR to SFI #1/KR_C.TX-")
	(net 115 "/2xSFP+/KR to SFI #2/CLK+")
	(net 116 "/2xSFP+/KR to SFI #2/REFCLK+")
	(net 117 "/2xSFP+/KR to SFI #2/CLK-")
	(net 118 "/2xSFP+/KR to SFI #2/REFCLK-")
	(net 119 "/2xSFP+/10GKR_SFP1.TX+")
	(net 120 "/2xSFP+/KR to SFI #2/KR_C.TX+")
	(net 121 "/2xSFP+/10GKR_SFP1.TX-")
	(net 122 "/2xSFP+/KR to SFI #2/KR_C.TX-")
	(net 123 "/2xUSB3.0+RJ45/P1_D-")
	(net 124 "/2xUSB3.0+RJ45/P1_D+")
	(net 125 "/2xUSB3.0+RJ45/P2_D-")
	(net 126 "/2xUSB3.0+RJ45/P2_D+")
	(net 127 "/USB-C console/FTDI_LED_RX")
	(net 128 "/USB-C console/FTDI_LED_TX")
	(net 129 "Net-(D17-C_{R})")
	(net 130 "Net-(D17-C_{G})")
	(net 131 "Net-(D17-C_{B})")
	(net 132 "Net-(D18-C_{R})")
	(net 133 "Net-(D18-C_{G})")
	(net 134 "unconnected-(D18-C_{B}-Pad3)")
	(net 135 "Net-(D19-Pad3)")
	(net 136 "/Com Express 7 MGMT/~{TYPE0}")
	(net 137 "/Com Express 7 MGMT/~{TYPE2}")
	(net 138 "Net-(U33-1A)")
	(net 139 "/Com Express 7 MGMT/SPI_POWER")
	(net 140 "unconnected-(D21-Pad2)")
	(net 141 "/2xSFP+/KR to SFI #1/~{RESET}")
	(net 142 "/2xSFP+/PHY0_{RESET}")
	(net 143 "/2xSFP+/KR to SFI #2/~{RESET}")
	(net 144 "VCC")
	(net 145 "Net-(D24-C)")
	(net 146 "/2xUSB3.0+RJ45/DA+")
	(net 147 "/2xUSB3.0+RJ45/DA-")
	(net 148 "/2xUSB3.0+RJ45/DB+")
	(net 149 "/2xUSB3.0+RJ45/DC+")
	(net 150 "/2xUSB3.0+RJ45/DC-")
	(net 151 "/2xUSB3.0+RJ45/DB-")
	(net 152 "/2xUSB3.0+RJ45/DD+")
	(net 153 "/2xUSB3.0+RJ45/DD-")
	(net 154 "Net-(J1A-LED_D1)")
	(net 155 "Net-(J1A-LED_D2)")
	(net 156 "Net-(J1A-LED_D3)")
	(net 157 "Net-(J1A-LED_D4)")
	(net 158 "/2xUSB3.0+RJ45/USBSS_1.RX-")
	(net 159 "/2xUSB3.0+RJ45/USBSS_1.RX+")
	(net 160 "/2xUSB3.0+RJ45/USBSS_2.RX-")
	(net 161 "/2xUSB3.0+RJ45/USBSS_2.RX+")
	(net 162 "Net-(J2A-TX_{FAULT})")
	(net 163 "Net-(J2A-TX_{DISABLE})")
	(net 164 "/2xSFP+/SDA0")
	(net 165 "/2xSFP+/SCL0")
	(net 166 "Net-(J2A-MOD_{ABS})")
	(net 167 "Net-(J2A-RS0)")
	(net 168 "Net-(J2A-RX_{LOS})")
	(net 169 "Net-(J2A-RS1)")
	(net 170 "/2xSFP+/SFI0.RX-")
	(net 171 "/2xSFP+/SFI0.RX+")
	(net 172 "/2xSFP+/SFI0.TX+")
	(net 173 "/2xSFP+/SFI0.TX-")
	(net 174 "unconnected-(J3-TX_{1}+-PadA2)")
	(net 175 "unconnected-(J3-TX_{1}--PadA3)")
	(net 176 "Net-(J3-CC_{1})")
	(net 177 "unconnected-(J3-SBU_{1}-PadA8)")
	(net 178 "unconnected-(J3-RX_{2}--PadA10)")
	(net 179 "unconnected-(J3-RX_{2}+-PadA11)")
	(net 180 "unconnected-(J3-TX_{2}+-PadB2)")
	(net 181 "unconnected-(J3-TX_{2}--PadB3)")
	(net 182 "Net-(J3-CC_{2})")
	(net 183 "unconnected-(J3-SBU_{2}-PadB8)")
	(net 184 "unconnected-(J3-RX_{1}--PadB10)")
	(net 185 "unconnected-(J3-RX_{1}+-PadB11)")
	(net 186 "/OCuLink/PCIe_{x4}.RX0+")
	(net 187 "/OCuLink/PCIe_{x4}.RX0-")
	(net 188 "/OCuLink/PCIe_{x4}.RX1+")
	(net 189 "/OCuLink/PCIe_{x4}.RX1-")
	(net 190 "unconnected-(J4-NC-PadA9)")
	(net 191 "unconnected-(J4-~{CWAKE}-PadA10)")
	(net 192 "/OCuLink/PCIe_{REF0}.CK+")
	(net 193 "/OCuLink/PCIe_{REF0}.CK-")
	(net 194 "/OCuLink/PCIe_{x4}.RX2+")
	(net 195 "/OCuLink/PCIe_{x4}.RX2-")
	(net 196 "/OCuLink/PCIe_{x4}.RX3+")
	(net 197 "/OCuLink/PCIe_{x4}.RX3-")
	(net 198 "/OCuLink/SCL")
	(net 199 "/OCuLink/SDA")
	(net 200 "/OCuLink/~{PERST_D0}")
	(net 201 "/OCuLink/~{CPRSNT_D0}")
	(net 202 "unconnected-(U12-Pad1)")
	(net 203 "/Backplane/PCIe_{REF}.CK+")
	(net 204 "/Backplane/USB.D-")
	(net 205 "/Backplane/PCIe_{REF}.CK-")
	(net 206 "/Backplane/USB.D+")
	(net 207 "/Backplane/UART.TX")
	(net 208 "/Backplane/UART.RX")
	(net 209 "/Com Express 7 Interfaces/PCIe_{B1x4}.RX3-")
	(net 210 "/Com Express 7 Interfaces/PCIe_{B1x4}.RX3+")
	(net 211 "/Com Express 7 Interfaces/PCIe_{B1x4}.TX3-")
	(net 212 "/Com Express 7 Interfaces/PCIe_{B1x4}.TX3+")
	(net 213 "/Com Express 7 Interfaces/PCIe_{B1x4}.RX2-")
	(net 214 "/Com Express 7 Interfaces/PCIe_{B1x4}.RX2+")
	(net 215 "/Com Express 7 Interfaces/PCIe_{B1x4}.TX2-")
	(net 216 "/Com Express 7 Interfaces/PCIe_{B1x4}.TX2+")
	(net 217 "/Com Express 7 Interfaces/PCIe_{B1x4}.RX1-")
	(net 218 "/Com Express 7 Interfaces/PCIe_{B1x4}.RX1+")
	(net 219 "/Com Express 7 Interfaces/PCIe_{B1x4}.TX1-")
	(net 220 "/Com Express 7 Interfaces/PCIe_{B1x4}.TX1+")
	(net 221 "/Com Express 7 Interfaces/PCIe_{B1x4}.RX0-")
	(net 222 "/Com Express 7 Interfaces/PCIe_{B1x4}.RX0+")
	(net 223 "unconnected-(J5-NC-Pad6)")
	(net 224 "unconnected-(J5-NC-Pad8)")
	(net 225 "/Com Express 7 Interfaces/PCIe_{B1x4}.TX0-")
	(net 226 "unconnected-(J5-NC-Pad20)")
	(net 227 "/Com Express 7 Interfaces/PCIe_{B1x4}.TX0+")
	(net 228 "/M.2 key M #1/~{PERST_D}")
	(net 229 "/M.2 key M #1/PCIE_{REF}.CK-")
	(net 230 "unconnected-(J5-NC-Pad22)")
	(net 231 "/M.2 key M #1/PCIE_{REF}.CK+")
	(net 232 "unconnected-(J5-NC-Pad24)")
	(net 233 "unconnected-(J5-NC-Pad26)")
	(net 234 "unconnected-(J5-NC-Pad28)")
	(net 235 "unconnected-(J5-NC-Pad30)")
	(net 236 "unconnected-(J5-NC-Pad32)")
	(net 237 "/Com Express 7 Interfaces/PCIe_{B2Bx4}.RX3-")
	(net 238 "unconnected-(J8-NC-Pad6)")
	(net 239 "/Com Express 7 Interfaces/PCIe_{B2Bx4}.RX3+")
	(net 240 "unconnected-(J8-NC-Pad8)")
	(net 241 "/Com Express 7 Interfaces/PCIe_{B2Bx4}.TX3-")
	(net 242 "/Com Express 7 Interfaces/PCIe_{B2Bx4}.TX3+")
	(net 243 "/Com Express 7 Interfaces/PCIe_{B2Bx4}.RX2-")
	(net 244 "/Com Express 7 Interfaces/PCIe_{B2Bx4}.RX2+")
	(net 245 "unconnected-(J8-NC-Pad20)")
	(net 246 "unconnected-(J8-NC-Pad22)")
	(net 247 "/Com Express 7 Interfaces/PCIe_{B2Bx4}.TX2-")
	(net 248 "unconnected-(J8-NC-Pad24)")
	(net 249 "/Com Express 7 Interfaces/PCIe_{B2Bx4}.TX2+")
	(net 250 "unconnected-(J8-NC-Pad26)")
	(net 251 "unconnected-(J8-NC-Pad28)")
	(net 252 "/Com Express 7 Interfaces/PCIe_{B2Bx4}.RX1-")
	(net 253 "unconnected-(J8-NC-Pad30)")
	(net 254 "/Com Express 7 Interfaces/PCIe_{B2Bx4}.RX1+")
	(net 255 "unconnected-(J8-NC-Pad32)")
	(net 256 "unconnected-(J8-NC-Pad34)")
	(net 257 "/Com Express 7 Interfaces/PCIe_{B2Bx4}.TX1-")
	(net 258 "unconnected-(J8-NC-Pad36)")
	(net 259 "/Com Express 7 Interfaces/PCIe_{B2Bx4}.TX1+")
	(net 260 "unconnected-(J8-NC-Pad38)")
	(net 261 "unconnected-(J8-SMB_CLK-Pad40)")
	(net 262 "/Com Express 7 Interfaces/PCIe_{B2Bx4}.RX0-")
	(net 263 "unconnected-(J8-SMB_DATA-Pad42)")
	(net 264 "/Com Express 7 Interfaces/PCIe_{B2Bx4}.RX0+")
	(net 265 "unconnected-(J8-ALERT-Pad44)")
	(net 266 "unconnected-(J8-NC-Pad46)")
	(net 267 "/Com Express 7 Interfaces/PCIe_{B2Bx4}.TX0-")
	(net 268 "unconnected-(J8-NC-Pad48)")
	(net 269 "/Com Express 7 Interfaces/PCIe_{B2Bx4}.TX0+")
	(net 270 "/M.2 key M #2/~{PERST_D}")
	(net 271 "/M.2 key M #2/PCIE_{REF}.CK-")
	(net 272 "unconnected-(J8-~{PEWAKE}-Pad54)")
	(net 273 "/M.2 key M #2/PCIE_{REF}.CK+")
	(net 274 "unconnected-(J8-NC-Pad56)")
	(net 275 "unconnected-(J8-NC-Pad58)")
	(net 276 "unconnected-(J8-NC-Pad67)")
	(net 277 "Net-(J8-SUSCLK)")
	(net 278 "unconnected-(J8-NC-Pad69)")
	(net 279 "/Misc/TACH_{A5V}")
	(net 280 "/Misc/PWM_{A5V}")
	(net 281 "/Misc/TACH_{B5V}")
	(net 282 "/Misc/PWM_{B5V}")
	(net 283 "/Misc/TACH_{C5V}")
	(net 284 "/Misc/PWM_{C5V}")
	(net 285 "/2xUSB3.0+RJ45/GbE.MDI3-")
	(net 286 "/2xUSB3.0+RJ45/GbE.MDI3+")
	(net 287 "unconnected-(J12B-~{GBE0_LINK100}-PadA4)")
	(net 288 "/2xUSB3.0+RJ45/~{GBE0_LINK_1000}")
	(net 289 "/2xUSB3.0+RJ45/GbE.MDI2-")
	(net 290 "/2xUSB3.0+RJ45/GbE.MDI2+")
	(net 291 "/2xUSB3.0+RJ45/~{GBE0_LINK}")
	(net 292 "/2xUSB3.0+RJ45/GbE.MDI1-")
	(net 293 "/2xUSB3.0+RJ45/GbE.MDI1+")
	(net 294 "/2xUSB3.0+RJ45/GbE.MDI0-")
	(net 295 "/2xUSB3.0+RJ45/GbE.MDI0+")
	(net 296 "/2xUSB3.0+RJ45/GbE.CTREF")
	(net 297 "Net-(J12D-~{SUS_S3})")
	(net 298 "unconnected-(J12F-SATA0_TX+-PadA16)")
	(net 299 "unconnected-(J12F-SATA0_TX--PadA17)")
	(net 300 "Net-(J12D-~{SUS_S4})")
	(net 301 "unconnected-(J12F-SATA0_RX+-PadA19)")
	(net 302 "unconnected-(J12F-SATA0_RX--PadA20)")
	(net 303 "/Com Express 7 MGMT/~{SUS_S5}")
	(net 304 "Net-(J12D-~{BATLOW})")
	(net 305 "unconnected-(J12F-~{(S)ATA_ACT}-PadA28)")
	(net 306 "unconnected-(J12H-RSVD-PadA29)")
	(net 307 "unconnected-(J12H-RSVD-PadA30)")
	(net 308 "unconnected-(J12H-RSVD-PadA32)")
	(net 309 "unconnected-(J12H-RSVD-PadA33)")
	(net 310 "/Com Express 7 MGMT/~{BIOS_DIS0}")
	(net 311 "Net-(J12D-~{THRMTRIP})")
	(net 312 "/2xUSB3.0+RJ45/USB_1.D-")
	(net 313 "/2xUSB3.0+RJ45/USB_1.D+")
	(net 314 "/2xUSB3.0+RJ45/FLG_1")
	(net 315 "Net-(J12H-VCC_RTC)")
	(net 316 "unconnected-(J12H-RSVD-PadA48)")
	(net 317 "unconnected-(J12B-GBE0_SDP-PadA49)")
	(net 318 "Net-(J12D-LPC_SERIRQ{slash}~{ESPI_CS1})")
	(net 319 "/Com Express 7 Interfaces/PCIe_{B1x2}.TX1+")
	(net 320 "/Com Express 7 Interfaces/PCIe_{B1x2}.TX1-")
	(net 321 "/Com Express 7 Interfaces/SDIO.DAT0")
	(net 322 "/Com Express 7 Interfaces/SDIO.DAT1")
	(net 323 "/Com Express 7 Interfaces/SDIO.DAT2")
	(net 324 "/Com Express 7 Interfaces/PCIe_{B2Ax4}.TX0+")
	(net 325 "/Com Express 7 Interfaces/PCIe_{B2Ax4}.TX0-")
	(net 326 "/Com Express 7 Interfaces/PCIe_{B2Ax4}.TX1+")
	(net 327 "/Com Express 7 Interfaces/PCIe_{B2Ax4}.TX1-")
	(net 328 "/Com Express 7 Interfaces/PCIe_{B2Ax4}.TX2+")
	(net 329 "/Com Express 7 Interfaces/PCIe_{B2Ax4}.TX2-")
	(net 330 "/Com Express 7 Interfaces/PCIe_{B2Ax4}.TX3+")
	(net 331 "/Com Express 7 Interfaces/PCIe_{B2Ax4}.TX3-")
	(net 332 "unconnected-(J12A-NCSI_TX_EN-PadA84)")
	(net 333 "/Com Express 7 Interfaces/SDIO.DAT3")
	(net 334 "unconnected-(J12H-RSVD-PadA86)")
	(net 335 "unconnected-(J12H-RSVD-PadA87)")
	(net 336 "/Com Express 7 Interfaces/PCIE_{REF}.CK+")
	(net 337 "/Com Express 7 Interfaces/PCIE_{REF}.CK-")
	(net 338 "/Com Express 7 MGMT/SPI.MISO")
	(net 339 "/Com Express 7 Interfaces/SDIO.CLK")
	(net 340 "/Com Express 7 MGMT/SPI.CLK")
	(net 341 "/Com Express 7 MGMT/SPI.MOSI")
	(net 342 "Net-(J12D-TPM_PP)")
	(net 343 "Net-(J12D-~{TYPE10})")
	(net 344 "/Com Express 7 MGMT/SER0.TX")
	(net 345 "/Com Express 7 MGMT/SER0.RX")
	(net 346 "unconnected-(J12D-~{LID}-PadA103)")
	(net 347 "/2xUSB3.0+RJ45/~{GBE0_ACT}")
	(net 348 "Net-(J12D-~{LPC_FRAME}{slash}~{ESPI_CS0})")
	(net 349 "Net-(J12D-LPC_AD0{slash}ESPI_IO_0)")
	(net 350 "Net-(J12D-LPC_AD1{slash}ESPI_IO_1)")
	(net 351 "Net-(J12D-LPC_AD2{slash}ESPI_IO_2)")
	(net 352 "Net-(J12D-LPC_AD3{slash}ESPI_IO_3)")
	(net 353 "Net-(J12D-~{LPC_DRQ0}{slash}~{ESPI_ALERT0})")
	(net 354 "Net-(J12D-~{LPC_DRQ1}{slash}~{ESPI_ALERT1})")
	(net 355 "Net-(J12D-LPC_CLK{slash}ESPI_CK)")
	(net 356 "/Com Express 7 MGMT/~{CW_PWRBTN}")
	(net 357 "/Com Express 7 MGMT/SMBus.SCL")
	(net 358 "/Com Express 7 MGMT/SMBus.SDA")
	(net 359 "/Com Express 7 MGMT/SMBus.~{INT}")
	(net 360 "unconnected-(J12F-SATA1_TX+-PadB16)")
	(net 361 "unconnected-(J12F-SATA1_TX--PadB17)")
	(net 362 "Net-(J12D-~{SUS_STAT}{slash}~{ESPI_RESET})")
	(net 363 "unconnected-(J12F-SATA1_RX+-PadB19)")
	(net 364 "unconnected-(J12F-SATA1_RX--PadB20)")
	(net 365 "/Com Express 7 MGMT/PWR_OK")
	(net 366 "Net-(J12D-WDT)")
	(net 367 "unconnected-(J12H-RSVD-PadB28)")
	(net 368 "unconnected-(J12H-RSVD-PadB29)")
	(net 369 "unconnected-(J12H-RSVD-PadB30)")
	(net 370 "Net-(J12D-SPKR)")
	(net 371 "/Com Express 7 MGMT/I2C.SCL")
	(net 372 "/Com Express 7 MGMT/I2C.SDA")
	(net 373 "Net-(J12D-~{THRM})")
	(net 374 "/2xUSB3.0+RJ45/USB_2.D-")
	(net 375 "/2xUSB3.0+RJ45/USB_2.D+")
	(net 376 "unconnected-(J12G-~{USB_0_1_OC}-PadB44)")
	(net 377 "/Com Express 7 Interfaces/USB1.D-")
	(net 378 "/Com Express 7 Interfaces/USB1.D+")
	(net 379 "Net-(J12D-~{ESPI_EN})")
	(net 380 "Net-(J12G-USB0_HOST_PRSNT)")
	(net 381 "Net-(J12D-~{SYS_RESET})")
	(net 382 "Net-(J12D-~{CB_RESET})")
	(net 383 "/Com Express 7 Interfaces/PCIe_{B1x2}.RX1+")
	(net 384 "/Com Express 7 Interfaces/PCIe_{B1x2}.RX1-")
	(net 385 "/Com Express 7 Interfaces/SDIO.CMD")
	(net 386 "/Com Express 7 Interfaces/SD_WP")
	(net 387 "unconnected-(J12D-~{WAKE0}-PadB66)")
	(net 388 "unconnected-(J12D-~{WAKE1}-PadB67)")
	(net 389 "Net-(J12D-~{BIOS_DIS1})")
	(net 390 "unconnected-(J12A-NCSI_RX_ER-PadB89)")
	(net 391 "unconnected-(J12A-NCSI_CLK_IN-PadB91)")
	(net 392 "unconnected-(J12A-NCSI_RXD1-PadB92)")
	(net 393 "unconnected-(J12A-NCSI_RXD0-PadB93)")
	(net 394 "unconnected-(J12A-NCSI_CRS_DV-PadB94)")
	(net 395 "unconnected-(J12A-NCSI_TXD1-PadB95)")
	(net 396 "unconnected-(J12A-NCSI_TXD0-PadB96)")
	(net 397 "/Com Express 7 MGMT/SPI.~{CS}")
	(net 398 "unconnected-(J12A-NCSI_ARB_IN-PadB98)")
	(net 399 "unconnected-(J12A-NCSI_ARB_OUT-PadB99)")
	(net 400 "/Com Express 7 MGMT/FAN_PWM")
	(net 401 "/Com Express 7 MGMT/FAM_TACH")
	(net 402 "unconnected-(J12D-~{SLEEP}-PadB103)")
	(net 403 "unconnected-(J12J-USB_SSRX0--PadC3)")
	(net 404 "unconnected-(J12J-USB_SSRX0+-PadC4)")
	(net 405 "unconnected-(J12J-USB_SSRX1--PadC6)")
	(net 406 "unconnected-(J12J-USB_SSRX1+-PadC7)")
	(net 407 "unconnected-(J12K-10G_PHY_MDC_SCL3-PadC15)")
	(net 408 "unconnected-(J12K-10G_PHY_MDC_SCL2-PadC16)")
	(net 409 "Net-(J12K-10G_SDP2)")
	(net 410 "unconnected-(J12O-PCIE_RX6+-PadC19)")
	(net 411 "unconnected-(J12O-PCIE_RX6--PadC20)")
	(net 412 "unconnected-(J12O-PCIE_RX7+-PadC22)")
	(net 413 "unconnected-(J12O-PCIE_RX7--PadC23)")
	(net 414 "unconnected-(J12K-10G_INT2-PadC24)")
	(net 415 "unconnected-(J12K-10G_KR_RX3+-PadC26)")
	(net 416 "unconnected-(J12K-10G_KR_RX3--PadC27)")
	(net 417 "unconnected-(J12K-10G_KR_RX2+-PadC29)")
	(net 418 "unconnected-(J12K-10G_KR_RX2--PadC30)")
	(net 419 "unconnected-(J12K-10G_SFP_SDA3-PadC32)")
	(net 420 "unconnected-(J12K-10G_SFP_SDA2-PadC33)")
	(net 421 "unconnected-(J12K-10G_PHY_RST_23-PadC34)")
	(net 422 "/2xSFP+/I2C_{LED}.SDA")
	(net 423 "/2xSFP+/I2C_{LED}.SCL")
	(net 424 "/2xSFP+/I2C_{SFP1}.SDA")
	(net 425 "/2xSFP+/I2C_{SFP0}.SDA")
	(net 426 "Net-(J12K-10G_SDP0)")
	(net 427 "/2xSFP+/10GKR_SFP1.RX+")
	(net 428 "/2xSFP+/10GKR_SFP1.RX-")
	(net 429 "/2xSFP+/MDIO1.MDC")
	(net 430 "/2xSFP+/MDIO0.MDC")
	(net 431 "/2xSFP+/MOD0_ABS")
	(net 432 "/2xSFP+/10GKR_SFP0.RX+")
	(net 433 "/2xSFP+/10GKR_SFP0.RX-")
	(net 434 "/Com Express 7 MGMT/~{TYPE1}")
	(net 435 "unconnected-(J12M-RSVD-PadC63)")
	(net 436 "unconnected-(J12M-RSVD-PadC64)")
	(net 437 "unconnected-(J12N-PCIE_RX20+-PadC65)")
	(net 438 "unconnected-(J12N-PCIE_RX20--PadC66)")
	(net 439 "Net-(J12L-RAPID_SHUTDOWN)")
	(net 440 "unconnected-(J12N-PCIE_RX21+-PadC68)")
	(net 441 "unconnected-(J12N-PCIE_RX21--PadC69)")
	(net 442 "unconnected-(J12N-PCIE_RX22+-PadC71)")
	(net 443 "unconnected-(J12N-PCIE_RX22--PadC72)")
	(net 444 "unconnected-(J12N-PCIE_RX23+-PadC74)")
	(net 445 "unconnected-(J12N-PCIE_RX23--PadC75)")
	(net 446 "unconnected-(J12M-RSVD-PadC77)")
	(net 447 "unconnected-(J12N-PCIE_RX24+-PadC78)")
	(net 448 "unconnected-(J12N-PCIE_RX24--PadC79)")
	(net 449 "unconnected-(J12N-PCIE_RX25+-PadC81)")
	(net 450 "unconnected-(J12N-PCIE_RX25--PadC82)")
	(net 451 "unconnected-(J12M-RSVD-PadC83)")
	(net 452 "unconnected-(J12N-PCIE_RX26+-PadC85)")
	(net 453 "unconnected-(J12N-PCIE_RX26--PadC86)")
	(net 454 "unconnected-(J12N-PCIE_RX27+-PadC88)")
	(net 455 "unconnected-(J12N-PCIE_RX27--PadC89)")
	(net 456 "unconnected-(J12N-PCIE_RX28+-PadC91)")
	(net 457 "unconnected-(J12N-PCIE_RX28--PadC92)")
	(net 458 "unconnected-(J12N-PCIE_RX29+-PadC94)")
	(net 459 "unconnected-(J12N-PCIE_RX29--PadC95)")
	(net 460 "unconnected-(J12M-RSVD-PadC97)")
	(net 461 "unconnected-(J12N-PCIE_RX30+-PadC98)")
	(net 462 "unconnected-(J12N-PCIE_RX30--PadC99)")
	(net 463 "unconnected-(J12N-PCIE_RX31+-PadC101)")
	(net 464 "unconnected-(J12N-PCIE_RX31--PadC102)")
	(net 465 "unconnected-(J12J-USB_SSTX0--PadD3)")
	(net 466 "unconnected-(J12J-USB_SSTX0+-PadD4)")
	(net 467 "unconnected-(J12J-USB_SSTX1--PadD6)")
	(net 468 "unconnected-(J12J-USB_SSTX1+-PadD7)")
	(net 469 "unconnected-(J12K-10G_PHY_MDIO_SDA3-PadD15)")
	(net 470 "unconnected-(J12K-10G_PHY_MDIO_SDA2-PadD16)")
	(net 471 "Net-(J12K-10G_SDP3)")
	(net 472 "unconnected-(J12O-PCIE_TX6+-PadD19)")
	(net 473 "unconnected-(J12O-PCIE_TX6--PadD20)")
	(net 474 "unconnected-(J12O-PCIE_TX7+-PadD22)")
	(net 475 "unconnected-(J12O-PCIE_TX7--PadD23)")
	(net 476 "unconnected-(J12K-10G_INT3-PadD24)")
	(net 477 "unconnected-(J12K-10G_KR_TX3+-PadD26)")
	(net 478 "unconnected-(J12K-10G_KR_TX3--PadD27)")
	(net 479 "unconnected-(J12K-10G_KR_TX2+-PadD29)")
	(net 480 "unconnected-(J12K-10G_KR_TX2--PadD30)")
	(net 481 "unconnected-(J12K-10G_SFP_SCL3-PadD32)")
	(net 482 "unconnected-(J12K-10G_SFP_SCL2-PadD33)")
	(net 483 "unconnected-(J12K-10G_PHY_CAP_23-PadD34)")
	(net 484 "Net-(J12K-10G_PHY_CAP_01)")
	(net 485 "unconnected-(J12M-RSVD-PadD36)")
	(net 486 "unconnected-(J12M-RSVD-PadD37)")
	(net 487 "/2xSFP+/I2C_{SFP1}.SCL")
	(net 488 "/2xSFP+/I2C_{SFP0}.SCL")
	(net 489 "Net-(J12K-10G_SDP1)")
	(net 490 "/2xSFP+/MDIO1.MDIO")
	(net 491 "/2xSFP+/MDIO0.MDIO")
	(net 492 "/2xSFP+/MOD1_ABS")
	(net 493 "unconnected-(J12M-RSVD-PadD54)")
	(net 494 "unconnected-(J12M-RSVD-PadD63)")
	(net 495 "unconnected-(J12M-RSVD-PadD64)")
	(net 496 "unconnected-(J12N-PCIE_TX20+-PadD65)")
	(net 497 "unconnected-(J12N-PCIE_TX20--PadD66)")
	(net 498 "unconnected-(J12N-PCIE_TX21+-PadD68)")
	(net 499 "unconnected-(J12N-PCIE_TX21--PadD69)")
	(net 500 "unconnected-(J12N-PCIE_TX22+-PadD71)")
	(net 501 "unconnected-(J12N-PCIE_TX22--PadD72)")
	(net 502 "unconnected-(J12N-PCIE_TX23+-PadD74)")
	(net 503 "unconnected-(J12N-PCIE_TX23--PadD75)")
	(net 504 "unconnected-(J12M-RSVD-PadD77)")
	(net 505 "unconnected-(J12N-PCIE_TX24+-PadD78)")
	(net 506 "unconnected-(J12N-PCIE_TX24--PadD79)")
	(net 507 "unconnected-(J12N-PCIE_TX25+-PadD81)")
	(net 508 "unconnected-(J12N-PCIE_TX25--PadD82)")
	(net 509 "unconnected-(J12M-RSVD-PadD83)")
	(net 510 "unconnected-(J12N-PCIE_TX26+-PadD85)")
	(net 511 "unconnected-(J12N-PCIE_TX26--PadD86)")
	(net 512 "unconnected-(J12N-PCIE_TX27+-PadD88)")
	(net 513 "unconnected-(J12N-PCIE_TX27--PadD89)")
	(net 514 "unconnected-(J12N-PCIE_TX28+-PadD91)")
	(net 515 "unconnected-(J12N-PCIE_TX28--PadD92)")
	(net 516 "unconnected-(J12N-PCIE_TX29+-PadD94)")
	(net 517 "unconnected-(J12N-PCIE_TX29--PadD95)")
	(net 518 "unconnected-(J12M-RSVD-PadD97)")
	(net 519 "unconnected-(J12N-PCIE_TX30+-PadD98)")
	(net 520 "unconnected-(J12N-PCIE_TX30--PadD99)")
	(net 521 "unconnected-(J12N-PCIE_TX31+-PadD101)")
	(net 522 "unconnected-(J12N-PCIE_TX31--PadD102)")
	(net 523 "Net-(J13-Pad1)")
	(net 524 "unconnected-(J14-Pad1)")
	(net 525 "Net-(J14-Pad2)")
	(net 526 "/Backplane/~{PRSNT}")
	(net 527 "/Backplane/GPIO")
	(net 528 "/Backplane/~{PERST}")
	(net 529 "/M.2 key M #1/~{CLKREQ}")
	(net 530 "/M.2 key M #2/~{CLKREQ}")
	(net 531 "/Com Express 7 Interfaces/SD_CD")
	(net 532 "/Backplane/PCIe_{x2}.RX0+")
	(net 533 "/Com Express 7 MGMT/PSON")
	(net 534 "Net-(Q1-D)")
	(net 535 "Net-(Q3-G)")
	(net 536 "Net-(Q3-D)")
	(net 537 "/Backplane/PCIe_{x2}.RX0-")
	(net 538 "Net-(Q5-D)")
	(net 539 "/Misc/~{PWR_OK}")
	(net 540 "Net-(Q8-D)")
	(net 541 "Net-(Q9-B)")
	(net 542 "Net-(Q9-E)")
	(net 543 "Net-(Q10-B)")
	(net 544 "Net-(Q10-E)")
	(net 545 "Net-(Q11-G)")
	(net 546 "/Com Express 7 MGMT/~{COM7}")
	(net 547 "/2xUSB3.0+RJ45/P1_ISET")
	(net 548 "/2xUSB3.0+RJ45/P2_ISET")
	(net 549 "Net-(R14-Pad2)")
	(net 550 "Net-(R15-Pad2)")
	(net 551 "Net-(R16-Pad2)")
	(net 552 "Net-(R17-Pad2)")
	(net 553 "/2xUSB3.0+RJ45/FLG_1B")
	(net 554 "/2xUSB3.0+RJ45/FLG_2B")
	(net 555 "/2xUSB3.0+RJ45/EN_1B")
	(net 556 "/2xUSB3.0+RJ45/EN_2B")
	(net 557 "Net-(U5-A0)")
	(net 558 "Net-(U5-SDA)")
	(net 559 "Net-(U5-SCL)")
	(net 560 "Net-(U5-~{RESET})")
	(net 561 "Net-(U5-A1)")
	(net 562 "/2xSFP+/~{LED0_0}")
	(net 563 "/2xSFP+/~{LED0_1}")
	(net 564 "/2xSFP+/~{LED0_2}")
	(net 565 "/2xSFP+/~{LED1_0}")
	(net 566 "/2xSFP+/~{LED1_1}")
	(net 567 "/2xSFP+/~{LED1_2}")
	(net 568 "/USB-C console/FTDI_D+")
	(net 569 "/USB-C console/FTDI_D-")
	(net 570 "Net-(U6-~{RESET})")
	(net 571 "Net-(U7-A_{1})")
	(net 572 "Net-(U7-A_{2})")
	(net 573 "/GPIO expander/GPIOEX0")
	(net 574 "Net-(U19-EN)")
	(net 575 "Net-(U18-MODE)")
	(net 576 "Net-(U19-MODE)")
	(net 577 "Net-(U18-EN)")
	(net 578 "/Power/PG_{1V0}")
	(net 579 "/2xUSB3.0+RJ45/SH")
	(net 580 "Net-(U18-FB)")
	(net 581 "Net-(U19-FB)")
	(net 582 "Net-(U20-~{MR})")
	(net 583 "Net-(U22-EN)")
	(net 584 "Net-(U21-EN)")
	(net 585 "Net-(U21-FB)")
	(net 586 "Net-(U22-FB)")
	(net 587 "/M.2 key E/SUSCLK")
	(net 588 "/Misc/~{ADDREN}")
	(net 589 "/Misc/~{ADDRSEL}")
	(net 590 "Net-(U24-+2.5V_{IN})")
	(net 591 "Net-(U24-+12V_{IN})")
	(net 592 "Net-(U24-+5V_{IN})")
	(net 593 "Net-(U24-V_{CCP})")
	(net 594 "Net-(U24-GPIO4)")
	(net 595 "/Misc/PWM_{SRCSEL}")
	(net 596 "/Misc/PWM2")
	(net 597 "/Misc/PWM1")
	(net 598 "Net-(U31-~{WC})")
	(net 599 "Net-(U34-~{INT})")
	(net 600 "Net-(U36-~{HOLD}(D3))")
	(net 601 "Net-(U36-~{WP}(D2))")
	(net 602 "Net-(U37-~{OE0})")
	(net 603 "Net-(U37-~{OE1})")
	(net 604 "Net-(U37-~{OE2})")
	(net 605 "Net-(U37-~{OE3})")
	(net 606 "Net-(U37-~{OE4})")
	(net 607 "Net-(U37-~{HIBW_BYPM_LOBW})")
	(net 608 "Net-(U37-~{OE5})")
	(net 609 "Net-(U37-~{CKPWRGD_PD})")
	(net 610 "Net-(Y1-EN)")
	(net 611 "/PCIe misc/DIF0+")
	(net 612 "/PCIe misc/DIF0-")
	(net 613 "/PCIe misc/DIF1+")
	(net 614 "/PCIe misc/DIF1-")
	(net 615 "/PCIe misc/DIF2+")
	(net 616 "/PCIe misc/DIF2-")
	(net 617 "/PCIe misc/DIF3+")
	(net 618 "/PCIe misc/DIF3-")
	(net 619 "/PCIe misc/DIF4+")
	(net 620 "/PCIe misc/DIF4-")
	(net 621 "/PCIe misc/DIF5+")
	(net 622 "/PCIe misc/DIF5-")
	(net 623 "/PCIe redriver/TX_EQ0")
	(net 624 "/PCIe redriver/TX_EQ1")
	(net 625 "/PCIe redriver/TX_EQ2")
	(net 626 "/PCIe redriver/TX_FG0")
	(net 627 "/PCIe redriver/TX_FG1")
	(net 628 "/PCIe redriver/TX_SW")
	(net 629 "Net-(U39-EN_{I2C})")
	(net 630 "Net-(U40-RXDET)")
	(net 631 "Net-(U39-RXDET)")
	(net 632 "Net-(U40-EN_{I2C})")
	(net 633 "Net-(U41-A0)")
	(net 634 "Net-(U41-SDA)")
	(net 635 "Net-(U41-SCL)")
	(net 636 "Net-(U41-~{INT})")
	(net 637 "Net-(U41-~{RESET})")
	(net 638 "Net-(U41-A1)")
	(net 639 "Net-(U41-IO0_0)")
	(net 640 "Net-(U41-IO0_1)")
	(net 641 "Net-(U41-IO0_2)")
	(net 642 "Net-(U41-IO0_3)")
	(net 643 "Net-(U41-IO0_4)")
	(net 644 "Net-(U41-IO0_5)")
	(net 645 "Net-(U41-IO0_6)")
	(net 646 "Net-(U41-IO0_7)")
	(net 647 "Net-(Y2-EN)")
	(net 648 "/2xSFP+/KR to SFI #1/MDIO_R")
	(net 649 "/2xSFP+/KR to SFI #1/MDIO")
	(net 650 "/2xSFP+/KR to SFI #1/MDC_R")
	(net 651 "/2xSFP+/KR to SFI #1/MDC")
	(net 652 "/2xSFP+/KR to SFI #1/PRBSEN")
	(net 653 "Net-(U43C-TESTEN)")
	(net 654 "Net-(U43C-GPI0)")
	(net 655 "Net-(U43C-PRTAD0)")
	(net 656 "Net-(U43C-PRTAD1)")
	(net 657 "Net-(U43A-~{PDTRXA})")
	(net 658 "Net-(U43C-PRTAD2)")
	(net 659 "Net-(U43C-PRTAD3)")
	(net 660 "Net-(U43B-~{PDTRXB})")
	(net 661 "Net-(U43C-PRTAD4)")
	(net 662 "Net-(U43C-MODE_{SEL})")
	(net 663 "Net-(U43C-ST)")
	(net 664 "/2xSFP+/KR to SFI #1/KR_R.RX+")
	(net 665 "/2xSFP+/KR to SFI #1/KR_R.RX-")
	(net 666 "/2xSFP+/KR to SFI #1/SFI_R.TX+")
	(net 667 "/2xSFP+/KR to SFI #1/SFI_R.RX+")
	(net 668 "Net-(Y3-EN)")
	(net 669 "/2xSFP+/KR to SFI #2/MDIO_R")
	(net 670 "/2xSFP+/KR to SFI #2/MDIO")
	(net 671 "/2xSFP+/KR to SFI #2/MDC_R")
	(net 672 "/2xSFP+/KR to SFI #2/MDC")
	(net 673 "/2xSFP+/KR to SFI #2/PRBSEN")
	(net 674 "Net-(U45C-TESTEN)")
	(net 675 "Net-(U45C-GPI0)")
	(net 676 "Net-(U45C-PRTAD0)")
	(net 677 "Net-(U45C-PRTAD1)")
	(net 678 "Net-(U45A-~{PDTRXA})")
	(net 679 "Net-(U45C-PRTAD2)")
	(net 680 "Net-(U45C-PRTAD3)")
	(net 681 "Net-(U45B-~{PDTRXB})")
	(net 682 "Net-(U45C-PRTAD4)")
	(net 683 "Net-(U45C-MODE_{SEL})")
	(net 684 "Net-(U45C-ST)")
	(net 685 "/2xSFP+/KR to SFI #1/SFI_R.TX-")
	(net 686 "/2xSFP+/KR to SFI #1/SFI_R.RX-")
	(net 687 "/2xSFP+/KR to SFI #2/KR_R.RX+")
	(net 688 "/2xSFP+/KR to SFI #2/KR_R.RX-")
	(net 689 "/2xUSB3.0+RJ45/DA_FL+")
	(net 690 "/2xUSB3.0+RJ45/DA_FL-")
	(net 691 "/2xUSB3.0+RJ45/DB_FL+")
	(net 692 "/2xUSB3.0+RJ45/DB_FL-")
	(net 693 "/2xUSB3.0+RJ45/DC_FL+")
	(net 694 "/2xUSB3.0+RJ45/DC_FL-")
	(net 695 "/2xUSB3.0+RJ45/DD_FL+")
	(net 696 "/2xUSB3.0+RJ45/DD_FL-")
	(net 697 "Net-(U5-IO0_6)")
	(net 698 "Net-(U5-IO0_7)")
	(net 699 "/USB-C console/FTDI_RX")
	(net 700 "/USB-C console/FTDI_TX")
	(net 701 "/USB-C console/FTDI_CBUS0")
	(net 702 "/USB-C console/FTDI_CBUS3")
	(net 703 "Net-(U24-GPIO3)")
	(net 704 "Net-(U24-GPIO2)")
	(net 705 "Net-(U24-GPIO1)")
	(net 706 "Net-(U24-GPIO0)")
	(net 707 "Net-(U24-TACH3)")
	(net 708 "Net-(U32-~{MR})")
	(net 709 "Net-(U37-SCLK)")
	(net 710 "Net-(U37-SDAT)")
	(net 711 "Net-(U37-SADR_{TRI})")
	(net 712 "Net-(U39-SDA)")
	(net 713 "Net-(U39-SCL)")
	(net 714 "Net-(U39-I2C_{DONE})")
	(net 715 "Net-(U39-~{I2C_{RESET}})")
	(net 716 "Net-(U40-SDA)")
	(net 717 "Net-(U40-SCL)")
	(net 718 "Net-(U40-I2C_{DONE})")
	(net 719 "Net-(U40-~{I2C_{RESET}})")
	(net 720 "Net-(U43C-REFCLK1+)")
	(net 721 "Net-(U43C-REFCLK1-)")
	(net 722 "/2xSFP+/KR to SFI #1/TDI")
	(net 723 "/2xSFP+/KR to SFI #1/TDO")
	(net 724 "/2xSFP+/KR to SFI #1/TMS")
	(net 725 "/2xSFP+/KR to SFI #1/TCK")
	(net 726 "/2xSFP+/KR to SFI #1/~{TRST}")
	(net 727 "Net-(U43C-PRBS_{PASS})")
	(net 728 "Net-(U43C-AMUXA)")
	(net 729 "Net-(U43C-AMUXB)")
	(net 730 "Net-(U43C-CLKOUTA+)")
	(net 731 "Net-(U43C-CLKOUTA-)")
	(net 732 "Net-(U43C-CLKOUTB+)")
	(net 733 "Net-(U43C-CLKOUTB-)")
	(net 734 "Net-(U43A-LOSA)")
	(net 735 "Net-(U43A-LS_OK_{IN_A})")
	(net 736 "Net-(U43A-LS_OK_{OUT_A})")
	(net 737 "Net-(U43B-LOSB)")
	(net 738 "Net-(U43B-LS_OK_{IN_B})")
	(net 739 "Net-(U43B-LS_OK_{OUT_B})")
	(net 740 "Net-(U45C-REFCLK1+)")
	(net 741 "Net-(U45C-REFCLK1-)")
	(net 742 "/2xSFP+/KR to SFI #2/TDI")
	(net 743 "/2xSFP+/KR to SFI #2/TDO")
	(net 744 "/2xSFP+/KR to SFI #2/TMS")
	(net 745 "/2xSFP+/KR to SFI #2/TCK")
	(net 746 "/2xSFP+/KR to SFI #2/~{TRST}")
	(net 747 "Net-(U45C-PRBS_{PASS})")
	(net 748 "Net-(U45C-AMUXA)")
	(net 749 "Net-(U45C-AMUXB)")
	(net 750 "Net-(U45C-CLKOUTA+)")
	(net 751 "Net-(U45C-CLKOUTA-)")
	(net 752 "Net-(U45C-CLKOUTB+)")
	(net 753 "Net-(U45C-CLKOUTB-)")
	(net 754 "Net-(U45A-LOSA)")
	(net 755 "Net-(U45A-LS_OK_{IN_A})")
	(net 756 "Net-(U45A-LS_OK_{OUT_A})")
	(net 757 "Net-(U45B-LOSB)")
	(net 758 "Net-(U45B-LS_OK_{IN_B})")
	(net 759 "Net-(U45B-LS_OK_{OUT_B})")
	(net 760 "unconnected-(U5-IO1_0-Pad10)")
	(net 761 "unconnected-(U5-IO1_1-Pad11)")
	(net 762 "unconnected-(U5-IO1_2-Pad12)")
	(net 763 "unconnected-(U5-IO1_3-Pad13)")
	(net 764 "unconnected-(U5-IO1_4-Pad14)")
	(net 765 "unconnected-(U5-IO1_5-Pad15)")
	(net 766 "unconnected-(U5-IO1_6-Pad16)")
	(net 767 "unconnected-(U5-IO1_7-Pad17)")
	(net 768 "unconnected-(U5-~{INT}-Pad22)")
	(net 769 "unconnected-(U6-~{CTS}-Pad4)")
	(net 770 "unconnected-(U6-~{RTS}-Pad16)")
	(net 771 "/Backplane/PCIe_{x2}.RX1+")
	(net 772 "/Backplane/PCIe_{x2}.RX1-")
	(net 773 "unconnected-(U18-NC-Pad10)")
	(net 774 "unconnected-(U18-SS-Pad11)")
	(net 775 "unconnected-(U18-NC-Pad16)")
	(net 776 "unconnected-(U19-NC-Pad10)")
	(net 777 "unconnected-(U19-SS-Pad11)")
	(net 778 "unconnected-(U19-NC-Pad16)")
	(net 779 "unconnected-(U23-NC-Pad4)")
	(net 780 "/Misc/TACH_{A3V3}")
	(net 781 "/Misc/TACH_{B3V3}")
	(net 782 "/Misc/PWM_{A3V3}")
	(net 783 "/Misc/PWM_{B3V3}")
	(net 784 "Net-(U30-1Y)")
	(net 785 "Net-(U33-1Y)")
	(net 786 "unconnected-(U37-FB_DNC+-Pad3)")
	(net 787 "unconnected-(U37-FB_DNC--Pad4)")
	(net 788 "unconnected-(U37-NC-Pad20)")
	(net 789 "unconnected-(U37-NC-Pad30)")
	(net 790 "Net-(U38-1A)")
	(net 791 "unconnected-(U38-2Y-Pad3)")
	(net 792 "unconnected-(U41-IO1_0-Pad10)")
	(net 793 "unconnected-(U41-IO1_1-Pad11)")
	(net 794 "unconnected-(U41-IO1_2-Pad12)")
	(net 795 "unconnected-(U41-IO1_3-Pad13)")
	(net 796 "unconnected-(U41-IO1_4-Pad14)")
	(net 797 "unconnected-(U41-IO1_5-Pad15)")
	(net 798 "unconnected-(U41-IO1_6-Pad16)")
	(net 799 "unconnected-(U41-IO1_7-Pad17)")
	(net 800 "unconnected-(U43A-INA1+-PadA1)")
	(net 801 "unconnected-(U43A-INA0--PadA3)")
	(net 802 "unconnected-(U43A-INA0+-PadA4)")
	(net 803 "unconnected-(U43A-OUTA0+-PadA6)")
	(net 804 "unconnected-(U43A-OUTA0--PadA7)")
	(net 805 "unconnected-(U43A-INA1--PadB1)")
	(net 806 "unconnected-(U43A-INA2+-PadB2)")
	(net 807 "unconnected-(U43A-OUTA1+-PadB5)")
	(net 808 "unconnected-(U43A-OUTA1--PadB6)")
	(net 809 "unconnected-(U43A-INA2--PadC2)")
	(net 810 "unconnected-(U43A-OUTA2+-PadC4)")
	(net 811 "unconnected-(U43A-OUTA2--PadC5)")
	(net 812 "unconnected-(U43A-INA3+-PadD1)")
	(net 813 "unconnected-(U43A-INA3--PadE1)")
	(net 814 "unconnected-(U43A-OUTA3--PadE3)")
	(net 815 "unconnected-(U43A-OUTA3+-PadF3)")
	(net 816 "unconnected-(U43B-INB0+-PadH1)")
	(net 817 "unconnected-(U43B-OUTB0--PadH3)")
	(net 818 "unconnected-(U43B-INB0--PadJ1)")
	(net 819 "unconnected-(U43B-OUTB0+-PadJ3)")
	(net 820 "unconnected-(U43B-INB1+-PadK2)")
	(net 821 "unconnected-(U43B-OUTB1--PadK4)")
	(net 822 "unconnected-(U43B-OUTB1+-PadK5)")
	(net 823 "unconnected-(U43B-INB2+-PadL1)")
	(net 824 "unconnected-(U43B-INB1--PadL2)")
	(net 825 "unconnected-(U43B-OUTB2--PadL5)")
	(net 826 "unconnected-(U43B-OUTB2+-PadL6)")
	(net 827 "unconnected-(U43B-INB2--PadM1)")
	(net 828 "unconnected-(U43B-INB3+-PadM3)")
	(net 829 "unconnected-(U43B-INB3--PadM4)")
	(net 830 "unconnected-(U43B-OUTB3--PadM6)")
	(net 831 "unconnected-(U43B-OUTB3+-PadM7)")
	(net 832 "unconnected-(U45A-INA1+-PadA1)")
	(net 833 "unconnected-(U45A-INA0--PadA3)")
	(net 834 "unconnected-(U45A-INA0+-PadA4)")
	(net 835 "unconnected-(U45A-OUTA0+-PadA6)")
	(net 836 "unconnected-(U45A-OUTA0--PadA7)")
	(net 837 "unconnected-(U45A-INA1--PadB1)")
	(net 838 "unconnected-(U45A-INA2+-PadB2)")
	(net 839 "unconnected-(U45A-OUTA1+-PadB5)")
	(net 840 "unconnected-(U45A-OUTA1--PadB6)")
	(net 841 "unconnected-(U45A-INA2--PadC2)")
	(net 842 "unconnected-(U45A-OUTA2+-PadC4)")
	(net 843 "unconnected-(U45A-OUTA2--PadC5)")
	(net 844 "unconnected-(U45A-INA3+-PadD1)")
	(net 845 "unconnected-(U45A-INA3--PadE1)")
	(net 846 "unconnected-(U45A-OUTA3--PadE3)")
	(net 847 "unconnected-(U45A-OUTA3+-PadF3)")
	(net 848 "unconnected-(U45B-INB0+-PadH1)")
	(net 849 "unconnected-(U45B-OUTB0--PadH3)")
	(net 850 "unconnected-(U45B-INB0--PadJ1)")
	(net 851 "unconnected-(U45B-OUTB0+-PadJ3)")
	(net 852 "unconnected-(U45B-INB1+-PadK2)")
	(net 853 "unconnected-(U45B-OUTB1--PadK4)")
	(net 854 "unconnected-(U45B-OUTB1+-PadK5)")
	(net 855 "unconnected-(U45B-INB2+-PadL1)")
	(net 856 "unconnected-(U45B-INB1--PadL2)")
	(net 857 "unconnected-(U45B-OUTB2--PadL5)")
	(net 858 "unconnected-(U45B-OUTB2+-PadL6)")
	(net 859 "unconnected-(U45B-INB2--PadM1)")
	(net 860 "unconnected-(U45B-INB3+-PadM3)")
	(net 861 "unconnected-(U45B-INB3--PadM4)")
	(net 862 "unconnected-(U45B-OUTB3--PadM6)")
	(net 863 "unconnected-(U45B-OUTB3+-PadM7)")
	(net 864 "unconnected-(Y2-NC-Pad2)")
	(net 865 "unconnected-(Y3-NC-Pad2)")
	(net 866 "/Backplane/PCIe_{x2}.TX0+")
	(net 867 "/Backplane/PCIe_{x2}.TX0-")
	(net 868 "/Backplane/PCIe_{x2}.TX1+")
	(net 869 "/Backplane/PCIe_{x2}.TX1-")
	(net 870 "Net-(U21-SW)")
	(net 871 "Net-(U22-SW)")
	(net 872 "Net-(U34-~{KILL})")
	(net 873 "Net-(U34-EN)")
	(net 874 "/2xSFP+/SDA1")
	(net 875 "/2xSFP+/SCL1")
	(net 876 "Net-(J2B-TX_{FAULT})")
	(net 877 "/2xSFP+/SFI1.RX-")
	(net 878 "/2xSFP+/SFI1.RX+")
	(net 879 "/2xSFP+/SFI1.TX+")
	(net 880 "/2xSFP+/SFI1.TX-")
	(net 881 "unconnected-(J12N-PCIE_RX18+-PadC58)")
	(net 882 "unconnected-(J12N-PCIE_RX18--PadC59)")
	(net 883 "unconnected-(J12N-PCIE_RX19+-PadC61)")
	(net 884 "unconnected-(J12N-PCIE_RX19--PadC62)")
	(net 885 "unconnected-(J12N-PCIE_TX18+-PadD58)")
	(net 886 "unconnected-(J12N-PCIE_TX18--PadD59)")
	(net 887 "unconnected-(J12N-PCIE_TX19+-PadD61)")
	(net 888 "unconnected-(J12N-PCIE_TX19--PadD62)")
	(net 889 "/Power/PG_{3V3}")
	(net 890 "unconnected-(U46-Pad5)")
	(net 891 "Net-(D13-A)")
	(net 892 "Net-(D14-A)")
	(net 893 "Net-(J2B-TX_{DISABLE})")
	(net 894 "Net-(J2B-MOD_{ABS})")
	(net 895 "Net-(J2B-RS0)")
	(net 896 "Net-(J2B-RX_{LOS})")
	(net 897 "Net-(J2B-RS1)")
	(net 898 "/2xSFP+/SFP1_LEDY")
	(net 899 "Net-(D4-C)")
	(net 900 "unconnected-(J100-W_DISABLE1-Pad56)")
	(net 901 "unconnected-(J100-I2C_DATA-Pad58)")
	(net 902 "unconnected-(J100-PET1_P-Pad59)")
	(net 903 "unconnected-(J100-I2C_CLK-Pad60)")
	(net 904 "unconnected-(J100-PET1_N-Pad61)")
	(net 905 "unconnected-(J100-~{ALERT}-Pad62)")
	(net 906 "unconnected-(J100-RFU-Pad64)")
	(net 907 "unconnected-(J100-PER1_P-Pad65)")
	(net 908 "unconnected-(J100-UIM_SWP-Pad66)")
	(net 909 "unconnected-(J100-PER1_N-Pad67)")
	(net 910 "unconnected-(J100-UIM_POWER_SNK-Pad68)")
	(net 911 "unconnected-(J100-UIM_POWER_SRC-Pad70)")
	(net 912 "unconnected-(J100-REFCLK1_P-Pad71)")
	(net 913 "unconnected-(J100-REFCLK1_N-Pad73)")
	(net 914 "unconnected-(J5-NC-Pad34)")
	(net 915 "unconnected-(J5-NC-Pad36)")
	(net 916 "unconnected-(J5-NC-Pad38)")
	(net 917 "unconnected-(J5-SMB_CLK-Pad40)")
	(net 918 "unconnected-(J5-SMB_DATA-Pad42)")
	(net 919 "unconnected-(J5-ALERT-Pad44)")
	(net 920 "unconnected-(J5-NC-Pad46)")
	(net 921 "unconnected-(J5-NC-Pad48)")
	(net 922 "unconnected-(J5-~{PEWAKE}-Pad54)")
	(net 923 "unconnected-(J5-NC-Pad56)")
	(net 924 "unconnected-(J5-NC-Pad58)")
	(net 925 "unconnected-(J5-NC-Pad67)")
	(net 926 "Net-(J5-SUSCLK)")
	(net 927 "unconnected-(J5-NC-Pad69)")
	(net 928 "unconnected-(D6-Pad1)")
	(net 929 "/2xSFP+/SFP1_LEDG")
	(net 930 "Net-(D5-C)")
	(net 931 "/2xSFP+/SFP0_LEDG")
	(net 932 "Net-(D7-C)")
	(net 933 "Net-(D11-A)")
	(net 934 "Net-(D12-A)")
	(net 935 "Net-(D13-C)")
	(net 936 "Net-(D14-C)")
	(net 937 "Net-(D15-A)")
	(net 938 "Net-(D16-A)")
	(net 939 "/2xSFP+/SFP0_LEDY")
	(net 940 "Net-(D8-C)")
	(net 941 "/2xUSB3.0+RJ45/EN_1")
	(net 942 "/2xUSB3.0+RJ45/EN_2")
	(net 943 "/GPIO expander/GPIOEX1")
	(net 944 "/GPIO expander/GPIOEX2")
	(net 945 "/GPIO expander/GPIOEX5")
	(net 946 "/2xSFP+/KR to SFI #1/BYP_RX+")
	(net 947 "/2xSFP+/KR to SFI #2/SFI_R.TX+")
	(net 948 "/2xSFP+/KR to SFI #1/BYP_TX-")
	(net 949 "/2xSFP+/KR to SFI #2/BYP_RX+")
	(net 950 "/2xSFP+/KR to SFI #2/SFI_R.RX+")
	(net 951 "/2xSFP+/KR to SFI #2/BYP_TX-")
	(net 952 "/2xSFP+/KR to SFI #2/SFI_R.TX-")
	(net 953 "/2xSFP+/KR to SFI #2/SFI_R.RX-")
	(net 954 "/2xSFP+/KR to SFI #1/BYP_TX+")
	(net 955 "/2xSFP+/KR to SFI #2/BYP_TX+")
	(net 956 "/PCIe redriver/PCIe_{I}_C.RX3-")
	(net 957 "/PCIe redriver/PCIe_{I}_C.RX0+")
	(net 958 "/PCIe redriver/PCIe_{I}_C.RX1+")
	(net 959 "/PCIe redriver/PCIe_{I}_C.RX2+")
	(net 960 "/PCIe redriver/PCIe_{I}_C.RX3+")
	(net 961 "/PCIe redriver/PCIe_{O}_C.TX2+")
	(net 962 "/PCIe redriver/PCIe_{O}_C.TX1+")
	(net 963 "/PCIe redriver/PCIe_{O}_C.TX0+")
	(net 964 "/PCIe redriver/PCIe_{O}_C.TX2-")
	(net 965 "/PCIe redriver/PCIe_{O}_C.TX1-")
	(net 966 "/PCIe redriver/PCIe_{O}_C.TX0-")
	(net 967 "/2xSFP+/KR to SFI #1/BYP_RX-")
	(net 968 "/2xSFP+/KR to SFI #2/BYP_RX-")
	(net 969 "/M.2 key M #1/M2_3V3")
	(net 970 "/M.2 key M #2/M2_3V3")
	(net 971 "unconnected-(U13-Pad1)")
	(net 972 "unconnected-(U13-Pad2)")
	(net 973 "/PCIe redriver/RX_SW")
	(net 974 "/PCIe redriver/RX_FG1")
	(net 975 "/PCIe redriver/RX_FG0")
	(net 976 "/PCIe redriver/RX_EQ2")
	(net 977 "/PCIe redriver/RX_EQ1")
	(net 978 "/PCIe redriver/RX_EQ0")
	(net 979 "Net-(D26-C)")
	(net 980 "Net-(D27-C)")
	(net 981 "Net-(D28-C)")
	(net 982 "Net-(D30-C)")
	(net 983 "Net-(D31-C)")
	(net 984 "Net-(D32-C)")
	(net 985 "Net-(D33-C)")
	(net 986 "Net-(D34-C)")
	(net 987 "Net-(Q13-B)")
	(net 988 "Net-(Q13-C)")
	(net 989 "Net-(Q14-B)")
	(net 990 "Net-(Q14-C)")
	(net 991 "unconnected-(U17-Pad4)")
	(net 992 "unconnected-(U17-Pad5)")
	(net 993 "unconnected-(U12-Pad1)_1")
	(net 994 "unconnected-(U13-Pad2)_1")
	(net 995 "unconnected-(U13-Pad1)_1")
	(net 996 "unconnected-(U17-Pad4)_1")
	(net 997 "unconnected-(U17-Pad5)_1")
	(net 998 "unconnected-(U46-Pad5)_1")
	(net 999 "Net-(C101-Pad1)")
	(net 1000 "unconnected-(J7-Pad1)")
	(footprint "antmicro-footprints:R_0402_1005Metric"
		(layer "F.Cu")
		(at 197.70861 77.152163 90)
		(descr "Resistor SMD 0402")
		(tags "resistor SMD 0402")
		(property "Reference" "R320"
			(at -1.9 -0.5 90)
			(layer "F.SilkS")
			(effects
				(font
					(size 0.7 0.7)
					(thickness 0.15)
				)
				(justify left bottom)
			)
		)
		(property "Value" "R_220R_0402"
			(at -1.011843 1.772047 90)
			(layer "F.Fab")
			(effects
				(font
					(size 0.7 0.7)
					(thickness 0.15)
				)
				(justify left bottom)
			)
		)
		(property "Datasheet" "https://www.bourns.com/docs/product-datasheets/cr.pdf"
			(at 0 0 90)
			(layer "F.Fab")
			(hide yes)
			(effects
				(font
					(size 1.27 1.27)
					(thickness 0.15)
				)
			)
		)
		(property "Author" "Antmicro"
			(at 274.860773 -120.556447 0)
			(layer "F.Fab")
			(hide yes)
			(effects
				(font
					(size 1 1)
					(thickness 0.15)
				)
			)
		)
		(property "License" "Apache-2.0"
			(at 274.860773 -120.556447 0)
			(layer "F.Fab")
			(hide yes)
			(effects
				(font
					(size 1 1)
					(thickness 0.15)
				)
			)
		)
		(property "MPN" "CR0402-FX-2200GLF"
			(at 274.860773 -120.556447 0)
			(layer "F.Fab")
			(hide yes)
			(effects
				(font
					(size 1 1)
					(thickness 0.15)
				)
			)
		)
		(property "Manufacturer" "Bourns"
			(at 274.860773 -120.556447 0)
			(layer "F.Fab")
			(hide yes)
			(effects
				(font
					(size 1 1)
					(thickness 0.15)
				)
			)
		)
		(property "Public" "False"
			(at 274.860773 -120.556447 0)
			(layer "F.Fab")
			(hide yes)
			(effects
				(font
					(size 1 1)
					(thickness 0.15)
				)
			)
		)
		(property "Tolerance" "1%"
			(at 274.860773 -120.556447 0)
			(layer "F.Fab")
			(hide yes)
			(effects
				(font
					(size 1 1)
					(thickness 0.15)
				)
			)
		)
		(property "Val" "220R"
			(at 274.860773 -120.556447 0)
			(layer "F.Fab")
			(hide yes)
			(effects
				(font
					(size 1 1)
					(thickness 0.15)
				)
			)
		)
		(sheetname "Power")
		(sheetfile "power.kicad_sch")
		(attr smd)
		(fp_rect
			(start -0.925 -0.47)
			(end 0.925 0.47)
			(stroke
				(width 0.05)
				(type default)
			)
			(fill no)
			(layer "F.CrtYd")
		)
		(fp_rect
			(start -0.5 -0.25)
			(end 0.5 0.25)
			(stroke
				(width 0.15)
				(type solid)
			)
			(fill no)
			(layer "F.Fab")
		)
		(pad "1" smd roundrect
			(at -0.48 0 90)
			(size 0.59 0.64)
			(layers "F.Cu" "F.Mask" "F.Paste")
			(roundrect_rratio 0.25)
			(net 1 "GND")
			(pintype "passive")
			(teardrops
				(best_length_ratio 0.2)
				(max_length 1)
				(best_width_ratio 0.9)
				(max_width 2)
				(curved_edges yes)
				(filter_ratio 0.9)
				(enabled yes)
				(allow_two_segments yes)
				(prefer_zone_connections yes)
			)
		)
		(pad "2" smd roundrect
			(at 0.48 0 90)
			(size 0.59 0.64)
			(layers "F.Cu" "F.Mask" "F.Paste")
			(roundrect_rratio 0.25)
			(net 981 "Net-(D28-C)")
			(pintype "passive")
			(teardrops
				(best_length_ratio 0.2)
				(max_length 1)
				(best_width_ratio 0.9)
				(max_width 2)
				(curved_edges yes)
				(filter_ratio 0.9)
				(enabled yes)
				(allow_two_segments yes)
				(prefer_zone_connections yes)
			)
		)
	)
	(footprint "antmicro-footprints:C_0402_1005Metric"
		(layer "F.Cu")
		(at 244.8 132.354 90)
		(descr "Capacitor SMD 0402")
		(tags "capacitor SMD 0402")
		(property "Reference" "C206"
			(at -3.656 0.45 90)
			(layer "F.SilkS")
			(effects
				(font
					(size 0.7 0.7)
					(thickness 0.15)
				)
				(justify left bottom)
			)
		)
		(property "Value" "C_1u_0402"
			(at -1.022927 2.155213 90)
			(layer "F.Fab")
			(effects
				(font
					(size 0.7 0.7)
					(thickness 0.15)
				)
				(justify left bottom)
			)
		)
		(property "Datasheet" "https://product.tdk.com/en/search/capacitor/ceramic/mlcc/info?part_no=C1005X6S1A105K050BC"
			(at 0 0 90)
			(layer "F.Fab")
			(hide yes)
			(effects
				(font
					(size 1.27 1.27)
					(thickness 0.15)
				)
			)
		)
		(property "Author" "Antmicro"
			(at 377.154 -112.446 0)
			(layer "F.Fab")
			(hide yes)
			(effects
				(font
					(size 1 1)
					(thickness 0.15)
				)
			)
		)
		(property "Dielectric" ""
			(at 377.154 -112.446 0)
			(layer "F.Fab")
			(hide yes)
			(effects
				(font
					(size 1 1)
					(thickness 0.15)
				)
			)
		)
		(property "License" "Apache-2.0"
			(at 377.154 -112.446 0)
			(layer "F.Fab")
			(hide yes)
			(effects
				(font
					(size 1 1)
					(thickness 0.15)
				)
			)
		)
		(property "MPN" "C1005X6S1A105K050BC"
			(at 377.154 -112.446 0)
			(layer "F.Fab")
			(hide yes)
			(effects
				(font
					(size 1 1)
					(thickness 0.15)
				)
			)
		)
		(property "Manufacturer" "TDK"
			(at 377.154 -112.446 0)
			(layer "F.Fab")
			(hide yes)
			(effects
				(font
					(size 1 1)
					(thickness 0.15)
				)
			)
		)
		(property "Public" "False"
			(at 377.154 -112.446 0)
			(layer "F.Fab")
			(hide yes)
			(effects
				(font
					(size 1 1)
					(thickness 0.15)
				)
			)
		)
		(property "Val" "1u"
			(at 377.154 -112.446 0)
			(layer "F.Fab")
			(hide yes)
			(effects
				(font
					(size 1 1)
					(thickness 0.15)
				)
			)
		)
		(property "Voltage" ""
			(at 377.154 -112.446 0)
			(layer "F.Fab")
			(hide yes)
			(effects
				(font
					(size 1 1)
					(thickness 0.15)
				)
			)
		)
		(sheetname "Com Express 7 MGMT")
		(sheetfile "com_express_7_mgmt.kicad_sch")
		(attr smd)
		(fp_rect
			(start -0.925 -0.47)
			(end 0.925 0.47)
			(stroke
				(width 0.05)
				(type default)
			)
			(fill no)
			(layer "F.CrtYd")
		)
		(fp_line
			(start 0.504 -0.25)
			(end 0.504 0.248)
			(stroke
				(width 0.15)
				(type solid)
			)
			(layer "F.Fab")
		)
		(fp_line
			(start -0.494 -0.25)
			(end 0.504 -0.25)
			(stroke
				(width 0.15)
				(type solid)
			)
			(layer "F.Fab")
		)
		(fp_line
			(start 0.504 0.248)
			(end -0.494 0.248)
			(stroke
				(width 0.15)
				(type solid)
			)
			(layer "F.Fab")
		)
		(fp_line
			(start -0.494 0.248)
			(end -0.494 -0.25)
			(stroke
				(width 0.15)
				(type solid)
			)
			(layer "F.Fab")
		)
		(pad "1" smd roundrect
			(at -0.48 0 90)
			(size 0.59 0.64)
			(layers "F.Cu" "F.Mask" "F.Paste")
			(roundrect_rratio 0.25)
			(net 1 "GND")
			(pintype "passive")
			(teardrops
				(best_length_ratio 0.2)
				(max_length 1)
				(best_width_ratio 0.9)
				(max_width 2)
				(curved_edges yes)
				(filter_ratio 0.9)
				(enabled yes)
				(allow_two_segments yes)
				(prefer_zone_connections yes)
			)
		)
		(pad "2" smd roundrect
			(at 0.48 0 90)
			(size 0.59 0.64)
			(layers "F.Cu" "F.Mask" "F.Paste")
			(roundrect_rratio 0.25)
			(net 46 "Net-(U34-OFFT)")
			(pintype "passive")
			(teardrops
				(best_length_ratio 0.2)
				(max_length 1)
				(best_width_ratio 0.9)
				(max_width 2)
				(curved_edges yes)
				(filter_ratio 0.9)
				(enabled yes)
				(allow_two_segments yes)
				(prefer_zone_connections yes)
			)
		)
	)
	(footprint "antmicro-footprints:C_0402_1005Metric"
		(layer "F.Cu")
		(at 310.2895 94.351 180)
		(descr "Capacitor SMD 0402")
		(tags "capacitor SMD 0402")
		(property "Reference" "C62"
			(at 0.8395 -0.409 0)
			(layer "F.SilkS")
			(effects
				(font
					(size 0.7 0.7)
					(thickness 0.15)
				)
				(justify right bottom)
			)
		)
		(property "Value" "C_1u_0402"
			(at -1.022927 2.155213 0)
			(layer "F.Fab")
			(effects
				(font
					(size 0.7 0.7)
					(thickness 0.15)
				)
				(justify right bottom)
			)
		)
		(property "Datasheet" "https://product.tdk.com/en/search/capacitor/ceramic/mlcc/info?part_no=C1005X6S1A105K050BC"
			(at 0 0 180)
			(layer "F.Fab")
			(hide yes)
			(effects
				(font
					(size 1.27 1.27)
					(thickness 0.15)
				)
			)
		)
		(property "Author" "Antmicro"
			(at 620.579 188.702 0)
			(layer "F.Fab")
			(hide yes)
			(effects
				(font
					(size 1 1)
					(thickness 0.15)
				)
			)
		)
		(property "Dielectric" ""
			(at 620.579 188.702 0)
			(layer "F.Fab")
			(hide yes)
			(effects
				(font
					(size 1 1)
					(thickness 0.15)
				)
			)
		)
		(property "License" "Apache-2.0"
			(at 620.579 188.702 0)
			(layer "F.Fab")
			(hide yes)
			(effects
				(font
					(size 1 1)
					(thickness 0.15)
				)
			)
		)
		(property "MPN" "C1005X6S1A105K050BC"
			(at 620.579 188.702 0)
			(layer "F.Fab")
			(hide yes)
			(effects
				(font
					(size 1 1)
					(thickness 0.15)
				)
			)
		)
		(property "Manufacturer" "TDK"
			(at 620.579 188.702 0)
			(layer "F.Fab")
			(hide yes)
			(effects
				(font
					(size 1 1)
					(thickness 0.15)
				)
			)
		)
		(property "Public" "False"
			(at 620.579 188.702 0)
			(layer "F.Fab")
			(hide yes)
			(effects
				(font
					(size 1 1)
					(thickness 0.15)
				)
			)
		)
		(property "Val" "1u"
			(at 620.579 188.702 0)
			(layer "F.Fab")
			(hide yes)
			(effects
				(font
					(size 1 1)
					(thickness 0.15)
				)
			)
		)
		(property "Voltage" ""
			(at 620.579 188.702 0)
			(layer "F.Fab")
			(hide yes)
			(effects
				(font
					(size 1 1)
					(thickness 0.15)
				)
			)
		)
		(sheetname "Power")
		(sheetfile "power.kicad_sch")
		(attr smd)
		(fp_rect
			(start -0.925 -0.47)
			(end 0.925 0.47)
			(stroke
				(width 0.05)
				(type default)
			)
			(fill no)
			(layer "F.CrtYd")
		)
		(fp_line
			(start 0.504 0.248)
			(end -0.494 0.248)
			(stroke
				(width 0.15)
				(type solid)
			)
			(layer "F.Fab")
		)
		(fp_line
			(start 0.504 -0.25)
			(end 0.504 0.248)
			(stroke
				(width 0.15)
				(type solid)
			)
			(layer "F.Fab")
		)
		(fp_line
			(start -0.494 0.248)
			(end -0.494 -0.25)
			(stroke
				(width 0.15)
				(type solid)
			)
			(layer "F.Fab")
		)
		(fp_line
			(start -0.494 -0.25)
			(end 0.504 -0.25)
			(stroke
				(width 0.15)
				(type solid)
			)
			(layer "F.Fab")
		)
		(pad "1" smd roundrect
			(at -0.48 0 180)
			(size 0.59 0.64)
			(layers "F.Cu" "F.Mask" "F.Paste")
			(roundrect_rratio 0.25)
			(net 1 "GND")
			(pintype "passive")
			(teardrops
				(best_length_ratio 0.2)
				(max_length 1)
				(best_width_ratio 0.9)
				(max_width 2)
				(curved_edges yes)
				(filter_ratio 0.9)
				(enabled yes)
				(allow_two_segments yes)
				(prefer_zone_connections yes)
			)
		)
		(pad "2" smd roundrect
			(at 0.48 0 180)
			(size 0.59 0.64)
			(layers "F.Cu" "F.Mask" "F.Paste")
			(roundrect_rratio 0.25)
			(net 75 "Net-(U50-IN+)")
			(pintype "passive")
			(teardrops
				(best_length_ratio 0.2)
				(max_length 1)
				(best_width_ratio 0.9)
				(max_width 2)
				(curved_edges yes)
				(filter_ratio 0.9)
				(enabled yes)
				(allow_two_segments yes)
				(prefer_zone_connections yes)
			)
		)
	)
	(footprint "antmicro-footprints:R_0402_1005Metric"
		(layer "F.Cu")
		(at 115.4 150.36 -90)
		(descr "Resistor SMD 0402")
		(tags "resistor SMD 0402")
		(property "Reference" "R210"
			(at -0.46 -4.5 90)
			(layer "F.SilkS")
			(effects
				(font
					(size 0.7 0.7)
					(thickness 0.15)
				)
				(justify right bottom)
			)
		)
		(property "Value" "R_1k_0402"
			(at -1.011843 1.772047 90)
			(layer "F.Fab")
			(effects
				(font
					(size 0.7 0.7)
					(thickness 0.15)
				)
				(justify right bottom)
			)
		)
		(property "Datasheet" "https://www.bourns.com/docs/product-datasheets/cr.pdf"
			(at 0 0 270)
			(layer "F.Fab")
			(hide yes)
			(effects
				(font
					(size 1.27 1.27)
					(thickness 0.15)
				)
			)
		)
		(property "Author" "Antmicro"
			(at -34.96 265.76 0)
			(layer "F.Fab")
			(hide yes)
			(effects
				(font
					(size 1 1)
					(thickness 0.15)
				)
			)
		)
		(property "License" "Apache-2.0"
			(at -34.96 265.76 0)
			(layer "F.Fab")
			(hide yes)
			(effects
				(font
					(size 1 1)
					(thickness 0.15)
				)
			)
		)
		(property "MPN" "CR0402-FX-1001GLF"
			(at -34.96 265.76 0)
			(layer "F.Fab")
			(hide yes)
			(effects
				(font
					(size 1 1)
					(thickness 0.15)
				)
			)
		)
		(property "Manufacturer" "Bourns"
			(at -34.96 265.76 0)
			(layer "F.Fab")
			(hide yes)
			(effects
				(font
					(size 1 1)
					(thickness 0.15)
				)
			)
		)
		(property "Public" "False"
			(at -34.96 265.76 0)
			(layer "F.Fab")
			(hide yes)
			(effects
				(font
					(size 1 1)
					(thickness 0.15)
				)
			)
		)
		(property "Tolerance" "1%"
			(at -34.96 265.76 0)
			(layer "F.Fab")
			(hide yes)
			(effects
				(font
					(size 1 1)
					(thickness 0.15)
				)
			)
		)
		(property "Val" "1k"
			(at -34.96 265.76 0)
			(layer "F.Fab")
			(hide yes)
			(effects
				(font
					(size 1 1)
					(thickness 0.15)
				)
			)
		)
		(sheetname "PCIe redriver")
		(sheetfile "pcie_redriver.kicad_sch")
		(attr smd)
		(fp_rect
			(start -0.925 -0.47)
			(end 0.925 0.47)
			(stroke
				(width 0.05)
				(type default)
			)
			(fill no)
			(layer "F.CrtYd")
		)
		(fp_rect
			(start -0.5 -0.25)
			(end 0.5 0.25)
			(stroke
				(width 0.15)
				(type solid)
			)
			(fill no)
			(layer "F.Fab")
		)
		(pad "1" smd roundrect
			(at -0.48 0 270)
			(size 0.59 0.64)
			(layers "F.Cu" "F.Mask" "F.Paste")
			(roundrect_rratio 0.25)
			(net 2 "+3V3")
			(pintype "passive")
			(teardrops
				(best_length_ratio 0.2)
				(max_length 1)
				(best_width_ratio 0.9)
				(max_width 2)
				(curved_edges yes)
				(filter_ratio 0.9)
				(enabled yes)
				(allow_two_segments yes)
				(prefer_zone_connections yes)
			)
		)
		(pad "2" smd roundrect
			(at 0.48 0 270)
			(size 0.59 0.64)
			(layers "F.Cu" "F.Mask" "F.Paste")
			(roundrect_rratio 0.25)
			(net 627 "/PCIe redriver/TX_FG1")
			(pintype "passive")
			(teardrops
				(best_length_ratio 0.2)
				(max_length 1)
				(best_width_ratio 0.9)
				(max_width 2)
				(curved_edges yes)
				(filter_ratio 0.9)
				(enabled yes)
				(allow_two_segments yes)
				(prefer_zone_connections yes)
			)
		)
	)
	(footprint "antmicro-footprints:R_0402_1005Metric"
		(layer "F.Cu")
		(at 252.670002 85.449999 180)
		(descr "Resistor SMD 0402")
		(tags "resistor SMD 0402")
		(property "Reference" "R154"
			(at 0.865 -0.440001 0)
			(layer "F.SilkS")
			(effects
				(font
					(size 0.7 0.7)
					(thickness 0.15)
				)
				(justify right bottom)
			)
		)
		(property "Value" "R_0R_0402"
			(at -1.011843 1.772047 0)
			(layer "F.Fab")
			(effects
				(font
					(size 0.7 0.7)
					(thickness 0.15)
				)
				(justify right bottom)
			)
		)
		(property "Datasheet" "https://industrial.panasonic.com/cdbs/www-data/pdf/RDA0000/AOA0000C301.pdf"
			(at 0 0 180)
			(layer "F.Fab")
			(hide yes)
			(effects
				(font
					(size 1.27 1.27)
					(thickness 0.15)
				)
			)
		)
		(property "Author" "Antmicro"
			(at 505.340004 170.899998 0)
			(layer "F.Fab")
			(hide yes)
			(effects
				(font
					(size 1 1)
					(thickness 0.15)
				)
			)
		)
		(property "Current" "1A"
			(at 505.340004 170.899998 0)
			(layer "F.Fab")
			(hide yes)
			(effects
				(font
					(size 1 1)
					(thickness 0.15)
				)
			)
		)
		(property "License" "Apache-2.0"
			(at 505.340004 170.899998 0)
			(layer "F.Fab")
			(hide yes)
			(effects
				(font
					(size 1 1)
					(thickness 0.15)
				)
			)
		)
		(property "MPN" "ERJ2GE0R00X"
			(at 505.340004 170.899998 0)
			(layer "F.Fab")
			(hide yes)
			(effects
				(font
					(size 1 1)
					(thickness 0.15)
				)
			)
		)
		(property "Manufacturer" "Panasonic"
			(at 505.340004 170.899998 0)
			(layer "F.Fab")
			(hide yes)
			(effects
				(font
					(size 1 1)
					(thickness 0.15)
				)
			)
		)
		(property "Public" "False"
			(at 505.340004 170.899998 0)
			(layer "F.Fab")
			(hide yes)
			(effects
				(font
					(size 1 1)
					(thickness 0.15)
				)
			)
		)
		(property "Tolerance" ""
			(at 505.340004 170.899998 0)
			(layer "F.Fab")
			(hide yes)
			(effects
				(font
					(size 1 1)
					(thickness 0.15)
				)
			)
		)
		(property "Val" "0R"
			(at 505.340004 170.899998 0)
			(layer "F.Fab")
			(hide yes)
			(effects
				(font
					(size 1 1)
					(thickness 0.15)
				)
			)
		)
		(sheetname "Misc")
		(sheetfile "misc.kicad_sch")
		(attr smd)
		(fp_rect
			(start -0.925 -0.47)
			(end 0.925 0.47)
			(stroke
				(width 0.05)
				(type default)
			)
			(fill no)
			(layer "F.CrtYd")
		)
		(fp_rect
			(start -0.5 -0.25)
			(end 0.5 0.25)
			(stroke
				(width 0.15)
				(type solid)
			)
			(fill no)
			(layer "F.Fab")
		)
		(pad "1" smd roundrect
			(at -0.48 0 180)
			(size 0.59 0.64)
			(layers "F.Cu" "F.Mask" "F.Paste")
			(roundrect_rratio 0.25)
			(net 594 "Net-(U24-GPIO4)")
			(pintype "passive")
			(teardrops
				(best_length_ratio 0.2)
				(max_length 1)
				(best_width_ratio 0.9)
				(max_width 2)
				(curved_edges yes)
				(filter_ratio 0.9)
				(enabled yes)
				(allow_two_segments yes)
				(prefer_zone_connections yes)
			)
		)
		(pad "2" smd roundrect
			(at 0.48 0 180)
			(size 0.59 0.64)
			(layers "F.Cu" "F.Mask" "F.Paste")
			(roundrect_rratio 0.25)
			(net 595 "/Misc/PWM_{SRCSEL}")
			(pintype "passive")
			(teardrops
				(best_length_ratio 0.2)
				(max_length 1)
				(best_width_ratio 0.9)
				(max_width 2)
				(curved_edges yes)
				(filter_ratio 0.9)
				(enabled yes)
				(allow_two_segments yes)
				(prefer_zone_connections yes)
			)
		)
	)
	(footprint "antmicro-footprints:C_0402_1005Metric"
		(layer "F.Cu")
		(at 308.7 102.91 180)
		(descr "Capacitor SMD 0402")
		(tags "capacitor SMD 0402")
		(property "Reference" "C50"
			(at 0.8 -0.5 0)
			(layer "F.SilkS")
			(effects
				(font
					(size 0.7 0.7)
					(thickness 0.15)
				)
				(justify right bottom)
			)
		)
		(property "Value" "C_1u_0402"
			(at -1.022927 2.155213 0)
			(layer "F.Fab")
			(effects
				(font
					(size 0.7 0.7)
					(thickness 0.15)
				)
				(justify right bottom)
			)
		)
		(property "Datasheet" "https://product.tdk.com/en/search/capacitor/ceramic/mlcc/info?part_no=C1005X6S1A105K050BC"
			(at 0 0 180)
			(layer "F.Fab")
			(hide yes)
			(effects
				(font
					(size 1.27 1.27)
					(thickness 0.15)
				)
			)
		)
		(property "Author" "Antmicro"
			(at 617.4 205.82 0)
			(layer "F.Fab")
			(hide yes)
			(effects
				(font
					(size 1 1)
					(thickness 0.15)
				)
			)
		)
		(property "Dielectric" ""
			(at 617.4 205.82 0)
			(layer "F.Fab")
			(hide yes)
			(effects
				(font
					(size 1 1)
					(thickness 0.15)
				)
			)
		)
		(property "License" "Apache-2.0"
			(at 617.4 205.82 0)
			(layer "F.Fab")
			(hide yes)
			(effects
				(font
					(size 1 1)
					(thickness 0.15)
				)
			)
		)
		(property "MPN" "C1005X6S1A105K050BC"
			(at 617.4 205.82 0)
			(layer "F.Fab")
			(hide yes)
			(effects
				(font
					(size 1 1)
					(thickness 0.15)
				)
			)
		)
		(property "Manufacturer" "TDK"
			(at 617.4 205.82 0)
			(layer "F.Fab")
			(hide yes)
			(effects
				(font
					(size 1 1)
					(thickness 0.15)
				)
			)
		)
		(property "Public" "False"
			(at 617.4 205.82 0)
			(layer "F.Fab")
			(hide yes)
			(effects
				(font
					(size 1 1)
					(thickness 0.15)
				)
			)
		)
		(property "Val" "1u"
			(at 617.4 205.82 0)
			(layer "F.Fab")
			(hide yes)
			(effects
				(font
					(size 1 1)
					(thickness 0.15)
				)
			)
		)
		(property "Voltage" ""
			(at 617.4 205.82 0)
			(layer "F.Fab")
			(hide yes)
			(effects
				(font
					(size 1 1)
					(thickness 0.15)
				)
			)
		)
		(sheetname "Power")
		(sheetfile "power.kicad_sch")
		(attr smd)
		(fp_rect
			(start -0.925 -0.47)
			(end 0.925 0.47)
			(stroke
				(width 0.05)
				(type default)
			)
			(fill no)
			(layer "F.CrtYd")
		)
		(fp_line
			(start 0.504 0.248)
			(end -0.494 0.248)
			(stroke
				(width 0.15)
				(type solid)
			)
			(layer "F.Fab")
		)
		(fp_line
			(start 0.504 -0.25)
			(end 0.504 0.248)
			(stroke
				(width 0.15)
				(type solid)
			)
			(layer "F.Fab")
		)
		(fp_line
			(start -0.494 0.248)
			(end -0.494 -0.25)
			(stroke
				(width 0.15)
				(type solid)
			)
			(layer "F.Fab")
		)
		(fp_line
			(start -0.494 -0.25)
			(end 0.504 -0.25)
			(stroke
				(width 0.15)
				(type solid)
			)
			(layer "F.Fab")
		)
		(pad "1" smd roundrect
			(at -0.48 0 180)
			(size 0.59 0.64)
			(layers "F.Cu" "F.Mask" "F.Paste")
			(roundrect_rratio 0.25)
			(net 1 "GND")
			(pintype "passive")
			(teardrops
				(best_length_ratio 0.2)
				(max_length 1)
				(best_width_ratio 0.9)
				(max_width 2)
				(curved_edges yes)
				(filter_ratio 0.9)
				(enabled yes)
				(allow_two_segments yes)
				(prefer_zone_connections yes)
			)
		)
		(pad "2" smd roundrect
			(at 0.48 0 180)
			(size 0.59 0.64)
			(layers "F.Cu" "F.Mask" "F.Paste")
			(roundrect_rratio 0.25)
			(net 71 "Net-(U49-IN+)")
			(pintype "passive")
			(teardrops
				(best_length_ratio 0.2)
				(max_length 1)
				(best_width_ratio 0.9)
				(max_width 2)
				(curved_edges yes)
				(filter_ratio 0.9)
				(enabled yes)
				(allow_two_segments yes)
				(prefer_zone_connections yes)
			)
		)
	)
	(footprint "antmicro-footprints:TSOT23-6"
		(layer "F.Cu")
		(at 116.9 91.76)
		(property "Reference" "U4"
			(at -0.85 -1.75 0)
			(layer "F.SilkS")
			(effects
				(font
					(size 0.7 0.7)
					(thickness 0.15)
				)
				(justify left bottom)
			)
		)
		(property "Value" "AP22615A_TSOT26"
			(at 0 2.6 0)
			(layer "F.Fab")
			(effects
				(font
					(size 0.7 0.7)
					(thickness 0.15)
				)
				(justify left bottom)
			)
		)
		(property "Datasheet" "https://www.mouser.com/datasheet/2/115/DIOD_S_A0008958405_1-2543193.pdf"
			(at 0 0 0)
			(layer "F.Fab")
			(hide yes)
			(effects
				(font
					(size 1.27 1.27)
					(thickness 0.15)
				)
			)
		)
		(property "Author" "Antmicro"
			(at 0 0 0)
			(layer "F.Fab")
			(hide yes)
			(effects
				(font
					(size 1 1)
					(thickness 0.15)
				)
			)
		)
		(property "License" "Apache-2.0"
			(at 0 0 0)
			(layer "F.Fab")
			(hide yes)
			(effects
				(font
					(size 1 1)
					(thickness 0.15)
				)
			)
		)
		(property "MPN" "AP22615AWU-7"
			(at 0 0 0)
			(layer "F.Fab")
			(hide yes)
			(effects
				(font
					(size 1 1)
					(thickness 0.15)
				)
			)
		)
		(property "Manufacturer" "Diodes Incorporated"
			(at 0 0 0)
			(layer "F.Fab")
			(hide yes)
			(effects
				(font
					(size 1 1)
					(thickness 0.15)
				)
			)
		)
		(sheetname "2xUSB3.0+RJ45")
		(sheetfile "usb3+rj45.kicad_sch")
		(attr smd)
		(fp_line
			(start -1 -1.5)
			(end -1 -1.375)
			(stroke
				(width 0.15)
				(type solid)
			)
			(layer "F.SilkS")
		)
		(fp_line
			(start -1 1.55)
			(end -1 1.4)
			(stroke
				(width 0.15)
				(type solid)
			)
			(layer "F.SilkS")
		)
		(fp_line
			(start 1 -1.497)
			(end -1 -1.5)
			(stroke
				(width 0.15)
				(type solid)
			)
			(layer "F.SilkS")
		)
		(fp_line
			(start 1 -1.497)
			(end 1 -1.375)
			(stroke
				(width 0.15)
				(type solid)
			)
			(layer "F.SilkS")
		)
		(fp_line
			(start 1 1.55)
			(end -1 1.55)
			(stroke
				(width 0.15)
				(type solid)
			)
			(layer "F.SilkS")
		)
		(fp_line
			(start 1 1.55)
			(end 1 1.4)
			(stroke
				(width 0.15)
				(type solid)
			)
			(layer "F.SilkS")
		)
		(fp_circle
			(center -1.44 -1.5)
			(end -1.39 -1.5)
			(stroke
				(width 0.15)
				(type solid)
			)
			(fill yes)
			(layer "F.SilkS")
		)
		(fp_rect
			(start 1.93 -1.7)
			(end -1.93 1.7)
			(stroke
				(width 0.05)
				(type solid)
			)
			(fill no)
			(layer "F.CrtYd")
		)
		(fp_line
			(start -0.45 -1.521)
			(end -0.876 -1.096)
			(stroke
				(width 0.15)
				(type solid)
			)
			(layer "F.Fab")
		)
		(fp_rect
			(start 0.875 1.528)
			(end -0.875 -1.525)
			(stroke
				(width 0.15)
				(type solid)
			)
			(fill no)
			(layer "F.Fab")
		)
		(pad "1" smd rect
			(at -1.301 -0.947 270)
			(size 0.7 1.2)
			(layers "F.Cu" "F.Mask" "F.Paste")
			(net 43 "/2xUSB3.0+RJ45/P2_VBUS")
			(pinfunction "OUT")
			(pintype "power_out")
			(teardrops
				(best_length_ratio 0.2)
				(max_length 1)
				(best_width_ratio 0.9)
				(max_width 2)
				(curved_edges yes)
				(filter_ratio 0.9)
				(enabled yes)
				(allow_two_segments yes)
				(prefer_zone_connections yes)
			)
		)
		(pad "2" smd rect
			(at -1.301 0.004 270)
			(size 0.7 1.2)
			(layers "F.Cu" "F.Mask" "F.Paste")
			(net 1 "GND")
			(pinfunction "GND")
			(pintype "power_in")
			(teardrops
				(best_length_ratio 0.2)
				(max_length 1)
				(best_width_ratio 0.9)
				(max_width 2)
				(curved_edges yes)
				(filter_ratio 0.9)
				(enabled yes)
				(allow_two_segments yes)
				(prefer_zone_connections yes)
			)
		)
		(pad "3" smd rect
			(at -1.301 0.954 270)
			(size 0.7 1.2)
			(layers "F.Cu" "F.Mask" "F.Paste")
			(net 554 "/2xUSB3.0+RJ45/FLG_2B")
			(pinfunction "FLG")
			(pintype "output")
			(teardrops
				(best_length_ratio 0.2)
				(max_length 1)
				(best_width_ratio 0.9)
				(max_width 2)
				(curved_edges yes)
				(filter_ratio 0.9)
				(enabled yes)
				(allow_two_segments yes)
				(prefer_zone_connections yes)
			)
		)
		(pad "4" smd rect
			(at 1.299 0.954 270)
			(size 0.7 1.2)
			(layers "F.Cu" "F.Mask" "F.Paste")
			(net 556 "/2xUSB3.0+RJ45/EN_2B")
			(pinfunction "EN")
			(pintype "input")
			(teardrops
				(best_length_ratio 0.2)
				(max_length 1)
				(best_width_ratio 0.9)
				(max_width 2)
				(curved_edges yes)
				(filter_ratio 0.9)
				(enabled yes)
				(allow_two_segments yes)
				(prefer_zone_connections yes)
			)
		)
		(pad "5" smd rect
			(at 1.299 0.004 270)
			(size 0.7 1.2)
			(layers "F.Cu" "F.Mask" "F.Paste")
			(net 548 "/2xUSB3.0+RJ45/P2_ISET")
			(pinfunction "ISET")
			(pintype "passive")
			(teardrops
				(best_length_ratio 0.2)
				(max_length 1)
				(best_width_ratio 0.9)
				(max_width 2)
				(curved_edges yes)
				(filter_ratio 0.9)
				(enabled yes)
				(allow_two_segments yes)
				(prefer_zone_connections yes)
			)
		)
		(pad "6" smd rect
			(at 1.299 -0.947 270)
			(size 0.7 1.2)
			(layers "F.Cu" "F.Mask" "F.Paste")
			(net 52 "+5V")
			(pinfunction "IN")
			(pintype "power_in")
			(teardrops
				(best_length_ratio 0.2)
				(max_length 1)
				(best_width_ratio 0.9)
				(max_width 2)
				(curved_edges yes)
				(filter_ratio 0.9)
				(enabled yes)
				(allow_two_segments yes)
				(prefer_zone_connections yes)
			)
		)
	)
	(footprint "antmicro-footprints:R_0402_1005Metric"
		(layer "F.Cu")
		(at 313.075499 136.46 -90)
		(descr "Resistor SMD 0402")
		(tags "resistor SMD 0402")
		(property "Reference" "R111"
			(at -3.05 -5.624501 90)
			(layer "F.SilkS")
			(effects
				(font
					(size 0.7 0.7)
					(thickness 0.15)
				)
				(justify right bottom)
			)
		)
		(property "Value" "R_30k_0402"
			(at -1.011843 1.772047 90)
			(layer "F.Fab")
			(effects
				(font
					(size 0.7 0.7)
					(thickness 0.15)
				)
				(justify right bottom)
			)
		)
		(property "Datasheet" "https://www.bourns.com/docs/product-datasheets/cr.pdf"
			(at 0 0 270)
			(layer "F.Fab")
			(hide yes)
			(effects
				(font
					(size 1.27 1.27)
					(thickness 0.15)
				)
			)
		)
		(property "Author" "Antmicro"
			(at 176.615499 449.535499 0)
			(layer "F.Fab")
			(hide yes)
			(effects
				(font
					(size 1 1)
					(thickness 0.15)
				)
			)
		)
		(property "License" "Apache-2.0"
			(at 176.615499 449.535499 0)
			(layer "F.Fab")
			(hide yes)
			(effects
				(font
					(size 1 1)
					(thickness 0.15)
				)
			)
		)
		(property "MPN" "CR0402-FX-3002GLF"
			(at 176.615499 449.535499 0)
			(layer "F.Fab")
			(hide yes)
			(effects
				(font
					(size 1 1)
					(thickness 0.15)
				)
			)
		)
		(property "Manufacturer" "Bourns"
			(at 176.615499 449.535499 0)
			(layer "F.Fab")
			(hide yes)
			(effects
				(font
					(size 1 1)
					(thickness 0.15)
				)
			)
		)
		(property "Public" "False"
			(at 176.615499 449.535499 0)
			(layer "F.Fab")
			(hide yes)
			(effects
				(font
					(size 1 1)
					(thickness 0.15)
				)
			)
		)
		(property "Tolerance" "1%"
			(at 176.615499 449.535499 0)
			(layer "F.Fab")
			(hide yes)
			(effects
				(font
					(size 1 1)
					(thickness 0.15)
				)
			)
		)
		(property "Val" "30k"
			(at 176.615499 449.535499 0)
			(layer "F.Fab")
			(hide yes)
			(effects
				(font
					(size 1 1)
					(thickness 0.15)
				)
			)
		)
		(sheetname "Power")
		(sheetfile "power.kicad_sch")
		(attr smd)
		(fp_rect
			(start -0.925 -0.47)
			(end 0.925 0.47)
			(stroke
				(width 0.05)
				(type default)
			)
			(fill no)
			(layer "F.CrtYd")
		)
		(fp_rect
			(start -0.5 -0.25)
			(end 0.5 0.25)
			(stroke
				(width 0.15)
				(type solid)
			)
			(fill no)
			(layer "F.Fab")
		)
		(pad "1" smd roundrect
			(at -0.48 0 270)
			(size 0.59 0.64)
			(layers "F.Cu" "F.Mask" "F.Paste")
			(roundrect_rratio 0.25)
			(net 586 "Net-(U22-FB)")
			(pintype "passive")
			(teardrops
				(best_length_ratio 0.2)
				(max_length 1)
				(best_width_ratio 0.9)
				(max_width 2)
				(curved_edges yes)
				(filter_ratio 0.9)
				(enabled yes)
				(allow_two_segments yes)
				(prefer_zone_connections yes)
			)
		)
		(pad "2" smd roundrect
			(at 0.48 0 270)
			(size 0.59 0.64)
			(layers "F.Cu" "F.Mask" "F.Paste")
			(roundrect_rratio 0.25)
			(net 76 "Net-(C63-Pad2)")
			(pintype "passive")
			(teardrops
				(best_length_ratio 0.2)
				(max_length 1)
				(best_width_ratio 0.9)
				(max_width 2)
				(curved_edges yes)
				(filter_ratio 0.9)
				(enabled yes)
				(allow_two_segments yes)
				(prefer_zone_connections yes)
			)
		)
	)
	(footprint "antmicro-footprints:LED_0603_1608Metric_G"
		(layer "F.Cu")
		(at 188.70861 74.802163 90)
		(descr "LED SMD 0603 Green")
		(tags "LED SMD 0603 Green")
		(property "Reference" "D33"
			(at -1.1 -0.55 90)
			(layer "F.SilkS")
			(effects
				(font
					(size 0.7 0.7)
					(thickness 0.15)
				)
				(justify left bottom)
			)
		)
		(property "Value" "LED_G_0603_LTST-C190GKT"
			(at -0.001 1.599 90)
			(layer "F.Fab")
			(effects
				(font
					(size 0.7 0.7)
					(thickness 0.15)
				)
				(justify left bottom)
			)
		)
		(property "Datasheet" "https://media.digikey.com/pdf/Data%20Sheets/Lite-On%20PDFs/LTST-C190GKT.pdf"
			(at 0 0 90)
			(layer "F.Fab")
			(hide yes)
			(effects
				(font
					(size 1.27 1.27)
					(thickness 0.15)
				)
			)
		)
		(property "Author" "Antmicro"
			(at 263.510773 -113.906447 0)
			(layer "F.Fab")
			(hide yes)
			(effects
				(font
					(size 1 1)
					(thickness 0.15)
				)
			)
		)
		(property "Color" "Green"
			(at 263.510773 -113.906447 0)
			(layer "F.Fab")
			(hide yes)
			(effects
				(font
					(size 1 1)
					(thickness 0.15)
				)
			)
		)
		(property "License" "Apache-2.0"
			(at 263.510773 -113.906447 0)
			(layer "F.Fab")
			(hide yes)
			(effects
				(font
					(size 1 1)
					(thickness 0.15)
				)
			)
		)
		(property "MPN" "LTST-C190GKT"
			(at 263.510773 -113.906447 0)
			(layer "F.Fab")
			(hide yes)
			(effects
				(font
					(size 1 1)
					(thickness 0.15)
				)
			)
		)
		(property "Manufacturer" "Lite-On"
			(at 263.510773 -113.906447 0)
			(layer "F.Fab")
			(hide yes)
			(effects
				(font
					(size 1 1)
					(thickness 0.15)
				)
			)
		)
		(property "Public" "False"
			(at 263.510773 -113.906447 0)
			(layer "F.Fab")
			(hide yes)
			(effects
				(font
					(size 1 1)
					(thickness 0.15)
				)
			)
		)
		(sheetname "Power")
		(sheetfile "power.kicad_sch")
		(attr smd)
		(fp_line
			(start 0.22 -0.35)
			(end -0.22 -0.35)
			(stroke
				(width 0.15)
				(type solid)
			)
			(layer "F.SilkS")
		)
		(fp_line
			(start -1.18 -0.319)
			(end -1.18 0.321)
			(stroke
				(width 0.15)
				(type solid)
			)
			(layer "F.SilkS")
		)
		(fp_line
			(start 0.105328 0.001008)
			(end 0.24 0.001)
			(stroke
				(width 0.1)
				(type solid)
			)
			(layer "F.SilkS")
		)
		(fp_line
			(start -0.094672 0.001008)
			(end 0.105328 -0.198992)
			(stroke
				(width 0.1)
				(type solid)
			)
			(layer "F.SilkS")
		)
		(fp_line
			(start -0.094672 0.001008)
			(end -0.24 0.001008)
			(stroke
				(width 0.1)
				(type solid)
			)
			(layer "F.SilkS")
		)
		(fp_line
			(start 0.105328 0.201008)
			(end 0.105328 -0.198992)
			(stroke
				(width 0.1)
				(type solid)
			)
			(layer "F.SilkS")
		)
		(fp_line
			(start 0.105328 0.201008)
			(end -0.094672 0.001008)
			(stroke
				(width 0.1)
				(type solid)
			)
			(layer "F.SilkS")
		)
		(fp_line
			(start -0.094672 0.201008)
			(end -0.094672 -0.198992)
			(stroke
				(width 0.1)
				(type solid)
			)
			(layer "F.SilkS")
		)
		(fp_line
			(start 0.22 0.35)
			(end -0.22 0.35)
			(stroke
				(width 0.15)
				(type solid)
			)
			(layer "F.SilkS")
		)
		(fp_rect
			(start 1.25 0.65)
			(end -1.25 -0.65)
			(stroke
				(width 0.05)
				(type solid)
			)
			(fill no)
			(layer "F.CrtYd")
		)
		(fp_line
			(start 0.201 -0.202)
			(end -0.101 0)
			(stroke
				(width 0.15)
				(type solid)
			)
			(layer "F.Fab")
		)
		(fp_line
			(start -0.199 -0.202)
			(end -0.199 0.1)
			(stroke
				(width 0.15)
				(type solid)
			)
			(layer "F.Fab")
		)
		(fp_line
			(start 0.599 0)
			(end 0.201 0)
			(stroke
				(width 0.15)
				(type solid)
			)
			(layer "F.Fab")
		)
		(fp_line
			(start 0.201 0)
			(end 0.201 -0.202)
			(stroke
				(width 0.15)
				(type solid)
			)
			(layer "F.Fab")
		)
		(fp_line
			(start -0.101 0)
			(end 0.201 0.2)
			(stroke
				(width 0.15)
				(type solid)
			)
			(layer "F.Fab")
		)
		(fp_line
			(start -0.199 0)
			(end -0.597 0)
			(stroke
				(width 0.15)
				(type solid)
			)
			(layer "F.Fab")
		)
		(fp_line
			(start 0.201 0.2)
			(end 0.201 0)
			(stroke
				(width 0.15)
				(type solid)
			)
			(layer "F.Fab")
		)
		(fp_line
			(start -0.199 0.2)
			(end -0.199 0.1)
			(stroke
				(width 0.15)
				(type solid)
			)
			(layer "F.Fab")
		)
		(fp_rect
			(start 0.848 0.4)
			(end -0.85 -0.402)
			(stroke
				(width 0.15)
				(type solid)
			)
			(fill no)
			(layer "F.Fab")
		)
		(pad "1" smd roundrect
			(at -0.7 0 270)
			(size 0.8 1)
			(layers "F.Cu" "F.Mask" "F.Paste")
			(roundrect_rratio 0.2)
			(net 985 "Net-(D33-C)")
			(pinfunction "C")
			(pintype "passive")
			(teardrops
				(best_length_ratio 0.2)
				(max_length 1)
				(best_width_ratio 0.9)
				(max_width 2)
				(curved_edges yes)
				(filter_ratio 0.9)
				(enabled yes)
				(allow_two_segments yes)
				(prefer_zone_connections yes)
			)
		)
		(pad "2" smd roundrect
			(at 0.7 0 270)
			(size 0.8 1)
			(layers "F.Cu" "F.Mask" "F.Paste")
			(roundrect_rratio 0.2)
			(net 77 "+5V_AON")
			(pinfunction "A")
			(pintype "passive")
			(teardrops
				(best_length_ratio 0.2)
				(max_length 1)
				(best_width_ratio 0.9)
				(max_width 2)
				(curved_edges yes)
				(filter_ratio 0.9)
				(enabled yes)
				(allow_two_segments yes)
				(prefer_zone_connections yes)
			)
		)
	)
	(footprint "antmicro-footprints:R_0402_1005Metric"
		(layer "F.Cu")
		(at 122.05 88.06 180)
		(descr "Resistor SMD 0402")
		(tags "resistor SMD 0402")
		(property "Reference" "R26"
			(at -2.95 -0.45 0)
			(layer "F.SilkS")
			(effects
				(font
					(size 0.7 0.7)
					(thickness 0.15)
				)
				(justify right bottom)
			)
		)
		(property "Value" "R_0R_0402"
			(at -1.011843 1.772047 0)
			(layer "F.Fab")
			(effects
				(font
					(size 0.7 0.7)
					(thickness 0.15)
				)
				(justify right bottom)
			)
		)
		(property "Datasheet" "https://industrial.panasonic.com/cdbs/www-data/pdf/RDA0000/AOA0000C301.pdf"
			(at 0 0 180)
			(layer "F.Fab")
			(hide yes)
			(effects
				(font
					(size 1.27 1.27)
					(thickness 0.15)
				)
			)
		)
		(property "Author" "Antmicro"
			(at 244.1 176.12 0)
			(layer "F.Fab")
			(hide yes)
			(effects
				(font
					(size 1 1)
					(thickness 0.15)
				)
			)
		)
		(property "Current" "1A"
			(at 244.1 176.12 0)
			(layer "F.Fab")
			(hide yes)
			(effects
				(font
					(size 1 1)
					(thickness 0.15)
				)
			)
		)
		(property "License" "Apache-2.0"
			(at 244.1 176.12 0)
			(layer "F.Fab")
			(hide yes)
			(effects
				(font
					(size 1 1)
					(thickness 0.15)
				)
			)
		)
		(property "MPN" "ERJ2GE0R00X"
			(at 244.1 176.12 0)
			(layer "F.Fab")
			(hide yes)
			(effects
				(font
					(size 1 1)
					(thickness 0.15)
				)
			)
		)
		(property "Manufacturer" "Panasonic"
			(at 244.1 176.12 0)
			(layer "F.Fab")
			(hide yes)
			(effects
				(font
					(size 1 1)
					(thickness 0.15)
				)
			)
		)
		(property "Public" "False"
			(at 244.1 176.12 0)
			(layer "F.Fab")
			(hide yes)
			(effects
				(font
					(size 1 1)
					(thickness 0.15)
				)
			)
		)
		(property "Tolerance" ""
			(at 244.1 176.12 0)
			(layer "F.Fab")
			(hide yes)
			(effects
				(font
					(size 1 1)
					(thickness 0.15)
				)
			)
		)
		(property "Val" "0R"
			(at 244.1 176.12 0)
			(layer "F.Fab")
			(hide yes)
			(effects
				(font
					(size 1 1)
					(thickness 0.15)
				)
			)
		)
		(sheetname "2xUSB3.0+RJ45")
		(sheetfile "usb3+rj45.kicad_sch")
		(attr smd)
		(fp_rect
			(start -0.925 -0.47)
			(end 0.925 0.47)
			(stroke
				(width 0.05)
				(type default)
			)
			(fill no)
			(layer "F.CrtYd")
		)
		(fp_rect
			(start -0.5 -0.25)
			(end 0.5 0.25)
			(stroke
				(width 0.15)
				(type solid)
			)
			(fill no)
			(layer "F.Fab")
		)
		(pad "1" smd roundrect
			(at -0.48 0 180)
			(size 0.59 0.64)
			(layers "F.Cu" "F.Mask" "F.Paste")
			(roundrect_rratio 0.25)
			(net 314 "/2xUSB3.0+RJ45/FLG_1")
			(pintype "passive")
			(teardrops
				(best_length_ratio 0.2)
				(max_length 1)
				(best_width_ratio 0.9)
				(max_width 2)
				(curved_edges yes)
				(filter_ratio 0.9)
				(enabled yes)
				(allow_two_segments yes)
				(prefer_zone_connections yes)
			)
		)
		(pad "2" smd roundrect
			(at 0.48 0 180)
			(size 0.59 0.64)
			(layers "F.Cu" "F.Mask" "F.Paste")
			(roundrect_rratio 0.25)
			(net 553 "/2xUSB3.0+RJ45/FLG_1B")
			(pintype "passive")
			(teardrops
				(best_length_ratio 0.2)
				(max_length 1)
				(best_width_ratio 0.9)
				(max_width 2)
				(curved_edges yes)
				(filter_ratio 0.9)
				(enabled yes)
				(allow_two_segments yes)
				(prefer_zone_connections yes)
			)
		)
	)
	(footprint "antmicro-footprints:C_0402_1005Metric"
		(layer "F.Cu")
		(at 297.2 98.670999)
		(descr "Capacitor SMD 0402")
		(tags "capacitor SMD 0402")
		(property "Reference" "C66"
			(at -1.15 -0.460999 0)
			(layer "F.SilkS")
			(effects
				(font
					(size 0.7 0.7)
					(thickness 0.15)
				)
				(justify left bottom)
			)
		)
		(property "Value" "C_1u_0402"
			(at -1.022927 2.155213 0)
			(layer "F.Fab")
			(effects
				(font
					(size 0.7 0.7)
					(thickness 0.15)
				)
				(justify left bottom)
			)
		)
		(property "Datasheet" "https://product.tdk.com/en/search/capacitor/ceramic/mlcc/info?part_no=C1005X6S1A105K050BC"
			(at 0 0 0)
			(layer "F.Fab")
			(hide yes)
			(effects
				(font
					(size 1.27 1.27)
					(thickness 0.15)
				)
			)
		)
		(property "Author" "Antmicro"
			(at 0 0 0)
			(layer "F.Fab")
			(hide yes)
			(effects
				(font
					(size 1 1)
					(thickness 0.15)
				)
			)
		)
		(property "Dielectric" ""
			(at 0 0 0)
			(layer "F.Fab")
			(hide yes)
			(effects
				(font
					(size 1 1)
					(thickness 0.15)
				)
			)
		)
		(property "License" "Apache-2.0"
			(at 0 0 0)
			(layer "F.Fab")
			(hide yes)
			(effects
				(font
					(size 1 1)
					(thickness 0.15)
				)
			)
		)
		(property "MPN" "C1005X6S1A105K050BC"
			(at 0 0 0)
			(layer "F.Fab")
			(hide yes)
			(effects
				(font
					(size 1 1)
					(thickness 0.15)
				)
			)
		)
		(property "Manufacturer" "TDK"
			(at 0 0 0)
			(layer "F.Fab")
			(hide yes)
			(effects
				(font
					(size 1 1)
					(thickness 0.15)
				)
			)
		)
		(property "Public" "False"
			(at 0 0 0)
			(layer "F.Fab")
			(hide yes)
			(effects
				(font
					(size 1 1)
					(thickness 0.15)
				)
			)
		)
		(property "Val" "1u"
			(at 0 0 0)
			(layer "F.Fab")
			(hide yes)
			(effects
				(font
					(size 1 1)
					(thickness 0.15)
				)
			)
		)
		(property "Voltage" ""
			(at 0 0 0)
			(layer "F.Fab")
			(hide yes)
			(effects
				(font
					(size 1 1)
					(thickness 0.15)
				)
			)
		)
		(sheetname "Power")
		(sheetfile "power.kicad_sch")
		(attr smd)
		(fp_rect
			(start -0.925 -0.47)
			(end 0.925 0.47)
			(stroke
				(width 0.05)
				(type default)
			)
			(fill no)
			(layer "F.CrtYd")
		)
		(fp_line
			(start -0.494 -0.25)
			(end 0.504 -0.25)
			(stroke
				(width 0.15)
				(type solid)
			)
			(layer "F.Fab")
		)
		(fp_line
			(start -0.494 0.248)
			(end -0.494 -0.25)
			(stroke
				(width 0.15)
				(type solid)
			)
			(layer "F.Fab")
		)
		(fp_line
			(start 0.504 -0.25)
			(end 0.504 0.248)
			(stroke
				(width 0.15)
				(type solid)
			)
			(layer "F.Fab")
		)
		(fp_line
			(start 0.504 0.248)
			(end -0.494 0.248)
			(stroke
				(width 0.15)
				(type solid)
			)
			(layer "F.Fab")
		)
		(pad "1" smd roundrect
			(at -0.48 0)
			(size 0.59 0.64)
			(layers "F.Cu" "F.Mask" "F.Paste")
			(roundrect_rratio 0.25)
			(net 1 "GND")
			(pintype "passive")
			(teardrops
				(best_length_ratio 0.2)
				(max_length 1)
				(best_width_ratio 0.9)
				(max_width 2)
				(curved_edges yes)
				(filter_ratio 0.9)
				(enabled yes)
				(allow_two_segments yes)
				(prefer_zone_connections yes)
			)
		)
		(pad "2" smd roundrect
			(at 0.48 0)
			(size 0.59 0.64)
			(layers "F.Cu" "F.Mask" "F.Paste")
			(roundrect_rratio 0.25)
			(net 77 "+5V_AON")
			(pintype "passive")
			(teardrops
				(best_length_ratio 0.2)
				(max_length 1)
				(best_width_ratio 0.9)
				(max_width 2)
				(curved_edges yes)
				(filter_ratio 0.9)
				(enabled yes)
				(allow_two_segments yes)
				(prefer_zone_connections yes)
			)
		)
	)
	(footprint "antmicro-footprints:TP_SMD_0.75mm"
		(layer "F.Cu")
		(at 147.9 128.71)
		(property "Reference" "TP65"
			(at 0.4 -3.3 90)
			(layer "F.SilkS")
			(effects
				(font
					(size 0.7 0.7)
					(thickness 0.15)
				)
				(justify left bottom)
			)
		)
		(property "Value" "TP_0.75mm_SMD"
			(at 0 1.2 0)
			(layer "F.Fab")
			(effects
				(font
					(size 0.7 0.7)
					(thickness 0.15)
				)
				(justify left bottom)
			)
		)
		(property "Author" "Antmicro"
			(at 0 0 0)
			(layer "F.Fab")
			(hide yes)
			(effects
				(font
					(size 1 1)
					(thickness 0.15)
				)
			)
		)
		(property "License" "Apache-2.0"
			(at 0 0 0)
			(layer "F.Fab")
			(hide yes)
			(effects
				(font
					(size 1 1)
					(thickness 0.15)
				)
			)
		)
		(property "MPN" ""
			(at 0 0 0)
			(layer "F.Fab")
			(hide yes)
			(effects
				(font
					(size 1 1)
					(thickness 0.15)
				)
			)
		)
		(property "Manufacturer" ""
			(at 0 0 0)
			(layer "F.Fab")
			(hide yes)
			(effects
				(font
					(size 1 1)
					(thickness 0.15)
				)
			)
		)
		(property "Public" "False"
			(at 0 0 0)
			(layer "F.Fab")
			(hide yes)
			(effects
				(font
					(size 1 1)
					(thickness 0.15)
				)
			)
		)
		(sheetname "KR to SFI #1")
		(sheetfile "kr_sfi.kicad_sch")
		(attr exclude_from_pos_files exclude_from_bom)
		(fp_circle
			(center 0 0)
			(end 0.475 0)
			(stroke
				(width 0.05)
				(type default)
			)
			(fill no)
			(layer "F.CrtYd")
		)
		(pad "1" smd circle
			(at 0 0)
			(size 0.75 0.75)
			(layers "F.Cu" "F.Mask")
			(net 728 "Net-(U43C-AMUXA)")
			(pinfunction "1")
			(pintype "passive")
			(teardrops
				(best_length_ratio 0.4)
				(max_length 1)
				(best_width_ratio 0.9)
				(max_width 2)
				(curved_edges yes)
				(filter_ratio 0.9)
				(enabled yes)
				(allow_two_segments yes)
				(prefer_zone_connections yes)
			)
		)
	)
	(footprint "antmicro-footprints:R_0402_1005Metric"
		(layer "F.Cu")
		(at 237.77 152.930999 180)
		(descr "Resistor SMD 0402")
		(tags "resistor SMD 0402")
		(property "Reference" "R170"
			(at -3.68 -0.429001 0)
			(layer "F.SilkS")
			(effects
				(font
					(size 0.7 0.7)
					(thickness 0.15)
				)
				(justify right bottom)
			)
		)
		(property "Value" "R_1k_0402"
			(at -1.011843 1.772047 0)
			(layer "F.Fab")
			(effects
				(font
					(size 0.7 0.7)
					(thickness 0.15)
				)
				(justify right bottom)
			)
		)
		(property "Datasheet" "https://www.bourns.com/docs/product-datasheets/cr.pdf"
			(at 0 0 180)
			(layer "F.Fab")
			(hide yes)
			(effects
				(font
					(size 1.27 1.27)
					(thickness 0.15)
				)
			)
		)
		(property "Author" "Antmicro"
			(at 475.54 305.861998 0)
			(layer "F.Fab")
			(hide yes)
			(effects
				(font
					(size 1 1)
					(thickness 0.15)
				)
			)
		)
		(property "License" "Apache-2.0"
			(at 475.54 305.861998 0)
			(layer "F.Fab")
			(hide yes)
			(effects
				(font
					(size 1 1)
					(thickness 0.15)
				)
			)
		)
		(property "MPN" "CR0402-FX-1001GLF"
			(at 475.54 305.861998 0)
			(layer "F.Fab")
			(hide yes)
			(effects
				(font
					(size 1 1)
					(thickness 0.15)
				)
			)
		)
		(property "Manufacturer" "Bourns"
			(at 475.54 305.861998 0)
			(layer "F.Fab")
			(hide yes)
			(effects
				(font
					(size 1 1)
					(thickness 0.15)
				)
			)
		)
		(property "Public" "False"
			(at 475.54 305.861998 0)
			(layer "F.Fab")
			(hide yes)
			(effects
				(font
					(size 1 1)
					(thickness 0.15)
				)
			)
		)
		(property "Tolerance" "1%"
			(at 475.54 305.861998 0)
			(layer "F.Fab")
			(hide yes)
			(effects
				(font
					(size 1 1)
					(thickness 0.15)
				)
			)
		)
		(property "Val" "1k"
			(at 475.54 305.861998 0)
			(layer "F.Fab")
			(hide yes)
			(effects
				(font
					(size 1 1)
					(thickness 0.15)
				)
			)
		)
		(sheetname "Com Express 7 MGMT")
		(sheetfile "com_express_7_mgmt.kicad_sch")
		(attr smd dnp)
		(fp_rect
			(start -0.925 -0.47)
			(end 0.925 0.47)
			(stroke
				(width 0.05)
				(type default)
			)
			(fill no)
			(layer "F.CrtYd")
		)
		(fp_rect
			(start -0.5 -0.25)
			(end 0.5 0.25)
			(stroke
				(width 0.15)
				(type solid)
			)
			(fill no)
			(layer "F.Fab")
		)
		(pad "1" smd roundrect
			(at -0.48 0 180)
			(size 0.59 0.64)
			(layers "F.Cu" "F.Mask" "F.Paste")
			(roundrect_rratio 0.25)
			(net 598 "Net-(U31-~{WC})")
			(pintype "passive")
			(teardrops
				(best_length_ratio 0.2)
				(max_length 1)
				(best_width_ratio 0.9)
				(max_width 2)
				(curved_edges yes)
				(filter_ratio 0.9)
				(enabled yes)
				(allow_two_segments yes)
				(prefer_zone_connections yes)
			)
		)
		(pad "2" smd roundrect
			(at 0.48 0 180)
			(size 0.59 0.64)
			(layers "F.Cu" "F.Mask" "F.Paste")
			(roundrect_rratio 0.25)
			(net 73 "+3V3_AON")
			(pintype "passive")
			(teardrops
				(best_length_ratio 0.2)
				(max_length 1)
				(best_width_ratio 0.9)
				(max_width 2)
				(curved_edges yes)
				(filter_ratio 0.9)
				(enabled yes)
				(allow_two_segments yes)
				(prefer_zone_connections yes)
			)
		)
	)
	(footprint "antmicro-footprints:PLCC4_3.2x2.8mm"
		(layer "F.Cu")
		(at 102.45 72.31 90)
		(property "Reference" "D18"
			(at -1.25 -2.9 90)
			(unlocked yes)
			(layer "F.SilkS")
			(effects
				(font
					(size 0.7 0.7)
					(thickness 0.15)
				)
				(justify left bottom)
			)
		)
		(property "Value" "LED_RGB_PLCC4_ASMB_MTB1_0A3A2"
			(at 0 2.7 90)
			(unlocked yes)
			(layer "F.Fab")
			(effects
				(font
					(size 0.7 0.7)
					(thickness 0.15)
				)
				(justify left bottom)
			)
		)
		(property "Datasheet" "https://docs.broadcom.com/doc/AV02-4194EN"
			(at 0 0 90)
			(layer "F.Fab")
			(hide yes)
			(effects
				(font
					(size 1.27 1.27)
					(thickness 0.15)
				)
			)
		)
		(property "Author" "Antmicro"
			(at 174.76 -30.14 0)
			(layer "F.Fab")
			(hide yes)
			(effects
				(font
					(size 1 1)
					(thickness 0.15)
				)
			)
		)
		(property "Color" "R, G, B"
			(at 174.76 -30.14 0)
			(layer "F.Fab")
			(hide yes)
			(effects
				(font
					(size 1 1)
					(thickness 0.15)
				)
			)
		)
		(property "License" "Apache-2.0"
			(at 174.76 -30.14 0)
			(layer "F.Fab")
			(hide yes)
			(effects
				(font
					(size 1 1)
					(thickness 0.15)
				)
			)
		)
		(property "MPN" "ASMB-MTB1-0A3A2"
			(at 174.76 -30.14 0)
			(layer "F.Fab")
			(hide yes)
			(effects
				(font
					(size 1 1)
					(thickness 0.15)
				)
			)
		)
		(property "Manufacturer" "Avago Technologies"
			(at 174.76 -30.14 0)
			(layer "F.Fab")
			(hide yes)
			(effects
				(font
					(size 1 1)
					(thickness 0.15)
				)
			)
		)
		(sheetname "Misc")
		(sheetfile "misc.kicad_sch")
		(attr smd)
		(fp_line
			(start -1.75 -1.491)
			(end 1.947 -1.491)
			(stroke
				(width 0.15)
				(type solid)
			)
			(layer "F.SilkS")
		)
		(fp_line
			(start -1.953 1.509)
			(end 1.947 1.509)
			(stroke
				(width 0.15)
				(type solid)
			)
			(layer "F.SilkS")
		)
		(fp_circle
			(center -2 -1.45)
			(end -1.95 -1.45)
			(stroke
				(width 0.15)
				(type solid)
			)
			(fill yes)
			(layer "F.SilkS")
		)
		(fp_rect
			(start -2.25 -1.65)
			(end 2.24 1.65)
			(stroke
				(width 0.05)
				(type solid)
			)
			(fill no)
			(layer "F.CrtYd")
		)
		(fp_line
			(start 1.597 -1.391)
			(end -1.603 -1.391)
			(stroke
				(width 0.15)
				(type solid)
			)
			(layer "F.Fab")
		)
		(fp_line
			(start -0.603 -1.391)
			(end -1.603 -0.391)
			(stroke
				(width 0.15)
				(type solid)
			)
			(layer "F.Fab")
		)
		(fp_line
			(start -1.603 -1.391)
			(end -1.603 1.409)
			(stroke
				(width 0.15)
				(type solid)
			)
			(layer "F.Fab")
		)
		(fp_line
			(start 1.597 1.409)
			(end 1.597 -1.391)
			(stroke
				(width 0.15)
				(type solid)
			)
			(layer "F.Fab")
		)
		(fp_line
			(start -1.603 1.409)
			(end 1.597 1.409)
			(stroke
				(width 0.15)
				(type solid)
			)
			(layer "F.Fab")
		)
		(fp_circle
			(center -0.003 0.009)
			(end 1.117 0.009)
			(stroke
				(width 0.15)
				(type solid)
			)
			(fill no)
			(layer "F.Fab")
		)
		(pad "1" smd rect
			(at -1.255 -0.74 90)
			(size 1.5 1.1)
			(layers "F.Cu" "F.Mask" "F.Paste")
			(net 132 "Net-(D18-C_{R})")
			(pinfunction "C_{R}")
			(pintype "passive")
			(teardrops
				(best_length_ratio 0.2)
				(max_length 1)
				(best_width_ratio 0.9)
				(max_width 2)
				(curved_edges yes)
				(filter_ratio 0.9)
				(enabled yes)
				(allow_two_segments yes)
				(prefer_zone_connections yes)
			)
		)
		(pad "2" smd rect
			(at 1.245 -0.74 90)
			(size 1.5 1.1)
			(layers "F.Cu" "F.Mask" "F.Paste")
			(net 133 "Net-(D18-C_{G})")
			(pinfunction "C_{G}")
			(pintype "passive")
			(teardrops
				(best_length_ratio 0.2)
				(max_length 1)
				(best_width_ratio 0.9)
				(max_width 2)
				(curved_edges yes)
				(filter_ratio 0.9)
				(enabled yes)
				(allow_two_segments yes)
				(prefer_zone_connections yes)
			)
		)
		(pad "3" smd rect
			(at 1.245 0.76 90)
			(size 1.5 1.1)
			(layers "F.Cu" "F.Mask" "F.Paste")
			(net 134 "unconnected-(D18-C_{B}-Pad3)")
			(pinfunction "C_{B}")
			(pintype "passive+no_connect")
			(teardrops
				(best_length_ratio 0.2)
				(max_length 1)
				(best_width_ratio 0.9)
				(max_width 2)
				(curved_edges yes)
				(filter_ratio 0.9)
				(enabled yes)
				(allow_two_segments yes)
				(prefer_zone_connections yes)
			)
		)
		(pad "4" smd rect
			(at -1.255 0.76 90)
			(size 1.5 1.1)
			(layers "F.Cu" "F.Mask" "F.Paste")
			(net 77 "+5V_AON")
			(pinfunction "A")
			(pintype "passive")
			(teardrops
				(best_length_ratio 0.2)
				(max_length 1)
				(best_width_ratio 0.9)
				(max_width 2)
				(curved_edges yes)
				(filter_ratio 0.9)
				(enabled yes)
				(allow_two_segments yes)
				(prefer_zone_connections yes)
			)
		)
	)
	(footprint "antmicro-footprints:R_0402_1005Metric"
		(layer "F.Cu")
		(at 302.24 127.79 180)
		(descr "Resistor SMD 0402")
		(tags "resistor SMD 0402")
		(property "Reference" "R105"
			(at -0.96 0.53 0)
			(layer "F.SilkS")
			(effects
				(font
					(size 0.7 0.7)
					(thickness 0.15)
				)
				(justify right bottom)
			)
		)
		(property "Value" "R_1k_0402"
			(at -1.011843 1.772047 0)
			(layer "F.Fab")
			(effects
				(font
					(size 0.7 0.7)
					(thickness 0.15)
				)
				(justify right bottom)
			)
		)
		(property "Datasheet" "https://www.bourns.com/docs/product-datasheets/cr.pdf"
			(at 0 0 180)
			(layer "F.Fab")
			(hide yes)
			(effects
				(font
					(size 1.27 1.27)
					(thickness 0.15)
				)
			)
		)
		(property "Author" "Antmicro"
			(at 604.48 255.58 0)
			(layer "F.Fab")
			(hide yes)
			(effects
				(font
					(size 1 1)
					(thickness 0.15)
				)
			)
		)
		(property "License" "Apache-2.0"
			(at 604.48 255.58 0)
			(layer "F.Fab")
			(hide yes)
			(effects
				(font
					(size 1 1)
					(thickness 0.15)
				)
			)
		)
		(property "MPN" "CR0402-FX-1001GLF"
			(at 604.48 255.58 0)
			(layer "F.Fab")
			(hide yes)
			(effects
				(font
					(size 1 1)
					(thickness 0.15)
				)
			)
		)
		(property "Manufacturer" "Bourns"
			(at 604.48 255.58 0)
			(layer "F.Fab")
			(hide yes)
			(effects
				(font
					(size 1 1)
					(thickness 0.15)
				)
			)
		)
		(property "Public" "False"
			(at 604.48 255.58 0)
			(layer "F.Fab")
			(hide yes)
			(effects
				(font
					(size 1 1)
					(thickness 0.15)
				)
			)
		)
		(property "Tolerance" "1%"
			(at 604.48 255.58 0)
			(layer "F.Fab")
			(hide yes)
			(effects
				(font
					(size 1 1)
					(thickness 0.15)
				)
			)
		)
		(property "Val" "1k"
			(at 604.48 255.58 0)
			(layer "F.Fab")
			(hide yes)
			(effects
				(font
					(size 1 1)
					(thickness 0.15)
				)
			)
		)
		(sheetname "Power")
		(sheetfile "power.kicad_sch")
		(attr smd)
		(fp_rect
			(start -0.925 -0.47)
			(end 0.925 0.47)
			(stroke
				(width 0.05)
				(type default)
			)
			(fill no)
			(layer "F.CrtYd")
		)
		(fp_rect
			(start -0.5 -0.25)
			(end 0.5 0.25)
			(stroke
				(width 0.15)
				(type solid)
			)
			(fill no)
			(layer "F.Fab")
		)
		(pad "1" smd roundrect
			(at -0.48 0 180)
			(size 0.59 0.64)
			(layers "F.Cu" "F.Mask" "F.Paste")
			(roundrect_rratio 0.25)
			(net 1 "GND")
			(pintype "passive")
			(teardrops
				(best_length_ratio 0.2)
				(max_length 1)
				(best_width_ratio 0.9)
				(max_width 2)
				(curved_edges yes)
				(filter_ratio 0.9)
				(enabled yes)
				(allow_two_segments yes)
				(prefer_zone_connections yes)
			)
		)
		(pad "2" smd roundrect
			(at 0.48 0 180)
			(size 0.59 0.64)
			(layers "F.Cu" "F.Mask" "F.Paste")
			(roundrect_rratio 0.25)
			(net 365 "/Com Express 7 MGMT/PWR_OK")
			(pintype "passive")
			(teardrops
				(best_length_ratio 0.2)
				(max_length 1)
				(best_width_ratio 0.9)
				(max_width 2)
				(curved_edges yes)
				(filter_ratio 0.9)
				(enabled yes)
				(allow_two_segments yes)
				(prefer_zone_connections yes)
			)
		)
	)
	(footprint "antmicro-footprints:R_0402_1005Metric"
		(layer "F.Cu")
		(at 122.05 91.96)
		(descr "Resistor SMD 0402")
		(tags "resistor SMD 0402")
		(property "Reference" "R19"
			(at 0.75 0.45 0)
			(layer "F.SilkS")
			(effects
				(font
					(size 0.7 0.7)
					(thickness 0.15)
				)
				(justify left bottom)
			)
		)
		(property "Value" "R_10k_0402"
			(at -1.011843 1.772047 0)
			(layer "F.Fab")
			(effects
				(font
					(size 0.7 0.7)
					(thickness 0.15)
				)
				(justify left bottom)
			)
		)
		(property "Datasheet" "https://www.bourns.com/docs/product-datasheets/cr.pdf"
			(at 0 0 0)
			(layer "F.Fab")
			(hide yes)
			(effects
				(font
					(size 1.27 1.27)
					(thickness 0.15)
				)
			)
		)
		(property "Author" "Antmicro"
			(at 0 0 0)
			(layer "F.Fab")
			(hide yes)
			(effects
				(font
					(size 1 1)
					(thickness 0.15)
				)
			)
		)
		(property "License" "Apache-2.0"
			(at 0 0 0)
			(layer "F.Fab")
			(hide yes)
			(effects
				(font
					(size 1 1)
					(thickness 0.15)
				)
			)
		)
		(property "MPN" "CR0402-FX-1002GLF"
			(at 0 0 0)
			(layer "F.Fab")
			(hide yes)
			(effects
				(font
					(size 1 1)
					(thickness 0.15)
				)
			)
		)
		(property "Manufacturer" "Bourns"
			(at 0 0 0)
			(layer "F.Fab")
			(hide yes)
			(effects
				(font
					(size 1 1)
					(thickness 0.15)
				)
			)
		)
		(property "Public" "False"
			(at 0 0 0)
			(layer "F.Fab")
			(hide yes)
			(effects
				(font
					(size 1 1)
					(thickness 0.15)
				)
			)
		)
		(property "Tolerance" "1%"
			(at 0 0 0)
			(layer "F.Fab")
			(hide yes)
			(effects
				(font
					(size 1 1)
					(thickness 0.15)
				)
			)
		)
		(property "Val" "10k"
			(at 0 0 0)
			(layer "F.Fab")
			(hide yes)
			(effects
				(font
					(size 1 1)
					(thickness 0.15)
				)
			)
		)
		(sheetname "2xUSB3.0+RJ45")
		(sheetfile "usb3+rj45.kicad_sch")
		(attr smd dnp)
		(fp_rect
			(start -0.925 -0.47)
			(end 0.925 0.47)
			(stroke
				(width 0.05)
				(type default)
			)
			(fill no)
			(layer "F.CrtYd")
		)
		(fp_rect
			(start -0.5 -0.25)
			(end 0.5 0.25)
			(stroke
				(width 0.15)
				(type solid)
			)
			(fill no)
			(layer "F.Fab")
		)
		(pad "1" smd roundrect
			(at -0.48 0)
			(size 0.59 0.64)
			(layers "F.Cu" "F.Mask" "F.Paste")
			(roundrect_rratio 0.25)
			(net 554 "/2xUSB3.0+RJ45/FLG_2B")
			(pintype "passive")
			(teardrops
				(best_length_ratio 0.2)
				(max_length 1)
				(best_width_ratio 0.9)
				(max_width 2)
				(curved_edges yes)
				(filter_ratio 0.9)
				(enabled yes)
				(allow_two_segments yes)
				(prefer_zone_connections yes)
			)
		)
		(pad "2" smd roundrect
			(at 0.48 0)
			(size 0.59 0.64)
			(layers "F.Cu" "F.Mask" "F.Paste")
			(roundrect_rratio 0.25)
			(net 2 "+3V3")
			(pintype "passive")
			(teardrops
				(best_length_ratio 0.2)
				(max_length 1)
				(best_width_ratio 0.9)
				(max_width 2)
				(curved_edges yes)
				(filter_ratio 0.9)
				(enabled yes)
				(allow_two_segments yes)
				(prefer_zone_connections yes)
			)
		)
	)
	(footprint "antmicro-footprints:Choke_0805_2012Metric"
		(layer "F.Cu")
		(at 127.25 105.5 180)
		(property "Reference" "T2"
			(at 1.6 -1.85 0)
			(unlocked yes)
			(layer "F.SilkS")
			(effects
				(font
					(size 0.7 0.7)
					(thickness 0.15)
				)
				(justify left bottom)
			)
		)
		(property "Value" "Choke_SRF2012A-801Y"
			(at 0 -7 180)
			(unlocked yes)
			(layer "F.Fab")
			(effects
				(font
					(size 0.7 0.7)
					(thickness 0.15)
				)
				(justify left bottom)
			)
		)
		(property "Datasheet" "https://www.bourns.com/docs/product-datasheets/srf2012a-801y.pdf"
			(at 0 0 180)
			(layer "F.Fab")
			(hide yes)
			(effects
				(font
					(size 1.27 1.27)
					(thickness 0.15)
				)
			)
		)
		(property "Author" "Antmicro"
			(at 254.5 211 0)
			(layer "F.Fab")
			(hide yes)
			(effects
				(font
					(size 1 1)
					(thickness 0.15)
				)
			)
		)
		(property "IMax" "0.3 A"
			(at 254.5 211 0)
			(layer "F.Fab")
			(hide yes)
			(effects
				(font
					(size 1 1)
					(thickness 0.15)
				)
			)
		)
		(property "License" "Apache-2.0"
			(at 254.5 211 0)
			(layer "F.Fab")
			(hide yes)
			(effects
				(font
					(size 1 1)
					(thickness 0.15)
				)
			)
		)
		(property "MPN" "SRF2012A-801Y"
			(at 254.5 211 0)
			(layer "F.Fab")
			(hide yes)
			(effects
				(font
					(size 1 1)
					(thickness 0.15)
				)
			)
		)
		(property "Manufacturer" "Bourns"
			(at 254.5 211 0)
			(layer "F.Fab")
			(hide yes)
			(effects
				(font
					(size 1 1)
					(thickness 0.15)
				)
			)
		)
		(property "Public" "False"
			(at 254.5 211 0)
			(layer "F.Fab")
			(hide yes)
			(effects
				(font
					(size 1 1)
					(thickness 0.15)
				)
			)
		)
		(property ki_fp_filters "IND_ACM9070_TDK")
		(sheetname "2xUSB3.0+RJ45")
		(sheetfile "usb3+rj45.kicad_sch")
		(attr smd)
		(fp_rect
			(start -1.5 -0.9)
			(end 1.5 0.9)
			(stroke
				(width 0.05)
				(type solid)
			)
			(fill no)
			(layer "F.CrtYd")
		)
		(pad "1" smd roundrect
			(at -0.96 -0.46 180)
			(size 0.675 0.475)
			(layers "F.Cu" "F.Mask" "F.Paste")
			(roundrect_rratio 0.25)
			(net 691 "/2xUSB3.0+RJ45/DB_FL+")
			(pinfunction "1")
			(pintype "passive")
			(teardrops
				(best_length_ratio 0.2)
				(max_length 1)
				(best_width_ratio 0.9)
				(max_width 2)
				(curved_edges yes)
				(filter_ratio 0.9)
				(enabled yes)
				(allow_two_segments yes)
				(prefer_zone_connections yes)
			)
		)
		(pad "2" smd roundrect
			(at 0.96 -0.46 180)
			(size 0.675 0.475)
			(layers "F.Cu" "F.Mask" "F.Paste")
			(roundrect_rratio 0.25)
			(net 148 "/2xUSB3.0+RJ45/DB+")
			(pinfunction "2")
			(pintype "passive")
			(teardrops
				(best_length_ratio 0.2)
				(max_length 1)
				(best_width_ratio 0.9)
				(max_width 2)
				(curved_edges yes)
				(filter_ratio 0.9)
				(enabled yes)
				(allow_two_segments yes)
				(prefer_zone_connections yes)
			)
		)
		(pad "3" smd roundrect
			(at 0.96 0.46 180)
			(size 0.675 0.475)
			(layers "F.Cu" "F.Mask" "F.Paste")
			(roundrect_rratio 0.25)
			(net 151 "/2xUSB3.0+RJ45/DB-")
			(pinfunction "3")
			(pintype "passive")
			(teardrops
				(best_length_ratio 0.2)
				(max_length 1)
				(best_width_ratio 0.9)
				(max_width 2)
				(curved_edges yes)
				(filter_ratio 0.9)
				(enabled yes)
				(allow_two_segments yes)
				(prefer_zone_connections yes)
			)
		)
		(pad "4" smd roundrect
			(at -0.96 0.46 180)
			(size 0.675 0.475)
			(layers "F.Cu" "F.Mask" "F.Paste")
			(roundrect_rratio 0.25)
			(net 692 "/2xUSB3.0+RJ45/DB_FL-")
			(pinfunction "4")
			(pintype "passive")
			(teardrops
				(best_length_ratio 0.2)
				(max_length 1)
				(best_width_ratio 0.9)
				(max_width 2)
				(curved_edges yes)
				(filter_ratio 0.9)
				(enabled yes)
				(allow_two_segments yes)
				(prefer_zone_connections yes)
			)
		)
	)
	(footprint "antmicro-footprints:R_0402_1005Metric"
		(layer "F.Cu")
		(at 177.52 108.66 180)
		(descr "Resistor SMD 0402")
		(tags "resistor SMD 0402")
		(property "Reference" "R124"
			(at 0.82 -0.5 0)
			(layer "F.SilkS")
			(effects
				(font
					(size 0.7 0.7)
					(thickness 0.15)
				)
				(justify right bottom)
			)
		)
		(property "Value" "R_0R_0402"
			(at -1.011843 1.772047 0)
			(layer "F.Fab")
			(effects
				(font
					(size 0.7 0.7)
					(thickness 0.15)
				)
				(justify right bottom)
			)
		)
		(property "Datasheet" "https://industrial.panasonic.com/cdbs/www-data/pdf/RDA0000/AOA0000C301.pdf"
			(at 0 0 180)
			(layer "F.Fab")
			(hide yes)
			(effects
				(font
					(size 1.27 1.27)
					(thickness 0.15)
				)
			)
		)
		(property "Author" "Antmicro"
			(at 355.04 217.32 0)
			(layer "F.Fab")
			(hide yes)
			(effects
				(font
					(size 1 1)
					(thickness 0.15)
				)
			)
		)
		(property "Current" "1A"
			(at 355.04 217.32 0)
			(layer "F.Fab")
			(hide yes)
			(effects
				(font
					(size 1 1)
					(thickness 0.15)
				)
			)
		)
		(property "License" "Apache-2.0"
			(at 355.04 217.32 0)
			(layer "F.Fab")
			(hide yes)
			(effects
				(font
					(size 1 1)
					(thickness 0.15)
				)
			)
		)
		(property "MPN" "ERJ2GE0R00X"
			(at 355.04 217.32 0)
			(layer "F.Fab")
			(hide yes)
			(effects
				(font
					(size 1 1)
					(thickness 0.15)
				)
			)
		)
		(property "Manufacturer" "Panasonic"
			(at 355.04 217.32 0)
			(layer "F.Fab")
			(hide yes)
			(effects
				(font
					(size 1 1)
					(thickness 0.15)
				)
			)
		)
		(property "Public" "False"
			(at 355.04 217.32 0)
			(layer "F.Fab")
			(hide yes)
			(effects
				(font
					(size 1 1)
					(thickness 0.15)
				)
			)
		)
		(property "Tolerance" ""
			(at 355.04 217.32 0)
			(layer "F.Fab")
			(hide yes)
			(effects
				(font
					(size 1 1)
					(thickness 0.15)
				)
			)
		)
		(property "Val" "0R"
			(at 355.04 217.32 0)
			(layer "F.Fab")
			(hide yes)
			(effects
				(font
					(size 1 1)
					(thickness 0.15)
				)
			)
		)
		(sheetname "M.2 key M #1")
		(sheetfile "m2keym_low.kicad_sch")
		(attr smd)
		(fp_rect
			(start -0.925 -0.47)
			(end 0.925 0.47)
			(stroke
				(width 0.05)
				(type default)
			)
			(fill no)
			(layer "F.CrtYd")
		)
		(fp_rect
			(start -0.5 -0.25)
			(end 0.5 0.25)
			(stroke
				(width 0.15)
				(type solid)
			)
			(fill no)
			(layer "F.Fab")
		)
		(pad "1" smd roundrect
			(at -0.48 0 180)
			(size 0.59 0.64)
			(layers "F.Cu" "F.Mask" "F.Paste")
			(roundrect_rratio 0.25)
			(net 926 "Net-(J5-SUSCLK)")
			(pintype "passive")
			(teardrops
				(best_length_ratio 0.2)
				(max_length 1)
				(best_width_ratio 0.9)
				(max_width 2)
				(curved_edges yes)
				(filter_ratio 0.9)
				(enabled yes)
				(allow_two_segments yes)
				(prefer_zone_connections yes)
			)
		)
		(pad "2" smd roundrect
			(at 0.48 0 180)
			(size 0.59 0.64)
			(layers "F.Cu" "F.Mask" "F.Paste")
			(roundrect_rratio 0.25)
			(net 587 "/M.2 key E/SUSCLK")
			(pintype "passive")
			(teardrops
				(best_length_ratio 0.2)
				(max_length 1)
				(best_width_ratio 0.9)
				(max_width 2)
				(curved_edges yes)
				(filter_ratio 0.9)
				(enabled yes)
				(allow_two_segments yes)
				(prefer_zone_connections yes)
			)
		)
	)
	(footprint "antmicro-footprints:C_Pol_EIA-B"
		(layer "F.Cu")
		(at 308.825 100.64)
		(property "Reference" "C52"
			(at 2.275 0.47 0)
			(layer "F.SilkS")
			(effects
				(font
					(size 0.7 0.7)
					(thickness 0.15)
				)
				(justify left bottom)
			)
		)
		(property "Value" "C_Pol_100u_10V_KEMET-T520-B"
			(at 0 2.85 0)
			(layer "F.Fab")
			(effects
				(font
					(size 0.7 0.7)
					(thickness 0.15)
				)
				(justify left bottom)
			)
		)
		(property "Datasheet" "https://www.kemet.com/en/us/capacitors/product/T520B107M010ATE070.html"
			(at 0 0 0)
			(layer "F.Fab")
			(hide yes)
			(effects
				(font
					(size 1.27 1.27)
					(thickness 0.15)
				)
			)
		)
		(property "Author" "Antmicro"
			(at 0 0 0)
			(layer "F.Fab")
			(hide yes)
			(effects
				(font
					(size 1 1)
					(thickness 0.15)
				)
			)
		)
		(property "Dielectric" "template_dielectric"
			(at 0 0 0)
			(layer "F.Fab")
			(hide yes)
			(effects
				(font
					(size 1 1)
					(thickness 0.15)
				)
			)
		)
		(property "License" "Apache-2.0"
			(at 0 0 0)
			(layer "F.Fab")
			(hide yes)
			(effects
				(font
					(size 1 1)
					(thickness 0.15)
				)
			)
		)
		(property "MPN" "T520B107M010ATE070"
			(at 0 0 0)
			(layer "F.Fab")
			(hide yes)
			(effects
				(font
					(size 1 1)
					(thickness 0.15)
				)
			)
		)
		(property "Manufacturer" "KEMET"
			(at 0 0 0)
			(layer "F.Fab")
			(hide yes)
			(effects
				(font
					(size 1 1)
					(thickness 0.15)
				)
			)
		)
		(property "Public" "False"
			(at 0 0 0)
			(layer "F.Fab")
			(hide yes)
			(effects
				(font
					(size 1 1)
					(thickness 0.15)
				)
			)
		)
		(property "Val" "100u"
			(at 0 0 0)
			(layer "F.Fab")
			(hide yes)
			(effects
				(font
					(size 1 1)
					(thickness 0.15)
				)
			)
		)
		(property "Voltage" "10V"
			(at 0 0 0)
			(layer "F.Fab")
			(hide yes)
			(effects
				(font
					(size 1 1)
					(thickness 0.15)
				)
			)
		)
		(sheetname "Power")
		(sheetfile "power.kicad_sch")
		(attr smd)
		(fp_line
			(start -2.521 -1.676)
			(end -2.123 -1.676)
			(stroke
				(width 0.15)
				(type solid)
			)
			(layer "F.SilkS")
		)
		(fp_line
			(start -2.325 -1.475)
			(end -2.325 -1.878)
			(stroke
				(width 0.15)
				(type solid)
			)
			(layer "F.SilkS")
		)
		(fp_line
			(start -1.8 -1.6)
			(end 1.8 -1.6)
			(stroke
				(width 0.15)
				(type solid)
			)
			(layer "F.SilkS")
		)
		(fp_line
			(start -1.8 -1.3)
			(end -1.8 -1.6)
			(stroke
				(width 0.15)
				(type solid)
			)
			(layer "F.SilkS")
		)
		(fp_line
			(start -1.8 1.3)
			(end -1.8 1.6)
			(stroke
				(width 0.15)
				(type solid)
			)
			(layer "F.SilkS")
		)
		(fp_line
			(start 1.8 -1.3)
			(end 1.8 -1.6)
			(stroke
				(width 0.15)
				(type solid)
			)
			(layer "F.SilkS")
		)
		(fp_line
			(start 1.8 1.3)
			(end 1.8 1.6)
			(stroke
				(width 0.15)
				(type solid)
			)
			(layer "F.SilkS")
		)
		(fp_line
			(start 1.8 1.6)
			(end -1.8 1.6)
			(stroke
				(width 0.15)
				(type solid)
			)
			(layer "F.SilkS")
		)
		(fp_line
			(start -2.411 -1.35)
			(end -2.41 1.35)
			(stroke
				(width 0.05)
				(type solid)
			)
			(layer "F.CrtYd")
		)
		(fp_line
			(start -1.97 -1.75)
			(end -1.97 -1.35)
			(stroke
				(width 0.05)
				(type solid)
			)
			(layer "F.CrtYd")
		)
		(fp_line
			(start -1.97 -1.35)
			(end -2.41 -1.35)
			(stroke
				(width 0.05)
				(type solid)
			)
			(layer "F.CrtYd")
		)
		(fp_line
			(start -1.97 1.35)
			(end -2.41 1.35)
			(stroke
				(width 0.05)
				(type solid)
			)
			(layer "F.CrtYd")
		)
		(fp_line
			(start -1.97 1.35)
			(end -1.97 1.75)
			(stroke
				(width 0.05)
				(type solid)
			)
			(layer "F.CrtYd")
		)
		(fp_line
			(start 1.959 -1.75)
			(end -1.97 -1.75)
			(stroke
				(width 0.05)
				(type solid)
			)
			(layer "F.CrtYd")
		)
		(fp_line
			(start 1.959 -1.75)
			(end 1.959 -1.35)
			(stroke
				(width 0.05)
				(type solid)
			)
			(layer "F.CrtYd")
		)
		(fp_line
			(start 1.96 1.35)
			(end 1.96 1.75)
			(stroke
				(width 0.05)
				(type solid)
			)
			(layer "F.CrtYd")
		)
		(fp_line
			(start 1.96 1.75)
			(end -1.97 1.75)
			(stroke
				(width 0.05)
				(type solid)
			)
			(layer "F.CrtYd")
		)
		(fp_line
			(start 2.399 -1.35)
			(end 1.959 -1.35)
			(stroke
				(width 0.05)
				(type solid)
			)
			(layer "F.CrtYd")
		)
		(fp_line
			(start 2.399 -1.35)
			(end 2.4 1.35)
			(stroke
				(width 0.05)
				(type solid)
			)
			(layer "F.CrtYd")
		)
		(fp_line
			(start 2.4 1.35)
			(end 1.96 1.35)
			(stroke
				(width 0.05)
				(type solid)
			)
			(layer "F.CrtYd")
		)
		(fp_line
			(start -1.7 1.324)
			(end -1.551 1.475)
			(stroke
				(width 0.15)
				(type solid)
			)
			(layer "F.Fab")
		)
		(fp_rect
			(start -1.72 -1.5)
			(end 1.719 1.499)
			(stroke
				(width 0.15)
				(type solid)
			)
			(fill no)
			(layer "F.Fab")
		)
		(pad "1" smd roundrect
			(at -1.551 0)
			(size 1.2 2.2)
			(layers "F.Cu" "F.Mask" "F.Paste")
			(roundrect_rratio 0.1)
			(net 71 "Net-(U49-IN+)")
			(pintype "passive")
			(teardrops
				(best_length_ratio 0.2)
				(max_length 1)
				(best_width_ratio 0.9)
				(max_width 2)
				(curved_edges yes)
				(filter_ratio 0.9)
				(enabled yes)
				(allow_two_segments yes)
				(prefer_zone_connections yes)
			)
		)
		(pad "2" smd roundrect
			(at 1.55 0)
			(size 1.2 2.2)
			(layers "F.Cu" "F.Mask" "F.Paste")
			(roundrect_rratio 0.1)
			(net 1 "GND")
			(pintype "passive")
			(teardrops
				(best_length_ratio 0.2)
				(max_length 1)
				(best_width_ratio 0.9)
				(max_width 2)
				(curved_edges yes)
				(filter_ratio 0.9)
				(enabled yes)
				(allow_two_segments yes)
				(prefer_zone_connections yes)
			)
		)
	)
	(footprint "antmicro-footprints:SC-74-6_1.5x2.9mm_P0.95mm"
		(layer "F.Cu")
		(at 242.620708 78.135)
		(tags "sc74 sc-74 sot23-6 sot457 tsop6 tsop-6")
		(property "Reference" "U26"
			(at -1 2.625 0)
			(layer "F.SilkS")
			(effects
				(font
					(size 0.7 0.7)
					(thickness 0.15)
				)
				(justify left bottom)
			)
		)
		(property "Value" "74LVC1G157-Q100H_SOT457"
			(at 0.001 2.7 0)
			(layer "F.Fab")
			(effects
				(font
					(size 0.7 0.7)
					(thickness 0.15)
				)
				(justify left bottom)
			)
		)
		(property "Datasheet" "https://www.mouser.com/datasheet/2/916/74LVC1G157_Q100-1578792.pdf"
			(at 0 0 0)
			(layer "F.Fab")
			(hide yes)
			(effects
				(font
					(size 1.27 1.27)
					(thickness 0.15)
				)
			)
		)
		(property "Author" "Antmicro"
			(at 0 0 0)
			(layer "F.Fab")
			(hide yes)
			(effects
				(font
					(size 1 1)
					(thickness 0.15)
				)
			)
		)
		(property "License" "Apache-2.0"
			(at 0 0 0)
			(layer "F.Fab")
			(hide yes)
			(effects
				(font
					(size 1 1)
					(thickness 0.15)
				)
			)
		)
		(property "MPN" "74LVC1G157-Q100H"
			(at 0 0 0)
			(layer "F.Fab")
			(hide yes)
			(effects
				(font
					(size 1 1)
					(thickness 0.15)
				)
			)
		)
		(property "Manufacturer" "Nexperia"
			(at 0 0 0)
			(layer "F.Fab")
			(hide yes)
			(effects
				(font
					(size 1 1)
					(thickness 0.15)
				)
			)
		)
		(sheetname "Misc")
		(sheetfile "misc.kicad_sch")
		(attr smd)
		(fp_circle
			(center -1.11 -1.454)
			(end -1.06 -1.454)
			(stroke
				(width 0.15)
				(type solid)
			)
			(fill yes)
			(layer "F.SilkS")
		)
		(fp_rect
			(start -1.7 -1.7)
			(end 1.7 1.7)
			(stroke
				(width 0.05)
				(type solid)
			)
			(fill no)
			(layer "F.CrtYd")
		)
		(fp_line
			(start -1.269 -0.915)
			(end -1.269 1.372)
			(stroke
				(width 0.15)
				(type solid)
			)
			(layer "F.Fab")
		)
		(fp_line
			(start -1.269 1.372)
			(end -1.167 1.372)
			(stroke
				(width 0.15)
				(type solid)
			)
			(layer "F.Fab")
		)
		(fp_line
			(start -1.167 1.372)
			(end 1.22 1.372)
			(stroke
				(width 0.15)
				(type solid)
			)
			(layer "F.Fab")
		)
		(fp_line
			(start -0.76 -1.422)
			(end -1.269 -0.915)
			(stroke
				(width 0.15)
				(type solid)
			)
			(layer "F.Fab")
		)
		(fp_line
			(start 1.22 -1.422)
			(end -0.76 -1.422)
			(stroke
				(width 0.15)
				(type solid)
			)
			(layer "F.Fab")
		)
		(fp_line
			(start 1.22 1.372)
			(end 1.22 -1.422)
			(stroke
				(width 0.15)
				(type solid)
			)
			(layer "F.Fab")
		)
		(pad "1" smd roundrect
			(at -1.2 -0.95)
			(size 0.8 0.55)
			(layers "F.Cu" "F.Mask" "F.Paste")
			(roundrect_rratio 0.15)
			(net 400 "/Com Express 7 MGMT/FAN_PWM")
			(pinfunction "I1")
			(pintype "input")
			(teardrops
				(best_length_ratio 0.2)
				(max_length 1)
				(best_width_ratio 0.9)
				(max_width 2)
				(curved_edges yes)
				(filter_ratio 0.9)
				(enabled yes)
				(allow_two_segments yes)
				(prefer_zone_connections yes)
			)
		)
		(pad "2" smd roundrect
			(at -1.2 0)
			(size 0.8 0.55)
			(layers "F.Cu" "F.Mask" "F.Paste")
			(roundrect_rratio 0.15)
			(net 1 "GND")
			(pinfunction "GND")
			(pintype "power_in")
			(teardrops
				(best_length_ratio 0.2)
				(max_length 1)
				(best_width_ratio 0.9)
				(max_width 2)
				(curved_edges yes)
				(filter_ratio 0.9)
				(enabled yes)
				(allow_two_segments yes)
				(prefer_zone_connections yes)
			)
		)
		(pad "3" smd roundrect
			(at -1.2 0.95)
			(size 0.8 0.55)
			(layers "F.Cu" "F.Mask" "F.Paste")
			(roundrect_rratio 0.15)
			(net 596 "/Misc/PWM2")
			(pinfunction "I0")
			(pintype "input")
			(teardrops
				(best_length_ratio 0.2)
				(max_length 1)
				(best_width_ratio 0.9)
				(max_width 2)
				(curved_edges yes)
				(filter_ratio 0.9)
				(enabled yes)
				(allow_two_segments yes)
				(prefer_zone_connections yes)
			)
		)
		(pad "4" smd roundrect
			(at 1.2 0.95)
			(size 0.8 0.55)
			(layers "F.Cu" "F.Mask" "F.Paste")
			(roundrect_rratio 0.15)
			(net 783 "/Misc/PWM_{B3V3}")
			(pinfunction "Y")
			(pintype "output")
			(teardrops
				(best_length_ratio 0.2)
				(max_length 1)
				(best_width_ratio 0.9)
				(max_width 2)
				(curved_edges yes)
				(filter_ratio 0.9)
				(enabled yes)
				(allow_two_segments yes)
				(prefer_zone_connections yes)
			)
		)
		(pad "5" smd roundrect
			(at 1.2 0)
			(size 0.8 0.55)
			(layers "F.Cu" "F.Mask" "F.Paste")
			(roundrect_rratio 0.15)
			(net 2 "+3V3")
			(pinfunction "VCC")
			(pintype "power_in")
			(teardrops
				(best_length_ratio 0.2)
				(max_length 1)
				(best_width_ratio 0.9)
				(max_width 2)
				(curved_edges yes)
				(filter_ratio 0.9)
				(enabled yes)
				(allow_two_segments yes)
				(prefer_zone_connections yes)
			)
		)
		(pad "6" smd roundrect
			(at 1.2 -0.95)
			(size 0.8 0.55)
			(layers "F.Cu" "F.Mask" "F.Paste")
			(roundrect_rratio 0.15)
			(net 595 "/Misc/PWM_{SRCSEL}")
			(pinfunction "S")
			(pintype "input")
			(teardrops
				(best_length_ratio 0.2)
				(max_length 1)
				(best_width_ratio 0.9)
				(max_width 2)
				(curved_edges yes)
				(filter_ratio 0.9)
				(enabled yes)
				(allow_two_segments yes)
				(prefer_zone_connections yes)
			)
		)
	)
	(footprint "antmicro-footprints:R_0402_1005Metric"
		(layer "F.Cu")
		(at 129.15 89.510001 -90)
		(descr "Resistor SMD 0402")
		(tags "resistor SMD 0402")
		(property "Reference" "R244"
			(at 0.799999 -0.4 90)
			(layer "F.SilkS")
			(effects
				(font
					(size 0.7 0.7)
					(thickness 0.15)
				)
				(justify right bottom)
			)
		)
		(property "Value" "R_0R_0402"
			(at -1.011843 1.772047 90)
			(layer "F.Fab")
			(effects
				(font
					(size 0.7 0.7)
					(thickness 0.15)
				)
				(justify right bottom)
			)
		)
		(property "Datasheet" "https://industrial.panasonic.com/cdbs/www-data/pdf/RDA0000/AOA0000C301.pdf"
			(at 0 0 270)
			(layer "F.Fab")
			(hide yes)
			(effects
				(font
					(size 1.27 1.27)
					(thickness 0.15)
				)
			)
		)
		(property "Author" "Antmicro"
			(at 39.639999 218.660001 0)
			(layer "F.Fab")
			(hide yes)
			(effects
				(font
					(size 1 1)
					(thickness 0.15)
				)
			)
		)
		(property "Current" "1A"
			(at 39.639999 218.660001 0)
			(layer "F.Fab")
			(hide yes)
			(effects
				(font
					(size 1 1)
					(thickness 0.15)
				)
			)
		)
		(property "License" "Apache-2.0"
			(at 39.639999 218.660001 0)
			(layer "F.Fab")
			(hide yes)
			(effects
				(font
					(size 1 1)
					(thickness 0.15)
				)
			)
		)
		(property "MPN" "ERJ2GE0R00X"
			(at 39.639999 218.660001 0)
			(layer "F.Fab")
			(hide yes)
			(effects
				(font
					(size 1 1)
					(thickness 0.15)
				)
			)
		)
		(property "Manufacturer" "Panasonic"
			(at 39.639999 218.660001 0)
			(layer "F.Fab")
			(hide yes)
			(effects
				(font
					(size 1 1)
					(thickness 0.15)
				)
			)
		)
		(property "Public" "False"
			(at 39.639999 218.660001 0)
			(layer "F.Fab")
			(hide yes)
			(effects
				(font
					(size 1 1)
					(thickness 0.15)
				)
			)
		)
		(property "Tolerance" ""
			(at 39.639999 218.660001 0)
			(layer "F.Fab")
			(hide yes)
			(effects
				(font
					(size 1 1)
					(thickness 0.15)
				)
			)
		)
		(property "Val" "0R"
			(at 39.639999 218.660001 0)
			(layer "F.Fab")
			(hide yes)
			(effects
				(font
					(size 1 1)
					(thickness 0.15)
				)
			)
		)
		(sheetname "GPIO expander")
		(sheetfile "gpio_exp.kicad_sch")
		(attr smd)
		(fp_rect
			(start -0.925 -0.47)
			(end 0.925 0.47)
			(stroke
				(width 0.05)
				(type default)
			)
			(fill no)
			(layer "F.CrtYd")
		)
		(fp_rect
			(start -0.5 -0.25)
			(end 0.5 0.25)
			(stroke
				(width 0.15)
				(type solid)
			)
			(fill no)
			(layer "F.Fab")
		)
		(pad "1" smd roundrect
			(at -0.48 0 270)
			(size 0.59 0.64)
			(layers "F.Cu" "F.Mask" "F.Paste")
			(roundrect_rratio 0.25)
			(net 645 "Net-(U41-IO0_6)")
			(pintype "passive")
			(teardrops
				(best_length_ratio 0.2)
				(max_length 1)
				(best_width_ratio 0.9)
				(max_width 2)
				(curved_edges yes)
				(filter_ratio 0.9)
				(enabled yes)
				(allow_two_segments yes)
				(prefer_zone_connections yes)
			)
		)
		(pad "2" smd roundrect
			(at 0.48 0 270)
			(size 0.59 0.64)
			(layers "F.Cu" "F.Mask" "F.Paste")
			(roundrect_rratio 0.25)
			(net 527 "/Backplane/GPIO")
			(pintype "passive")
			(teardrops
				(best_length_ratio 0.2)
				(max_length 1)
				(best_width_ratio 0.9)
				(max_width 2)
				(curved_edges yes)
				(filter_ratio 0.9)
				(enabled yes)
				(allow_two_segments yes)
				(prefer_zone_connections yes)
			)
		)
	)
	(footprint "antmicro-footprints:C_0402_1005Metric"
		(layer "F.Cu")
		(at 114.35 86.41 90)
		(descr "Capacitor SMD 0402")
		(tags "capacitor SMD 0402")
		(property "Reference" "C8"
			(at 0.8 0.45 90)
			(layer "F.SilkS")
			(effects
				(font
					(size 0.7 0.7)
					(thickness 0.15)
				)
				(justify left bottom)
			)
		)
		(property "Value" "C_1u_0402"
			(at -1.022927 2.155213 90)
			(layer "F.Fab")
			(effects
				(font
					(size 0.7 0.7)
					(thickness 0.15)
				)
				(justify left bottom)
			)
		)
		(property "Datasheet" "https://product.tdk.com/en/search/capacitor/ceramic/mlcc/info?part_no=C1005X6S1A105K050BC"
			(at 0 0 90)
			(layer "F.Fab")
			(hide yes)
			(effects
				(font
					(size 1.27 1.27)
					(thickness 0.15)
				)
			)
		)
		(property "Author" "Antmicro"
			(at 200.76 -27.94 0)
			(layer "F.Fab")
			(hide yes)
			(effects
				(font
					(size 1 1)
					(thickness 0.15)
				)
			)
		)
		(property "Dielectric" ""
			(at 200.76 -27.94 0)
			(layer "F.Fab")
			(hide yes)
			(effects
				(font
					(size 1 1)
					(thickness 0.15)
				)
			)
		)
		(property "License" "Apache-2.0"
			(at 200.76 -27.94 0)
			(layer "F.Fab")
			(hide yes)
			(effects
				(font
					(size 1 1)
					(thickness 0.15)
				)
			)
		)
		(property "MPN" "C1005X6S1A105K050BC"
			(at 200.76 -27.94 0)
			(layer "F.Fab")
			(hide yes)
			(effects
				(font
					(size 1 1)
					(thickness 0.15)
				)
			)
		)
		(property "Manufacturer" "TDK"
			(at 200.76 -27.94 0)
			(layer "F.Fab")
			(hide yes)
			(effects
				(font
					(size 1 1)
					(thickness 0.15)
				)
			)
		)
		(property "Public" "False"
			(at 200.76 -27.94 0)
			(layer "F.Fab")
			(hide yes)
			(effects
				(font
					(size 1 1)
					(thickness 0.15)
				)
			)
		)
		(property "Val" "1u"
			(at 200.76 -27.94 0)
			(layer "F.Fab")
			(hide yes)
			(effects
				(font
					(size 1 1)
					(thickness 0.15)
				)
			)
		)
		(property "Voltage" ""
			(at 200.76 -27.94 0)
			(layer "F.Fab")
			(hide yes)
			(effects
				(font
					(size 1 1)
					(thickness 0.15)
				)
			)
		)
		(sheetname "2xUSB3.0+RJ45")
		(sheetfile "usb3+rj45.kicad_sch")
		(attr smd)
		(fp_rect
			(start -0.925 -0.47)
			(end 0.925 0.47)
			(stroke
				(width 0.05)
				(type default)
			)
			(fill no)
			(layer "F.CrtYd")
		)
		(fp_line
			(start 0.504 -0.25)
			(end 0.504 0.248)
			(stroke
				(width 0.15)
				(type solid)
			)
			(layer "F.Fab")
		)
		(fp_line
			(start -0.494 -0.25)
			(end 0.504 -0.25)
			(stroke
				(width 0.15)
				(type solid)
			)
			(layer "F.Fab")
		)
		(fp_line
			(start 0.504 0.248)
			(end -0.494 0.248)
			(stroke
				(width 0.15)
				(type solid)
			)
			(layer "F.Fab")
		)
		(fp_line
			(start -0.494 0.248)
			(end -0.494 -0.25)
			(stroke
				(width 0.15)
				(type solid)
			)
			(layer "F.Fab")
		)
		(pad "1" smd roundrect
			(at -0.48 0 90)
			(size 0.59 0.64)
			(layers "F.Cu" "F.Mask" "F.Paste")
			(roundrect_rratio 0.25)
			(net 1 "GND")
			(pintype "passive")
			(teardrops
				(best_length_ratio 0.2)
				(max_length 1)
				(best_width_ratio 0.9)
				(max_width 2)
				(curved_edges yes)
				(filter_ratio 0.9)
				(enabled yes)
				(allow_two_segments yes)
				(prefer_zone_connections yes)
			)
		)
		(pad "2" smd roundrect
			(at 0.48 0 90)
			(size 0.59 0.64)
			(layers "F.Cu" "F.Mask" "F.Paste")
			(roundrect_rratio 0.25)
			(net 42 "/2xUSB3.0+RJ45/P1_VBUS")
			(pintype "passive")
			(teardrops
				(best_length_ratio 0.2)
				(max_length 1)
				(best_width_ratio 0.9)
				(max_width 2)
				(curved_edges yes)
				(filter_ratio 0.9)
				(enabled yes)
				(allow_two_segments yes)
				(prefer_zone_connections yes)
			)
		)
	)
	(footprint "antmicro-footprints:R_0402_1005Metric"
		(layer "F.Cu")
		(at 219.73 122.9)
		(descr "Resistor SMD 0402")
		(tags "resistor SMD 0402")
		(property "Reference" "R188"
			(at 0.77 0.46 0)
			(layer "F.SilkS")
			(effects
				(font
					(size 0.7 0.7)
					(thickness 0.15)
				)
				(justify left bottom)
			)
		)
		(property "Value" "R_1k_0402"
			(at -1.011843 1.772047 0)
			(layer "F.Fab")
			(effects
				(font
					(size 0.7 0.7)
					(thickness 0.15)
				)
				(justify left bottom)
			)
		)
		(property "Datasheet" "https://www.bourns.com/docs/product-datasheets/cr.pdf"
			(at 0 0 0)
			(layer "F.Fab")
			(hide yes)
			(effects
				(font
					(size 1.27 1.27)
					(thickness 0.15)
				)
			)
		)
		(property "Author" "Antmicro"
			(at 0 0 0)
			(layer "F.Fab")
			(hide yes)
			(effects
				(font
					(size 1 1)
					(thickness 0.15)
				)
			)
		)
		(property "License" "Apache-2.0"
			(at 0 0 0)
			(layer "F.Fab")
			(hide yes)
			(effects
				(font
					(size 1 1)
					(thickness 0.15)
				)
			)
		)
		(property "MPN" "CR0402-FX-1001GLF"
			(at 0 0 0)
			(layer "F.Fab")
			(hide yes)
			(effects
				(font
					(size 1 1)
					(thickness 0.15)
				)
			)
		)
		(property "Manufacturer" "Bourns"
			(at 0 0 0)
			(layer "F.Fab")
			(hide yes)
			(effects
				(font
					(size 1 1)
					(thickness 0.15)
				)
			)
		)
		(property "Public" "False"
			(at 0 0 0)
			(layer "F.Fab")
			(hide yes)
			(effects
				(font
					(size 1 1)
					(thickness 0.15)
				)
			)
		)
		(property "Tolerance" "1%"
			(at 0 0 0)
			(layer "F.Fab")
			(hide yes)
			(effects
				(font
					(size 1 1)
					(thickness 0.15)
				)
			)
		)
		(property "Val" "1k"
			(at 0 0 0)
			(layer "F.Fab")
			(hide yes)
			(effects
				(font
					(size 1 1)
					(thickness 0.15)
				)
			)
		)
		(sheetname "PCIe misc")
		(sheetfile "pcie_misc.kicad_sch")
		(attr smd dnp)
		(fp_rect
			(start -0.925 -0.47)
			(end 0.925 0.47)
			(stroke
				(width 0.05)
				(type default)
			)
			(fill no)
			(layer "F.CrtYd")
		)
		(fp_rect
			(start -0.5 -0.25)
			(end 0.5 0.25)
			(stroke
				(width 0.15)
				(type solid)
			)
			(fill no)
			(layer "F.Fab")
		)
		(pad "1" smd roundrect
			(at -0.48 0)
			(size 0.59 0.64)
			(layers "F.Cu" "F.Mask" "F.Paste")
			(roundrect_rratio 0.25)
			(net 607 "Net-(U37-~{HIBW_BYPM_LOBW})")
			(pintype "passive")
			(teardrops
				(best_length_ratio 0.2)
				(max_length 1)
				(best_width_ratio 0.9)
				(max_width 2)
				(curved_edges yes)
				(filter_ratio 0.9)
				(enabled yes)
				(allow_two_segments yes)
				(prefer_zone_connections yes)
			)
		)
		(pad "2" smd roundrect
			(at 0.48 0)
			(size 0.59 0.64)
			(layers "F.Cu" "F.Mask" "F.Paste")
			(roundrect_rratio 0.25)
			(net 1 "GND")
			(pintype "passive")
			(teardrops
				(best_length_ratio 0.2)
				(max_length 1)
				(best_width_ratio 0.9)
				(max_width 2)
				(curved_edges yes)
				(filter_ratio 0.9)
				(enabled yes)
				(allow_two_segments yes)
				(prefer_zone_connections yes)
			)
		)
	)
	(footprint "antmicro-footprints:R_0402_1005Metric"
		(layer "F.Cu")
		(at 246.8 132.36 -90)
		(descr "Resistor SMD 0402")
		(tags "resistor SMD 0402")
		(property "Reference" "R175"
			(at 0.85 -0.45 90)
			(layer "F.SilkS")
			(effects
				(font
					(size 0.7 0.7)
					(thickness 0.15)
				)
				(justify right bottom)
			)
		)
		(property "Value" "R_10k_0402"
			(at -1.011843 1.772047 90)
			(layer "F.Fab")
			(effects
				(font
					(size 0.7 0.7)
					(thickness 0.15)
				)
				(justify right bottom)
			)
		)
		(property "Datasheet" "https://www.bourns.com/docs/product-datasheets/cr.pdf"
			(at 0 0 270)
			(layer "F.Fab")
			(hide yes)
			(effects
				(font
					(size 1.27 1.27)
					(thickness 0.15)
				)
			)
		)
		(property "Author" "Antmicro"
			(at 114.44 379.16 0)
			(layer "F.Fab")
			(hide yes)
			(effects
				(font
					(size 1 1)
					(thickness 0.15)
				)
			)
		)
		(property "License" "Apache-2.0"
			(at 114.44 379.16 0)
			(layer "F.Fab")
			(hide yes)
			(effects
				(font
					(size 1 1)
					(thickness 0.15)
				)
			)
		)
		(property "MPN" "CR0402-FX-1002GLF"
			(at 114.44 379.16 0)
			(layer "F.Fab")
			(hide yes)
			(effects
				(font
					(size 1 1)
					(thickness 0.15)
				)
			)
		)
		(property "Manufacturer" "Bourns"
			(at 114.44 379.16 0)
			(layer "F.Fab")
			(hide yes)
			(effects
				(font
					(size 1 1)
					(thickness 0.15)
				)
			)
		)
		(property "Public" "False"
			(at 114.44 379.16 0)
			(layer "F.Fab")
			(hide yes)
			(effects
				(font
					(size 1 1)
					(thickness 0.15)
				)
			)
		)
		(property "Tolerance" "1%"
			(at 114.44 379.16 0)
			(layer "F.Fab")
			(hide yes)
			(effects
				(font
					(size 1 1)
					(thickness 0.15)
				)
			)
		)
		(property "Val" "10k"
			(at 114.44 379.16 0)
			(layer "F.Fab")
			(hide yes)
			(effects
				(font
					(size 1 1)
					(thickness 0.15)
				)
			)
		)
		(sheetname "Com Express 7 MGMT")
		(sheetfile "com_express_7_mgmt.kicad_sch")
		(attr smd dnp)
		(fp_rect
			(start -0.925 -0.47)
			(end 0.925 0.47)
			(stroke
				(width 0.05)
				(type default)
			)
			(fill no)
			(layer "F.CrtYd")
		)
		(fp_rect
			(start -0.5 -0.25)
			(end 0.5 0.25)
			(stroke
				(width 0.15)
				(type solid)
			)
			(fill no)
			(layer "F.Fab")
		)
		(pad "1" smd roundrect
			(at -0.48 0 270)
			(size 0.59 0.64)
			(layers "F.Cu" "F.Mask" "F.Paste")
			(roundrect_rratio 0.25)
			(net 872 "Net-(U34-~{KILL})")
			(pintype "passive")
			(teardrops
				(best_length_ratio 0.2)
				(max_length 1)
				(best_width_ratio 0.9)
				(max_width 2)
				(curved_edges yes)
				(filter_ratio 0.9)
				(enabled yes)
				(allow_two_segments yes)
				(prefer_zone_connections yes)
			)
		)
		(pad "2" smd roundrect
			(at 0.48 0 270)
			(size 0.59 0.64)
			(layers "F.Cu" "F.Mask" "F.Paste")
			(roundrect_rratio 0.25)
			(net 73 "+3V3_AON")
			(pintype "passive")
			(teardrops
				(best_length_ratio 0.2)
				(max_length 1)
				(best_width_ratio 0.9)
				(max_width 2)
				(curved_edges yes)
				(filter_ratio 0.9)
				(enabled yes)
				(allow_two_segments yes)
				(prefer_zone_connections yes)
			)
		)
	)
	(footprint "antmicro-footprints:C_0201"
		(layer "F.Cu")
		(at 138.172 147.31 90)
		(descr "Capacitor SMD 0201")
		(tags "capacitor SMD 0201")
		(property "Reference" "C181"
			(at -4.1 0.578 90)
			(layer "F.SilkS")
			(effects
				(font
					(size 0.7 0.7)
					(thickness 0.15)
				)
				(justify left bottom)
			)
		)
		(property "Value" "C_100n_0201_25V"
			(at 0 1.4 90)
			(layer "F.Fab")
			(effects
				(font
					(size 0.7 0.7)
					(thickness 0.15)
				)
				(justify left bottom)
			)
		)
		(property "Datasheet" "https://product.tdk.com/en/search/capacitor/ceramic/mlcc/info?part_no=C0603X5R1E104K030BB"
			(at 0 0 90)
			(layer "F.Fab")
			(hide yes)
			(effects
				(font
					(size 1.27 1.27)
					(thickness 0.15)
				)
			)
		)
		(property "Author" "Antmicro"
			(at 285.482 9.138 0)
			(layer "F.Fab")
			(hide yes)
			(effects
				(font
					(size 1 1)
					(thickness 0.15)
				)
			)
		)
		(property "Dielectric" ""
			(at 285.482 9.138 0)
			(layer "F.Fab")
			(hide yes)
			(effects
				(font
					(size 1 1)
					(thickness 0.15)
				)
			)
		)
		(property "License" "Apache-2.0"
			(at 285.482 9.138 0)
			(layer "F.Fab")
			(hide yes)
			(effects
				(font
					(size 1 1)
					(thickness 0.15)
				)
			)
		)
		(property "MPN" "C0603X5R1E104K030BB"
			(at 285.482 9.138 0)
			(layer "F.Fab")
			(hide yes)
			(effects
				(font
					(size 1 1)
					(thickness 0.15)
				)
			)
		)
		(property "Manufacturer" "TDK"
			(at 285.482 9.138 0)
			(layer "F.Fab")
			(hide yes)
			(effects
				(font
					(size 1 1)
					(thickness 0.15)
				)
			)
		)
		(property "Public" "False"
			(at 285.482 9.138 0)
			(layer "F.Fab")
			(hide yes)
			(effects
				(font
					(size 1 1)
					(thickness 0.15)
				)
			)
		)
		(property "Val" "100n"
			(at 285.482 9.138 0)
			(layer "F.Fab")
			(hide yes)
			(effects
				(font
					(size 1 1)
					(thickness 0.15)
				)
			)
		)
		(property "Voltage" "25V"
			(at 285.482 9.138 0)
			(layer "F.Fab")
			(hide yes)
			(effects
				(font
					(size 1 1)
					(thickness 0.15)
				)
			)
		)
		(sheetname "KR to SFI #2")
		(sheetfile "kr_sfi.kicad_sch")
		(attr smd)
		(fp_rect
			(start -0.7 -0.35)
			(end 0.7 0.35)
			(stroke
				(width 0.05)
				(type default)
			)
			(fill no)
			(layer "F.CrtYd")
		)
		(fp_rect
			(start 0.3 0.15)
			(end -0.301 -0.149)
			(stroke
				(width 0.15)
				(type solid)
			)
			(fill no)
			(layer "F.Fab")
		)
		(pad "" smd roundrect
			(at -0.349 -0.002 90)
			(size 0.318 0.36)
			(layers "F.Paste")
			(roundrect_rratio 0.25)
			(teardrops
				(best_length_ratio 0.2)
				(max_length 1)
				(best_width_ratio 0.9)
				(max_width 2)
				(curved_edges yes)
				(filter_ratio 0.9)
				(enabled yes)
				(allow_two_segments yes)
				(prefer_zone_connections yes)
			)
		)
		(pad "" smd roundrect
			(at 0.341 -0.002 90)
			(size 0.318 0.36)
			(layers "F.Paste")
			(roundrect_rratio 0.25)
			(teardrops
				(best_length_ratio 0.2)
				(max_length 1)
				(best_width_ratio 0.9)
				(max_width 2)
				(curved_edges yes)
				(filter_ratio 0.9)
				(enabled yes)
				(allow_two_segments yes)
				(prefer_zone_connections yes)
			)
		)
		(pad "1" smd roundrect
			(at -0.321 -0.002 90)
			(size 0.46 0.4)
			(layers "F.Cu" "F.Mask")
			(roundrect_rratio 0.25)
			(net 121 "/2xSFP+/10GKR_SFP1.TX-")
			(pintype "passive")
			(teardrops
				(best_length_ratio 0.2)
				(max_length 1)
				(best_width_ratio 0.9)
				(max_width 2)
				(curved_edges yes)
				(filter_ratio 0.9)
				(enabled yes)
				(allow_two_segments yes)
				(prefer_zone_connections yes)
			)
		)
		(pad "2" smd roundrect
			(at 0.32 -0.002 90)
			(size 0.46 0.4)
			(layers "F.Cu" "F.Mask")
			(roundrect_rratio 0.25)
			(net 122 "/2xSFP+/KR to SFI #2/KR_C.TX-")
			(pintype "passive")
			(teardrops
				(best_length_ratio 0.2)
				(max_length 1)
				(best_width_ratio 0.9)
				(max_width 2)
				(curved_edges yes)
				(filter_ratio 0.9)
				(enabled yes)
				(allow_two_segments yes)
				(prefer_zone_connections yes)
			)
		)
	)
	(footprint "antmicro-footprints:PLCC4_3.2x2.8mm"
		(layer "F.Cu")
		(at 102.44 77.555 90)
		(property "Reference" "D17"
			(at -0.905 -2.94 90)
			(unlocked yes)
			(layer "F.SilkS")
			(effects
				(font
					(size 0.7 0.7)
					(thickness 0.15)
				)
				(justify left bottom)
			)
		)
		(property "Value" "LED_RGB_PLCC4_ASMB_MTB1_0A3A2"
			(at 0 2.7 90)
			(unlocked yes)
			(layer "F.Fab")
			(effects
				(font
					(size 0.7 0.7)
					(thickness 0.15)
				)
				(justify left bottom)
			)
		)
		(property "Datasheet" "https://docs.broadcom.com/doc/AV02-4194EN"
			(at 0 0 90)
			(layer "F.Fab")
			(hide yes)
			(effects
				(font
					(size 1.27 1.27)
					(thickness 0.15)
				)
			)
		)
		(property "Author" "Antmicro"
			(at 179.995 -24.885 0)
			(layer "F.Fab")
			(hide yes)
			(effects
				(font
					(size 1 1)
					(thickness 0.15)
				)
			)
		)
		(property "Color" "R, G, B"
			(at 179.995 -24.885 0)
			(layer "F.Fab")
			(hide yes)
			(effects
				(font
					(size 1 1)
					(thickness 0.15)
				)
			)
		)
		(property "License" "Apache-2.0"
			(at 179.995 -24.885 0)
			(layer "F.Fab")
			(hide yes)
			(effects
				(font
					(size 1 1)
					(thickness 0.15)
				)
			)
		)
		(property "MPN" "ASMB-MTB1-0A3A2"
			(at 179.995 -24.885 0)
			(layer "F.Fab")
			(hide yes)
			(effects
				(font
					(size 1 1)
					(thickness 0.15)
				)
			)
		)
		(property "Manufacturer" "Avago Technologies"
			(at 179.995 -24.885 0)
			(layer "F.Fab")
			(hide yes)
			(effects
				(font
					(size 1 1)
					(thickness 0.15)
				)
			)
		)
		(sheetname "Misc")
		(sheetfile "misc.kicad_sch")
		(attr smd)
		(fp_line
			(start -1.75 -1.491)
			(end 1.947 -1.491)
			(stroke
				(width 0.15)
				(type solid)
			)
			(layer "F.SilkS")
		)
		(fp_line
			(start -1.953 1.509)
			(end 1.947 1.509)
			(stroke
				(width 0.15)
				(type solid)
			)
			(layer "F.SilkS")
		)
		(fp_circle
			(center -2 -1.45)
			(end -1.95 -1.45)
			(stroke
				(width 0.15)
				(type solid)
			)
			(fill yes)
			(layer "F.SilkS")
		)
		(fp_rect
			(start -2.25 -1.65)
			(end 2.24 1.65)
			(stroke
				(width 0.05)
				(type solid)
			)
			(fill no)
			(layer "F.CrtYd")
		)
		(fp_line
			(start 1.597 -1.391)
			(end -1.603 -1.391)
			(stroke
				(width 0.15)
				(type solid)
			)
			(layer "F.Fab")
		)
		(fp_line
			(start -0.603 -1.391)
			(end -1.603 -0.391)
			(stroke
				(width 0.15)
				(type solid)
			)
			(layer "F.Fab")
		)
		(fp_line
			(start -1.603 -1.391)
			(end -1.603 1.409)
			(stroke
				(width 0.15)
				(type solid)
			)
			(layer "F.Fab")
		)
		(fp_line
			(start 1.597 1.409)
			(end 1.597 -1.391)
			(stroke
				(width 0.15)
				(type solid)
			)
			(layer "F.Fab")
		)
		(fp_line
			(start -1.603 1.409)
			(end 1.597 1.409)
			(stroke
				(width 0.15)
				(type solid)
			)
			(layer "F.Fab")
		)
		(fp_circle
			(center -0.003 0.009)
			(end 1.117 0.009)
			(stroke
				(width 0.15)
				(type solid)
			)
			(fill no)
			(layer "F.Fab")
		)
		(pad "1" smd rect
			(at -1.255 -0.74 90)
			(size 1.5 1.1)
			(layers "F.Cu" "F.Mask" "F.Paste")
			(net 129 "Net-(D17-C_{R})")
			(pinfunction "C_{R}")
			(pintype "passive")
			(teardrops
				(best_length_ratio 0.2)
				(max_length 1)
				(best_width_ratio 0.9)
				(max_width 2)
				(curved_edges yes)
				(filter_ratio 0.9)
				(enabled yes)
				(allow_two_segments yes)
				(prefer_zone_connections yes)
			)
		)
		(pad "2" smd rect
			(at 1.245 -0.74 90)
			(size 1.5 1.1)
			(layers "F.Cu" "F.Mask" "F.Paste")
			(net 130 "Net-(D17-C_{G})")
			(pinfunction "C_{G}")
			(pintype "passive")
			(teardrops
				(best_length_ratio 0.2)
				(max_length 1)
				(best_width_ratio 0.9)
				(max_width 2)
				(curved_edges yes)
				(filter_ratio 0.9)
				(enabled yes)
				(allow_two_segments yes)
				(prefer_zone_connections yes)
			)
		)
		(pad "3" smd rect
			(at 1.245 0.76 90)
			(size 1.5 1.1)
			(layers "F.Cu" "F.Mask" "F.Paste")
			(net 131 "Net-(D17-C_{B})")
			(pinfunction "C_{B}")
			(pintype "passive")
			(teardrops
				(best_length_ratio 0.2)
				(max_length 1)
				(best_width_ratio 0.9)
				(max_width 2)
				(curved_edges yes)
				(filter_ratio 0.9)
				(enabled yes)
				(allow_two_segments yes)
				(prefer_zone_connections yes)
			)
		)
		(pad "4" smd rect
			(at -1.255 0.76 90)
			(size 1.5 1.1)
			(layers "F.Cu" "F.Mask" "F.Paste")
			(net 52 "+5V")
			(pinfunction "A")
			(pintype "passive")
			(teardrops
				(best_length_ratio 0.2)
				(max_length 1)
				(best_width_ratio 0.9)
				(max_width 2)
				(curved_edges yes)
				(filter_ratio 0.9)
				(enabled yes)
				(allow_two_segments yes)
				(prefer_zone_connections yes)
			)
		)
	)
	(footprint "antmicro-footprints:VFQFPN-40-1EP_5x5mm_P0.4mm_EP3.5x3.5mm"
		(layer "F.Cu")
		(at 215.678 128.725 -90)
		(descr "UQFN, 40 Pin")
		(tags "UQFN NoLead")
		(property "Reference" "U37"
			(at -3.015 -1.022 180)
			(layer "F.SilkS")
			(effects
				(font
					(size 0.7 0.7)
					(thickness 0.15)
				)
				(justify right bottom)
			)
		)
		(property "Value" "9DBL0651CKILF"
			(at 0 3.9 90)
			(layer "F.Fab")
			(effects
				(font
					(size 0.7 0.7)
					(thickness 0.15)
				)
				(justify right bottom)
			)
		)
		(property "Datasheet" "https://eu.mouser.com/datasheet/2/698/REN_9DBL02x2_9DBL04x2_9DBL06x1_9DBL08x1C_DST_20221-3075841.pdf"
			(at 0 0 270)
			(layer "F.Fab")
			(hide yes)
			(effects
				(font
					(size 1.27 1.27)
					(thickness 0.15)
				)
			)
		)
		(property "Author" "Antmicro"
			(at 86.953 344.403 0)
			(layer "F.Fab")
			(hide yes)
			(effects
				(font
					(size 1 1)
					(thickness 0.15)
				)
			)
		)
		(property "License" "Apache-2.0"
			(at 86.953 344.403 0)
			(layer "F.Fab")
			(hide yes)
			(effects
				(font
					(size 1 1)
					(thickness 0.15)
				)
			)
		)
		(property "MPN" "9DBL0651CKILF"
			(at 86.953 344.403 0)
			(layer "F.Fab")
			(hide yes)
			(effects
				(font
					(size 1 1)
					(thickness 0.15)
				)
			)
		)
		(property "Manufacturer" "Renesas"
			(at 86.953 344.403 0)
			(layer "F.Fab")
			(hide yes)
			(effects
				(font
					(size 1 1)
					(thickness 0.15)
				)
			)
		)
		(sheetname "PCIe misc")
		(sheetfile "pcie_misc.kicad_sch")
		(attr smd)
		(fp_line
			(start -2.61 2.608)
			(end -2.61 2.16)
			(stroke
				(width 0.15)
				(type solid)
			)
			(layer "F.SilkS")
		)
		(fp_line
			(start -2.161 2.608)
			(end -2.61 2.608)
			(stroke
				(width 0.15)
				(type solid)
			)
			(layer "F.SilkS")
		)
		(fp_line
			(start 2.16 2.608)
			(end 2.608 2.608)
			(stroke
				(width 0.15)
				(type solid)
			)
			(layer "F.SilkS")
		)
		(fp_line
			(start 2.608 2.608)
			(end 2.608 2.16)
			(stroke
				(width 0.15)
				(type solid)
			)
			(layer "F.SilkS")
		)
		(fp_line
			(start -2.61 -2.161)
			(end -2.61 -2.61)
			(stroke
				(width 0.15)
				(type solid)
			)
			(layer "F.SilkS")
		)
		(fp_line
			(start -2.161 -2.61)
			(end -2.61 -2.61)
			(stroke
				(width 0.15)
				(type solid)
			)
			(layer "F.SilkS")
		)
		(fp_line
			(start 2.16 -2.61)
			(end 2.608 -2.61)
			(stroke
				(width 0.15)
				(type solid)
			)
			(layer "F.SilkS")
		)
		(fp_line
			(start 2.608 -2.61)
			(end 2.608 -2.161)
			(stroke
				(width 0.15)
				(type solid)
			)
			(layer "F.SilkS")
		)
		(fp_circle
			(center -2.85 -2.05)
			(end -2.8 -2.05)
			(stroke
				(width 0.15)
				(type solid)
			)
			(fill yes)
			(layer "F.SilkS")
		)
		(fp_rect
			(start -3 -3)
			(end 2.999 2.999)
			(stroke
				(width 0.05)
				(type solid)
			)
			(fill no)
			(layer "F.CrtYd")
		)
		(fp_line
			(start -2.5 2.499)
			(end -2.5 -1.5)
			(stroke
				(width 0.15)
				(type solid)
			)
			(layer "F.Fab")
		)
		(fp_line
			(start 2.499 2.499)
			(end -2.5 2.499)
			(stroke
				(width 0.15)
				(type solid)
			)
			(layer "F.Fab")
		)
		(fp_line
			(start -2.5 -1.5)
			(end -1.5 -2.5)
			(stroke
				(width 0.15)
				(type solid)
			)
			(layer "F.Fab")
		)
		(fp_line
			(start -1.5 -2.5)
			(end 2.499 -2.5)
			(stroke
				(width 0.15)
				(type solid)
			)
			(layer "F.Fab")
		)
		(fp_line
			(start 2.499 -2.5)
			(end 2.499 2.499)
			(stroke
				(width 0.15)
				(type solid)
			)
			(layer "F.Fab")
		)
		(pad "" smd roundrect
			(at -1.1 -1.1 270)
			(size 0.8 0.8)
			(layers "F.Paste")
			(roundrect_rratio 0.245098)
			(teardrops
				(best_length_ratio 0.2)
				(max_length 1)
				(best_width_ratio 0.9)
				(max_width 2)
				(curved_edges yes)
				(filter_ratio 0.9)
				(enabled yes)
				(allow_two_segments yes)
				(prefer_zone_connections yes)
			)
		)
		(pad "" smd roundrect
			(at -1.1 0 270)
			(size 0.8 0.8)
			(layers "F.Paste")
			(roundrect_rratio 0.245098)
			(teardrops
				(best_length_ratio 0.2)
				(max_length 1)
				(best_width_ratio 0.9)
				(max_width 2)
				(curved_edges yes)
				(filter_ratio 0.9)
				(enabled yes)
				(allow_two_segments yes)
				(prefer_zone_connections yes)
			)
		)
		(pad "" smd roundrect
			(at -1.1 1.1 270)
			(size 0.8 0.8)
			(layers "F.Paste")
			(roundrect_rratio 0.245098)
			(teardrops
				(best_length_ratio 0.2)
				(max_length 1)
				(best_width_ratio 0.9)
				(max_width 2)
				(curved_edges yes)
				(filter_ratio 0.9)
				(enabled yes)
				(allow_two_segments yes)
				(prefer_zone_connections yes)
			)
		)
		(pad "" smd roundrect
			(at 0 -1.1 270)
			(size 0.8 0.8)
			(layers "F.Paste")
			(roundrect_rratio 0.245098)
			(teardrops
				(best_length_ratio 0.2)
				(max_length 1)
				(best_width_ratio 0.9)
				(max_width 2)
				(curved_edges yes)
				(filter_ratio 0.9)
				(enabled yes)
				(allow_two_segments yes)
				(prefer_zone_connections yes)
			)
		)
		(pad "" smd roundrect
			(at 0 0 270)
			(size 0.8 0.8)
			(layers "F.Paste")
			(roundrect_rratio 0.245098)
			(teardrops
				(best_length_ratio 0.2)
				(max_length 1)
				(best_width_ratio 0.9)
				(max_width 2)
				(curved_edges yes)
				(filter_ratio 0.9)
				(enabled yes)
				(allow_two_segments yes)
				(prefer_zone_connections yes)
			)
		)
		(pad "" smd roundrect
			(at 0 1.1 270)
			(size 0.8 0.8)
			(layers "F.Paste")
			(roundrect_rratio 0.245098)
			(teardrops
				(best_length_ratio 0.2)
				(max_length 1)
				(best_width_ratio 0.9)
				(max_width 2)
				(curved_edges yes)
				(filter_ratio 0.9)
				(enabled yes)
				(allow_two_segments yes)
				(prefer_zone_connections yes)
			)
		)
		(pad "" smd roundrect
			(at 1.1 -1.1 270)
			(size 0.8 0.8)
			(layers "F.Paste")
			(roundrect_rratio 0.245098)
			(teardrops
				(best_length_ratio 0.2)
				(max_length 1)
				(best_width_ratio 0.9)
				(max_width 2)
				(curved_edges yes)
				(filter_ratio 0.9)
				(enabled yes)
				(allow_two_segments yes)
				(prefer_zone_connections yes)
			)
		)
		(pad "" smd roundrect
			(at 1.1 0 270)
			(size 0.8 0.8)
			(layers "F.Paste")
			(roundrect_rratio 0.245098)
			(teardrops
				(best_length_ratio 0.2)
				(max_length 1)
				(best_width_ratio 0.9)
				(max_width 2)
				(curved_edges yes)
				(filter_ratio 0.9)
				(enabled yes)
				(allow_two_segments yes)
				(prefer_zone_connections yes)
			)
		)
		(pad "" smd roundrect
			(at 1.1 1.1 270)
			(size 0.8 0.8)
			(layers "F.Paste")
			(roundrect_rratio 0.245098)
			(teardrops
				(best_length_ratio 0.2)
				(max_length 1)
				(best_width_ratio 0.9)
				(max_width 2)
				(curved_edges yes)
				(filter_ratio 0.9)
				(enabled yes)
				(allow_two_segments yes)
				(prefer_zone_connections yes)
			)
		)
		(pad "1" smd roundrect
			(at -2.476 -1.801 270)
			(size 0.75 0.2)
			(layers "F.Cu" "F.Mask" "F.Paste")
			(roundrect_rratio 0.25)
			(net 711 "Net-(U37-SADR_{TRI})")
			(pinfunction "SADR_{TRI}")
			(pintype "input")
			(teardrops
				(best_length_ratio 0.2)
				(max_length 1)
				(best_width_ratio 0.9)
				(max_width 2)
				(curved_edges yes)
				(filter_ratio 0.9)
				(enabled yes)
				(allow_two_segments yes)
				(prefer_zone_connections yes)
			)
		)
		(pad "2" smd roundrect
			(at -2.476 -1.401 270)
			(size 0.75 0.2)
			(layers "F.Cu" "F.Mask" "F.Paste")
			(roundrect_rratio 0.25)
			(net 607 "Net-(U37-~{HIBW_BYPM_LOBW})")
			(pinfunction "~{HIBW_BYPM_LOBW}")
			(pintype "input")
			(teardrops
				(best_length_ratio 0.2)
				(max_length 1)
				(best_width_ratio 0.9)
				(max_width 2)
				(curved_edges yes)
				(filter_ratio 0.9)
				(enabled yes)
				(allow_two_segments yes)
				(prefer_zone_connections yes)
			)
		)
		(pad "3" smd roundrect
			(at -2.476 -1 270)
			(size 0.75 0.2)
			(layers "F.Cu" "F.Mask" "F.Paste")
			(roundrect_rratio 0.25)
			(net 786 "unconnected-(U37-FB_DNC+-Pad3)")
			(pinfunction "FB_DNC+")
			(pintype "no_connect")
			(teardrops
				(best_length_ratio 0.2)
				(max_length 1)
				(best_width_ratio 0.9)
				(max_width 2)
				(curved_edges yes)
				(filter_ratio 0.9)
				(enabled yes)
				(allow_two_segments yes)
				(prefer_zone_connections yes)
			)
		)
		(pad "4" smd roundrect
			(at -2.476 -0.6 270)
			(size 0.75 0.2)
			(layers "F.Cu" "F.Mask" "F.Paste")
			(roundrect_rratio 0.25)
			(net 787 "unconnected-(U37-FB_DNC--Pad4)")
			(pinfunction "FB_DNC-")
			(pintype "no_connect")
			(teardrops
				(best_length_ratio 0.2)
				(max_length 1)
				(best_width_ratio 0.9)
				(max_width 2)
				(curved_edges yes)
				(filter_ratio 0.9)
				(enabled yes)
				(allow_two_segments yes)
				(prefer_zone_connections yes)
			)
		)
		(pad "5" smd roundrect
			(at -2.476 -0.202 270)
			(size 0.75 0.2)
			(layers "F.Cu" "F.Mask" "F.Paste")
			(roundrect_rratio 0.25)
			(net 2 "+3V3")
			(pinfunction "VDDR")
			(pintype "power_in")
			(teardrops
				(best_length_ratio 0.2)
				(max_length 1)
				(best_width_ratio 0.9)
				(max_width 2)
				(curved_edges yes)
				(filter_ratio 0.9)
				(enabled yes)
				(allow_two_segments yes)
				(prefer_zone_connections yes)
			)
		)
		(pad "6" smd roundrect
			(at -2.476 0.2 270)
			(size 0.75 0.2)
			(layers "F.Cu" "F.Mask" "F.Paste")
			(roundrect_rratio 0.25)
			(net 336 "/Com Express 7 Interfaces/PCIE_{REF}.CK+")
			(pinfunction "CLK_IN+")
			(pintype "input")
			(teardrops
				(best_length_ratio 0.2)
				(max_length 1)
				(best_width_ratio 0.9)
				(max_width 2)
				(curved_edges yes)
				(filter_ratio 0.9)
				(enabled yes)
				(allow_two_segments yes)
				(prefer_zone_connections yes)
			)
		)
		(pad "7" smd roundrect
			(at -2.476 0.598 270)
			(size 0.75 0.2)
			(layers "F.Cu" "F.Mask" "F.Paste")
			(roundrect_rratio 0.25)
			(net 337 "/Com Express 7 Interfaces/PCIE_{REF}.CK-")
			(pinfunction "CLK_IN-")
			(pintype "input")
			(teardrops
				(best_length_ratio 0.2)
				(max_length 1)
				(best_width_ratio 0.9)
				(max_width 2)
				(curved_edges yes)
				(filter_ratio 0.9)
				(enabled yes)
				(allow_two_segments yes)
				(prefer_zone_connections yes)
			)
		)
		(pad "8" smd roundrect
			(at -2.476 0.998 270)
			(size 0.75 0.2)
			(layers "F.Cu" "F.Mask" "F.Paste")
			(roundrect_rratio 0.25)
			(net 1 "GND")
			(pinfunction "GNDDIG")
			(pintype "power_in")
			(teardrops
				(best_length_ratio 0.2)
				(max_length 1)
				(best_width_ratio 0.9)
				(max_width 2)
				(curved_edges yes)
				(filter_ratio 0.9)
				(enabled no)
				(allow_two_segments yes)
				(prefer_zone_connections yes)
			)
		)
		(pad "9" smd roundrect
			(at -2.476 1.398 270)
			(size 0.75 0.2)
			(layers "F.Cu" "F.Mask" "F.Paste")
			(roundrect_rratio 0.25)
			(net 709 "Net-(U37-SCLK)")
			(pinfunction "SCLK")
			(pintype "input")
			(teardrops
				(best_length_ratio 0.2)
				(max_length 1)
				(best_width_ratio 0.9)
				(max_width 2)
				(curved_edges yes)
				(filter_ratio 0.9)
				(enabled yes)
				(allow_two_segments yes)
				(prefer_zone_connections yes)
			)
		)
		(pad "10" smd roundrect
			(at -2.476 1.8 270)
			(size 0.75 0.2)
			(layers "F.Cu" "F.Mask" "F.Paste")
			(roundrect_rratio 0.25)
			(net 710 "Net-(U37-SDAT)")
			(pinfunction "SDAT")
			(pintype "bidirectional")
			(teardrops
				(best_length_ratio 0.2)
				(max_length 1)
				(best_width_ratio 0.9)
				(max_width 2)
				(curved_edges yes)
				(filter_ratio 0.9)
				(enabled yes)
				(allow_two_segments yes)
				(prefer_zone_connections yes)
			)
		)
		(pad "11" smd roundrect
			(at -1.801 2.475 270)
			(size 0.2 0.75)
			(layers "F.Cu" "F.Mask" "F.Paste")
			(roundrect_rratio 0.25)
			(net 2 "+3V3")
			(pinfunction "VDDDIG3V3")
			(pintype "power_in")
			(teardrops
				(best_length_ratio 0.2)
				(max_length 1)
				(best_width_ratio 0.9)
				(max_width 2)
				(curved_edges yes)
				(filter_ratio 0.9)
				(enabled yes)
				(allow_two_segments yes)
				(prefer_zone_connections yes)
			)
		)
		(pad "12" smd roundrect
			(at -1.401 2.475 270)
			(size 0.2 0.75)
			(layers "F.Cu" "F.Mask" "F.Paste")
			(roundrect_rratio 0.25)
			(net 2 "+3V3")
			(pinfunction "VDDIO")
			(pintype "power_in")
			(teardrops
				(best_length_ratio 0.2)
				(max_length 1)
				(best_width_ratio 0.9)
				(max_width 2)
				(curved_edges yes)
				(filter_ratio 0.9)
				(enabled yes)
				(allow_two_segments yes)
				(prefer_zone_connections yes)
			)
		)
		(pad "13" smd roundrect
			(at -1 2.475 270)
			(size 0.2 0.75)
			(layers "F.Cu" "F.Mask" "F.Paste")
			(roundrect_rratio 0.25)
			(net 602 "Net-(U37-~{OE0})")
			(pinfunction "~{OE0}")
			(pintype "input")
			(teardrops
				(best_length_ratio 0.2)
				(max_length 1)
				(best_width_ratio 0.9)
				(max_width 2)
				(curved_edges yes)
				(filter_ratio 0.9)
				(enabled yes)
				(allow_two_segments yes)
				(prefer_zone_connections yes)
			)
		)
		(pad "14" smd roundrect
			(at -0.6 2.475 270)
			(size 0.2 0.75)
			(layers "F.Cu" "F.Mask" "F.Paste")
			(roundrect_rratio 0.25)
			(net 611 "/PCIe misc/DIF0+")
			(pinfunction "DIF0+")
			(pintype "output")
			(teardrops
				(best_length_ratio 0.2)
				(max_length 1)
				(best_width_ratio 0.9)
				(max_width 2)
				(curved_edges yes)
				(filter_ratio 0.9)
				(enabled yes)
				(allow_two_segments yes)
				(prefer_zone_connections yes)
			)
		)
		(pad "15" smd roundrect
			(at -0.202 2.475 270)
			(size 0.2 0.75)
			(layers "F.Cu" "F.Mask" "F.Paste")
			(roundrect_rratio 0.25)
			(net 612 "/PCIe misc/DIF0-")
			(pinfunction "DIF0-")
			(pintype "output")
			(teardrops
				(best_length_ratio 0.2)
				(max_length 1)
				(best_width_ratio 0.9)
				(max_width 2)
				(curved_edges yes)
				(filter_ratio 0.9)
				(enabled yes)
				(allow_two_segments yes)
				(prefer_zone_connections yes)
			)
		)
		(pad "16" smd roundrect
			(at 0.2 2.475 270)
			(size 0.2 0.75)
			(layers "F.Cu" "F.Mask" "F.Paste")
			(roundrect_rratio 0.25)
			(net 2 "+3V3")
			(pinfunction "VDD3V3")
			(pintype "power_in")
			(teardrops
				(best_length_ratio 0.2)
				(max_length 1)
				(best_width_ratio 0.9)
				(max_width 2)
				(curved_edges yes)
				(filter_ratio 0.9)
				(enabled yes)
				(allow_two_segments yes)
				(prefer_zone_connections yes)
			)
		)
		(pad "17" smd roundrect
			(at 0.598 2.475 270)
			(size 0.2 0.75)
			(layers "F.Cu" "F.Mask" "F.Paste")
			(roundrect_rratio 0.25)
			(net 2 "+3V3")
			(pinfunction "VDDIO")
			(pintype "passive")
			(teardrops
				(best_length_ratio 0.2)
				(max_length 1)
				(best_width_ratio 0.9)
				(max_width 2)
				(curved_edges yes)
				(filter_ratio 0.9)
				(enabled yes)
				(allow_two_segments yes)
				(prefer_zone_connections yes)
			)
		)
		(pad "18" smd roundrect
			(at 0.998 2.475 270)
			(size 0.2 0.75)
			(layers "F.Cu" "F.Mask" "F.Paste")
			(roundrect_rratio 0.25)
			(net 613 "/PCIe misc/DIF1+")
			(pinfunction "DIF1+")
			(pintype "output")
			(teardrops
				(best_length_ratio 0.2)
				(max_length 1)
				(best_width_ratio 0.9)
				(max_width 2)
				(curved_edges yes)
				(filter_ratio 0.9)
				(enabled yes)
				(allow_two_segments yes)
				(prefer_zone_connections yes)
			)
		)
		(pad "19" smd roundrect
			(at 1.398 2.475 270)
			(size 0.2 0.75)
			(layers "F.Cu" "F.Mask" "F.Paste")
			(roundrect_rratio 0.25)
			(net 614 "/PCIe misc/DIF1-")
			(pinfunction "DIF1-")
			(pintype "output")
			(teardrops
				(best_length_ratio 0.2)
				(max_length 1)
				(best_width_ratio 0.9)
				(max_width 2)
				(curved_edges yes)
				(filter_ratio 0.9)
				(enabled yes)
				(allow_two_segments yes)
				(prefer_zone_connections yes)
			)
		)
		(pad "20" smd roundrect
			(at 1.8 2.475 270)
			(size 0.2 0.75)
			(layers "F.Cu" "F.Mask" "F.Paste")
			(roundrect_rratio 0.25)
			(net 788 "unconnected-(U37-NC-Pad20)")
			(pinfunction "NC")
			(pintype "no_connect")
			(teardrops
				(best_length_ratio 0.2)
				(max_length 1)
				(best_width_ratio 0.9)
				(max_width 2)
				(curved_edges yes)
				(filter_ratio 0.9)
				(enabled yes)
				(allow_two_segments yes)
				(prefer_zone_connections yes)
			)
		)
		(pad "21" smd roundrect
			(at 2.475 1.8 270)
			(size 0.75 0.2)
			(layers "F.Cu" "F.Mask" "F.Paste")
			(roundrect_rratio 0.25)
			(net 603 "Net-(U37-~{OE1})")
			(pinfunction "~{OE1}")
			(pintype "input")
			(teardrops
				(best_length_ratio 0.2)
				(max_length 1)
				(best_width_ratio 0.9)
				(max_width 2)
				(curved_edges yes)
				(filter_ratio 0.9)
				(enabled yes)
				(allow_two_segments yes)
				(prefer_zone_connections yes)
			)
		)
		(pad "22" smd roundrect
			(at 2.475 1.398 270)
			(size 0.75 0.2)
			(layers "F.Cu" "F.Mask" "F.Paste")
			(roundrect_rratio 0.25)
			(net 615 "/PCIe misc/DIF2+")
			(pinfunction "DIF2+")
			(pintype "output")
			(teardrops
				(best_length_ratio 0.2)
				(max_length 1)
				(best_width_ratio 0.9)
				(max_width 2)
				(curved_edges yes)
				(filter_ratio 0.9)
				(enabled yes)
				(allow_two_segments yes)
				(prefer_zone_connections yes)
			)
		)
		(pad "23" smd roundrect
			(at 2.475 0.998 270)
			(size 0.75 0.2)
			(layers "F.Cu" "F.Mask" "F.Paste")
			(roundrect_rratio 0.25)
			(net 616 "/PCIe misc/DIF2-")
			(pinfunction "DIF2-")
			(pintype "output")
			(teardrops
				(best_length_ratio 0.2)
				(max_length 1)
				(best_width_ratio 0.9)
				(max_width 2)
				(curved_edges yes)
				(filter_ratio 0.9)
				(enabled yes)
				(allow_two_segments yes)
				(prefer_zone_connections yes)
			)
		)
		(pad "24" smd roundrect
			(at 2.475 0.598 270)
			(size 0.75 0.2)
			(layers "F.Cu" "F.Mask" "F.Paste")
			(roundrect_rratio 0.25)
			(net 604 "Net-(U37-~{OE2})")
			(pinfunction "~{OE2}")
			(pintype "input")
			(teardrops
				(best_length_ratio 0.2)
				(max_length 1)
				(best_width_ratio 0.9)
				(max_width 2)
				(curved_edges yes)
				(filter_ratio 0.9)
				(enabled yes)
				(allow_two_segments yes)
				(prefer_zone_connections yes)
			)
		)
		(pad "25" smd roundrect
			(at 2.475 0.2 270)
			(size 0.75 0.2)
			(layers "F.Cu" "F.Mask" "F.Paste")
			(roundrect_rratio 0.25)
			(net 2 "+3V3")
			(pinfunction "VDDA3V3")
			(pintype "power_in")
			(teardrops
				(best_length_ratio 0.2)
				(max_length 1)
				(best_width_ratio 0.9)
				(max_width 2)
				(curved_edges yes)
				(filter_ratio 0.9)
				(enabled yes)
				(allow_two_segments yes)
				(prefer_zone_connections yes)
			)
		)
		(pad "26" smd roundrect
			(at 2.475 -0.202 270)
			(size 0.75 0.2)
			(layers "F.Cu" "F.Mask" "F.Paste")
			(roundrect_rratio 0.25)
			(net 2 "+3V3")
			(pinfunction "VDDIO")
			(pintype "passive")
			(teardrops
				(best_length_ratio 0.2)
				(max_length 1)
				(best_width_ratio 0.9)
				(max_width 2)
				(curved_edges yes)
				(filter_ratio 0.9)
				(enabled yes)
				(allow_two_segments yes)
				(prefer_zone_connections yes)
			)
		)
		(pad "27" smd roundrect
			(at 2.475 -0.6 270)
			(size 0.75 0.2)
			(layers "F.Cu" "F.Mask" "F.Paste")
			(roundrect_rratio 0.25)
			(net 617 "/PCIe misc/DIF3+")
			(pinfunction "DIF3+")
			(pintype "output")
			(teardrops
				(best_length_ratio 0.2)
				(max_length 1)
				(best_width_ratio 0.9)
				(max_width 2)
				(curved_edges yes)
				(filter_ratio 0.9)
				(enabled yes)
				(allow_two_segments yes)
				(prefer_zone_connections yes)
			)
		)
		(pad "28" smd roundrect
			(at 2.475 -1 270)
			(size 0.75 0.2)
			(layers "F.Cu" "F.Mask" "F.Paste")
			(roundrect_rratio 0.25)
			(net 618 "/PCIe misc/DIF3-")
			(pinfunction "DIF3-")
			(pintype "output")
			(teardrops
				(best_length_ratio 0.2)
				(max_length 1)
				(best_width_ratio 0.9)
				(max_width 2)
				(curved_edges yes)
				(filter_ratio 0.9)
				(enabled yes)
				(allow_two_segments yes)
				(prefer_zone_connections yes)
			)
		)
		(pad "29" smd roundrect
			(at 2.475 -1.401 270)
			(size 0.75 0.2)
			(layers "F.Cu" "F.Mask" "F.Paste")
			(roundrect_rratio 0.25)
			(net 605 "Net-(U37-~{OE3})")
			(pinfunction "~{OE3}")
			(pintype "input")
			(teardrops
				(best_length_ratio 0.2)
				(max_length 1)
				(best_width_ratio 0.9)
				(max_width 2)
				(curved_edges yes)
				(filter_ratio 0.9)
				(enabled yes)
				(allow_two_segments yes)
				(prefer_zone_connections yes)
			)
		)
		(pad "30" smd roundrect
			(at 2.475 -1.801 270)
			(size 0.75 0.2)
			(layers "F.Cu" "F.Mask" "F.Paste")
			(roundrect_rratio 0.25)
			(net 789 "unconnected-(U37-NC-Pad30)")
			(pinfunction "NC")
			(pintype "no_connect")
			(teardrops
				(best_length_ratio 0.2)
				(max_length 1)
				(best_width_ratio 0.9)
				(max_width 2)
				(curved_edges yes)
				(filter_ratio 0.9)
				(enabled yes)
				(allow_two_segments yes)
				(prefer_zone_connections yes)
			)
		)
		(pad "31" smd roundrect
			(at 1.8 -2.476 270)
			(size 0.2 0.75)
			(layers "F.Cu" "F.Mask" "F.Paste")
			(roundrect_rratio 0.25)
			(net 2 "+3V3")
			(pinfunction "VDD3V3")
			(pintype "passive")
			(teardrops
				(best_length_ratio 0.2)
				(max_length 1)
				(best_width_ratio 0.9)
				(max_width 2)
				(curved_edges yes)
				(filter_ratio 0.9)
				(enabled yes)
				(allow_two_segments yes)
				(prefer_zone_connections yes)
			)
		)
		(pad "32" smd roundrect
			(at 1.398 -2.476 270)
			(size 0.2 0.75)
			(layers "F.Cu" "F.Mask" "F.Paste")
			(roundrect_rratio 0.25)
			(net 2 "+3V3")
			(pinfunction "VDDIO")
			(pintype "passive")
			(teardrops
				(best_length_ratio 0.2)
				(max_length 1)
				(best_width_ratio 0.9)
				(max_width 2)
				(curved_edges yes)
				(filter_ratio 0.9)
				(enabled yes)
				(allow_two_segments yes)
				(prefer_zone_connections yes)
			)
		)
		(pad "33" smd roundrect
			(at 0.998 -2.476 270)
			(size 0.2 0.75)
			(layers "F.Cu" "F.Mask" "F.Paste")
			(roundrect_rratio 0.25)
			(net 619 "/PCIe misc/DIF4+")
			(pinfunction "DIF4+")
			(pintype "output")
			(teardrops
				(best_length_ratio 0.2)
				(max_length 1)
				(best_width_ratio 0.9)
				(max_width 2)
				(curved_edges yes)
				(filter_ratio 0.9)
				(enabled yes)
				(allow_two_segments yes)
				(prefer_zone_connections yes)
			)
		)
		(pad "34" smd roundrect
			(at 0.598 -2.476 270)
			(size 0.2 0.75)
			(layers "F.Cu" "F.Mask" "F.Paste")
			(roundrect_rratio 0.25)
			(net 620 "/PCIe misc/DIF4-")
			(pinfunction "DIF4-")
			(pintype "output")
			(teardrops
				(best_length_ratio 0.2)
				(max_length 1)
				(best_width_ratio 0.9)
				(max_width 2)
				(curved_edges yes)
				(filter_ratio 0.9)
				(enabled yes)
				(allow_two_segments yes)
				(prefer_zone_connections yes)
			)
		)
		(pad "35" smd roundrect
			(at 0.2 -2.476 270)
			(size 0.2 0.75)
			(layers "F.Cu" "F.Mask" "F.Paste")
			(roundrect_rratio 0.25)
			(net 606 "Net-(U37-~{OE4})")
			(pinfunction "~{OE4}")
			(pintype "input")
			(teardrops
				(best_length_ratio 0.2)
				(max_length 1)
				(best_width_ratio 0.9)
				(max_width 2)
				(curved_edges yes)
				(filter_ratio 0.9)
				(enabled yes)
				(allow_two_segments yes)
				(prefer_zone_connections yes)
			)
		)
		(pad "36" smd roundrect
			(at -0.202 -2.476 270)
			(size 0.2 0.75)
			(layers "F.Cu" "F.Mask" "F.Paste")
			(roundrect_rratio 0.25)
			(net 621 "/PCIe misc/DIF5+")
			(pinfunction "DIF5+")
			(pintype "output")
			(teardrops
				(best_length_ratio 0.2)
				(max_length 1)
				(best_width_ratio 0.9)
				(max_width 2)
				(curved_edges yes)
				(filter_ratio 0.9)
				(enabled yes)
				(allow_two_segments yes)
				(prefer_zone_connections yes)
			)
		)
		(pad "37" smd roundrect
			(at -0.6 -2.476 270)
			(size 0.2 0.75)
			(layers "F.Cu" "F.Mask" "F.Paste")
			(roundrect_rratio 0.25)
			(net 622 "/PCIe misc/DIF5-")
			(pinfunction "DIF5-")
			(pintype "output")
			(teardrops
				(best_length_ratio 0.2)
				(max_length 1)
				(best_width_ratio 0.9)
				(max_width 2)
				(curved_edges yes)
				(filter_ratio 0.9)
				(enabled yes)
				(allow_two_segments yes)
				(prefer_zone_connections yes)
			)
		)
		(pad "38" smd roundrect
			(at -1 -2.476 270)
			(size 0.2 0.75)
			(layers "F.Cu" "F.Mask" "F.Paste")
			(roundrect_rratio 0.25)
			(net 608 "Net-(U37-~{OE5})")
			(pinfunction "~{OE5}")
			(pintype "input")
			(teardrops
				(best_length_ratio 0.2)
				(max_length 1)
				(best_width_ratio 0.9)
				(max_width 2)
				(curved_edges yes)
				(filter_ratio 0.9)
				(enabled yes)
				(allow_two_segments yes)
				(prefer_zone_connections yes)
			)
		)
		(pad "39" smd roundrect
			(at -1.401 -2.476 270)
			(size 0.2 0.75)
			(layers "F.Cu" "F.Mask" "F.Paste")
			(roundrect_rratio 0.25)
			(net 2 "+3V3")
			(pinfunction "VDDIO")
			(pintype "passive")
			(teardrops
				(best_length_ratio 0.2)
				(max_length 1)
				(best_width_ratio 0.9)
				(max_width 2)
				(curved_edges yes)
				(filter_ratio 0.9)
				(enabled yes)
				(allow_two_segments yes)
				(prefer_zone_connections yes)
			)
		)
		(pad "40" smd roundrect
			(at -1.801 -2.476 270)
			(size 0.2 0.75)
			(layers "F.Cu" "F.Mask" "F.Paste")
			(roundrect_rratio 0.25)
			(net 609 "Net-(U37-~{CKPWRGD_PD})")
			(pinfunction "~{CKPWRGD_PD}")
			(pintype "input")
			(teardrops
				(best_length_ratio 0.2)
				(max_length 1)
				(best_width_ratio 0.9)
				(max_width 2)
				(curved_edges yes)
				(filter_ratio 0.9)
				(enabled yes)
				(allow_two_segments yes)
				(prefer_zone_connections yes)
			)
		)
		(pad "41" smd rect
			(at 0 0 270)
			(size 3.5 3.5)
			(layers "F.Cu" "F.Mask")
			(net 1 "GND")
			(pinfunction "EPAD")
			(pintype "passive")
			(teardrops
				(best_length_ratio 0.2)
				(max_length 1)
				(best_width_ratio 0.9)
				(max_width 2)
				(curved_edges yes)
				(filter_ratio 0.9)
				(enabled no)
				(allow_two_segments yes)
				(prefer_zone_connections yes)
			)
		)
	)
	(footprint "antmicro-footprints:TP_SMD_0.75mm"
		(layer "F.Cu")
		(at 197.875 133.7 45)
		(property "Reference" "TP55"
			(at 0.45 0.499999 45)
			(layer "F.SilkS")
			(effects
				(font
					(size 0.7 0.7)
					(thickness 0.15)
				)
				(justify left bottom)
			)
		)
		(property "Value" "TP_0.75mm_SMD"
			(at 0 1.2 45)
			(layer "F.Fab")
			(effects
				(font
					(size 0.7 0.7)
					(thickness 0.15)
				)
				(justify left bottom)
			)
		)
		(property "Author" "Antmicro"
			(at 369.6 -273.32 45)
			(layer "F.Fab")
			(hide yes)
			(effects
				(font
					(size 1 1)
					(thickness 0.15)
				)
			)
		)
		(property "License" "Apache-2.0"
			(at 369.6 -273.32 45)
			(layer "F.Fab")
			(hide yes)
			(effects
				(font
					(size 1 1)
					(thickness 0.15)
				)
			)
		)
		(property "MPN" ""
			(at 369.6 -273.32 45)
			(layer "F.Fab")
			(hide yes)
			(effects
				(font
					(size 1 1)
					(thickness 0.15)
				)
			)
		)
		(property "Manufacturer" ""
			(at 369.6 -273.32 45)
			(layer "F.Fab")
			(hide yes)
			(effects
				(font
					(size 1 1)
					(thickness 0.15)
				)
			)
		)
		(property "Public" "False"
			(at 369.6 -273.32 45)
			(layer "F.Fab")
			(hide yes)
			(effects
				(font
					(size 1 1)
					(thickness 0.15)
				)
			)
		)
		(sheetname "PCIe redriver")
		(sheetfile "pcie_redriver.kicad_sch")
		(attr exclude_from_pos_files exclude_from_bom)
		(fp_circle
			(center 0 0)
			(end 0.475 0)
			(stroke
				(width 0.05)
				(type default)
			)
			(fill no)
			(layer "F.CrtYd")
		)
		(pad "1" smd circle
			(at 0 0 45)
			(size 0.75 0.75)
			(layers "F.Cu" "F.Mask")
			(net 718 "Net-(U40-I2C_{DONE})")
			(pinfunction "1")
			(pintype "passive")
			(teardrops
				(best_length_ratio 0.4)
				(max_length 1)
				(best_width_ratio 0.9)
				(max_width 2)
				(curved_edges yes)
				(filter_ratio 0.9)
				(enabled yes)
				(allow_two_segments yes)
				(prefer_zone_connections yes)
			)
		)
	)
	(footprint "antmicro-footprints:R_0402_1005Metric"
		(layer "F.Cu")
		(at 177.52 107.66 180)
		(descr "Resistor SMD 0402")
		(tags "resistor SMD 0402")
		(property "Reference" "R120"
			(at 0.82 -0.45 0)
			(layer "F.SilkS")
			(effects
				(font
					(size 0.7 0.7)
					(thickness 0.15)
				)
				(justify right bottom)
			)
		)
		(property "Value" "R_0R_0402"
			(at -1.011843 1.772047 0)
			(layer "F.Fab")
			(effects
				(font
					(size 0.7 0.7)
					(thickness 0.15)
				)
				(justify right bottom)
			)
		)
		(property "Datasheet" "https://industrial.panasonic.com/cdbs/www-data/pdf/RDA0000/AOA0000C301.pdf"
			(at 0 0 180)
			(layer "F.Fab")
			(hide yes)
			(effects
				(font
					(size 1.27 1.27)
					(thickness 0.15)
				)
			)
		)
		(property "Author" "Antmicro"
			(at 355.04 215.32 0)
			(layer "F.Fab")
			(hide yes)
			(effects
				(font
					(size 1 1)
					(thickness 0.15)
				)
			)
		)
		(property "Current" "1A"
			(at 355.04 215.32 0)
			(layer "F.Fab")
			(hide yes)
			(effects
				(font
					(size 1 1)
					(thickness 0.15)
				)
			)
		)
		(property "License" "Apache-2.0"
			(at 355.04 215.32 0)
			(layer "F.Fab")
			(hide yes)
			(effects
				(font
					(size 1 1)
					(thickness 0.15)
				)
			)
		)
		(property "MPN" "ERJ2GE0R00X"
			(at 355.04 215.32 0)
			(layer "F.Fab")
			(hide yes)
			(effects
				(font
					(size 1 1)
					(thickness 0.15)
				)
			)
		)
		(property "Manufacturer" "Panasonic"
			(at 355.04 215.32 0)
			(layer "F.Fab")
			(hide yes)
			(effects
				(font
					(size 1 1)
					(thickness 0.15)
				)
			)
		)
		(property "Public" "False"
			(at 355.04 215.32 0)
			(layer "F.Fab")
			(hide yes)
			(effects
				(font
					(size 1 1)
					(thickness 0.15)
				)
			)
		)
		(property "Tolerance" ""
			(at 355.04 215.32 0)
			(layer "F.Fab")
			(hide yes)
			(effects
				(font
					(size 1 1)
					(thickness 0.15)
				)
			)
		)
		(property "Val" "0R"
			(at 355.04 215.32 0)
			(layer "F.Fab")
			(hide yes)
			(effects
				(font
					(size 1 1)
					(thickness 0.15)
				)
			)
		)
		(sheetname "M.2 key M #1")
		(sheetfile "m2keym_low.kicad_sch")
		(attr smd)
		(fp_rect
			(start -0.925 -0.47)
			(end 0.925 0.47)
			(stroke
				(width 0.05)
				(type default)
			)
			(fill no)
			(layer "F.CrtYd")
		)
		(fp_rect
			(start -0.5 -0.25)
			(end 0.5 0.25)
			(stroke
				(width 0.15)
				(type solid)
			)
			(fill no)
			(layer "F.Fab")
		)
		(pad "1" smd roundrect
			(at -0.48 0 180)
			(size 0.59 0.64)
			(layers "F.Cu" "F.Mask" "F.Paste")
			(roundrect_rratio 0.25)
			(net 528 "/Backplane/~{PERST}")
			(pintype "passive")
			(teardrops
				(best_length_ratio 0.2)
				(max_length 1)
				(best_width_ratio 0.9)
				(max_width 2)
				(curved_edges yes)
				(filter_ratio 0.9)
				(enabled yes)
				(allow_two_segments yes)
				(prefer_zone_connections yes)
			)
		)
		(pad "2" smd roundrect
			(at 0.48 0 180)
			(size 0.59 0.64)
			(layers "F.Cu" "F.Mask" "F.Paste")
			(roundrect_rratio 0.25)
			(net 228 "/M.2 key M #1/~{PERST_D}")
			(pintype "passive")
			(teardrops
				(best_length_ratio 0.2)
				(max_length 1)
				(best_width_ratio 0.9)
				(max_width 2)
				(curved_edges yes)
				(filter_ratio 0.9)
				(enabled yes)
				(allow_two_segments yes)
				(prefer_zone_connections yes)
			)
		)
	)
	(footprint "antmicro-footprints:R_0402_1005Metric"
		(layer "F.Cu")
		(at 306.14 130.03)
		(descr "Resistor SMD 0402")
		(tags "resistor SMD 0402")
		(property "Reference" "R101"
			(at -1.14 -0.52 0)
			(layer "F.SilkS")
			(effects
				(font
					(size 0.7 0.7)
					(thickness 0.15)
				)
				(justify left bottom)
			)
		)
		(property "Value" "R_100k_0402"
			(at -1.011843 1.772047 0)
			(layer "F.Fab")
			(effects
				(font
					(size 0.7 0.7)
					(thickness 0.15)
				)
				(justify left bottom)
			)
		)
		(property "Datasheet" "https://www.bourns.com/docs/product-datasheets/cr.pdf"
			(at 0 0 0)
			(layer "F.Fab")
			(hide yes)
			(effects
				(font
					(size 1.27 1.27)
					(thickness 0.15)
				)
			)
		)
		(property "Author" "Antmicro"
			(at 0 0 0)
			(layer "F.Fab")
			(hide yes)
			(effects
				(font
					(size 1 1)
					(thickness 0.15)
				)
			)
		)
		(property "License" "Apache-2.0"
			(at 0 0 0)
			(layer "F.Fab")
			(hide yes)
			(effects
				(font
					(size 1 1)
					(thickness 0.15)
				)
			)
		)
		(property "MPN" "CR0402-FX-1003GLF"
			(at 0 0 0)
			(layer "F.Fab")
			(hide yes)
			(effects
				(font
					(size 1 1)
					(thickness 0.15)
				)
			)
		)
		(property "Manufacturer" "Bourns"
			(at 0 0 0)
			(layer "F.Fab")
			(hide yes)
			(effects
				(font
					(size 1 1)
					(thickness 0.15)
				)
			)
		)
		(property "Public" "False"
			(at 0 0 0)
			(layer "F.Fab")
			(hide yes)
			(effects
				(font
					(size 1 1)
					(thickness 0.15)
				)
			)
		)
		(property "Tolerance" "1%"
			(at 0 0 0)
			(layer "F.Fab")
			(hide yes)
			(effects
				(font
					(size 1 1)
					(thickness 0.15)
				)
			)
		)
		(property "Val" "100k"
			(at 0 0 0)
			(layer "F.Fab")
			(hide yes)
			(effects
				(font
					(size 1 1)
					(thickness 0.15)
				)
			)
		)
		(sheetname "Power")
		(sheetfile "power.kicad_sch")
		(attr smd)
		(fp_rect
			(start -0.925 -0.47)
			(end 0.925 0.47)
			(stroke
				(width 0.05)
				(type default)
			)
			(fill no)
			(layer "F.CrtYd")
		)
		(fp_rect
			(start -0.5 -0.25)
			(end 0.5 0.25)
			(stroke
				(width 0.15)
				(type solid)
			)
			(fill no)
			(layer "F.Fab")
		)
		(pad "1" smd roundrect
			(at -0.48 0)
			(size 0.59 0.64)
			(layers "F.Cu" "F.Mask" "F.Paste")
			(roundrect_rratio 0.25)
			(net 1 "GND")
			(pintype "passive")
			(teardrops
				(best_length_ratio 0.2)
				(max_length 1)
				(best_width_ratio 0.9)
				(max_width 2)
				(curved_edges yes)
				(filter_ratio 0.9)
				(enabled yes)
				(allow_two_segments yes)
				(prefer_zone_connections yes)
			)
		)
		(pad "2" smd roundrect
			(at 0.48 0)
			(size 0.59 0.64)
			(layers "F.Cu" "F.Mask" "F.Paste")
			(roundrect_rratio 0.25)
			(net 578 "/Power/PG_{1V0}")
			(pintype "passive")
			(teardrops
				(best_length_ratio 0.2)
				(max_length 1)
				(best_width_ratio 0.9)
				(max_width 2)
				(curved_edges yes)
				(filter_ratio 0.9)
				(enabled yes)
				(allow_two_segments yes)
				(prefer_zone_connections yes)
			)
		)
	)
	(footprint "antmicro-footprints:USON-10_2.5x1mm_P0.5mm"
		(layer "F.Cu")
		(at 110.7 152.2 -90)
		(descr "USON-10 2.5x1mm_ Pitch 0.5mm")
		(tags "USON-10 2.5x1mm Pitch 0.5mm")
		(property "Reference" "U17"
			(at -1.7 1.3 0)
			(layer "F.SilkS")
			(effects
				(font
					(size 0.7 0.7)
					(thickness 0.15)
				)
				(justify left top)
			)
		)
		(property "Value" "ESD204DQAR"
			(at 0.018 2.499 90)
			(layer "F.Fab")
			(effects
				(font
					(size 0.7 0.7)
					(thickness 0.15)
				)
				(justify right bottom)
			)
		)
		(property "Datasheet" "https://www.ti.com/lit/ds/symlink/esd204.pdf?ts=1706004844383&ref_url=https%253A%252F%252Fwww.ti.com%252Finterface%252Fdiodes%252Fesd-protection-diodes%252Fproducts.html"
			(at 0 0 90)
			(layer "F.Fab")
			(hide yes)
			(effects
				(font
					(size 1.27 1.27)
					(thickness 0.15)
				)
			)
		)
		(property "Author" "Antmicro"
			(at -46.422998 258.252998 0)
			(layer "F.Fab")
			(hide yes)
			(effects
				(font
					(size 1 1)
					(thickness 0.15)
				)
			)
		)
		(property "License" "Apache-2.0"
			(at -46.422998 258.252998 0)
			(layer "F.Fab")
			(hide yes)
			(effects
				(font
					(size 1 1)
					(thickness 0.15)
				)
			)
		)
		(property "MPN" "ESD204DQAR"
			(at -46.422998 258.252998 0)
			(layer "F.Fab")
			(hide yes)
			(effects
				(font
					(size 1 1)
					(thickness 0.15)
				)
			)
		)
		(property "Manufacturer" "Texas Instruments"
			(at -46.422998 258.252998 0)
			(layer "F.Fab")
			(hide yes)
			(effects
				(font
					(size 1 1)
					(thickness 0.15)
				)
			)
		)
		(sheetname "OCuLink")
		(sheetfile "oculink.kicad_sch")
		(attr smd)
		(fp_line
			(start 0.498 1.398)
			(end -0.5 1.398)
			(stroke
				(width 0.15)
				(type solid)
			)
			(layer "F.SilkS")
		)
		(fp_line
			(start 0.498 -1.401)
			(end -0.5 -1.401)
			(stroke
				(width 0.15)
				(type solid)
			)
			(layer "F.SilkS")
		)
		(fp_circle
			(center -0.68 -1.27)
			(end -0.63 -1.27)
			(stroke
				(width 0.15)
				(type solid)
			)
			(fill yes)
			(layer "F.SilkS")
		)
		(fp_rect
			(start -0.8 -1.5)
			(end 0.8 1.499)
			(stroke
				(width 0.05)
				(type solid)
			)
			(fill no)
			(layer "F.CrtYd")
		)
		(fp_line
			(start -0.5 1.249)
			(end 0.498 1.249)
			(stroke
				(width 0.15)
				(type solid)
			)
			(layer "F.Fab")
		)
		(fp_line
			(start -0.5 -1)
			(end -0.5 1.249)
			(stroke
				(width 0.15)
				(type solid)
			)
			(layer "F.Fab")
		)
		(fp_line
			(start -0.25 -1.25)
			(end -0.5 -1)
			(stroke
				(width 0.15)
				(type solid)
			)
			(layer "F.Fab")
		)
		(fp_line
			(start 0.498 -1.25)
			(end 0.498 1.249)
			(stroke
				(width 0.15)
				(type solid)
			)
			(layer "F.Fab")
		)
		(fp_line
			(start 0.498 -1.25)
			(end -0.25 -1.25)
			(stroke
				(width 0.15)
				(type solid)
			)
			(layer "F.Fab")
		)
		(pad "1" smd roundrect
			(at -0.387 -1 180)
			(size 0.25 0.55)
			(layers "F.Cu" "F.Mask" "F.Paste")
			(roundrect_rratio 0.25)
			(net 192 "/OCuLink/PCIe_{REF0}.CK+")
			(pintype "passive")
			(teardrops
				(best_length_ratio 0.2)
				(max_length 1)
				(best_width_ratio 0.9)
				(max_width 2)
				(curved_edges yes)
				(filter_ratio 0.9)
				(enabled yes)
				(allow_two_segments yes)
				(prefer_zone_connections yes)
			)
		)
		(pad "2" smd roundrect
			(at -0.387 -0.5 180)
			(size 0.25 0.55)
			(layers "F.Cu" "F.Mask" "F.Paste")
			(roundrect_rratio 0.25)
			(net 193 "/OCuLink/PCIe_{REF0}.CK-")
			(pintype "passive")
			(teardrops
				(best_length_ratio 0.2)
				(max_length 1)
				(best_width_ratio 0.9)
				(max_width 2)
				(curved_edges yes)
				(filter_ratio 0.9)
				(enabled yes)
				(allow_two_segments yes)
				(prefer_zone_connections yes)
			)
		)
		(pad "3" smd roundrect
			(at -0.387 0 180)
			(size 0.4 0.55)
			(layers "F.Cu" "F.Mask" "F.Paste")
			(roundrect_rratio 0.25)
			(net 1 "GND")
			(pintype "power_in")
			(teardrops
				(best_length_ratio 0.2)
				(max_length 1)
				(best_width_ratio 0.9)
				(max_width 2)
				(curved_edges yes)
				(filter_ratio 0.9)
				(enabled yes)
				(allow_two_segments yes)
				(prefer_zone_connections yes)
			)
		)
		(pad "4" smd roundrect
			(at -0.387 0.498 180)
			(size 0.25 0.55)
			(layers "F.Cu" "F.Mask" "F.Paste")
			(roundrect_rratio 0.25)
			(net 996 "unconnected-(U17-Pad4)_1")
			(pintype "passive+no_connect")
			(teardrops
				(best_length_ratio 0.2)
				(max_length 1)
				(best_width_ratio 0.9)
				(max_width 2)
				(curved_edges yes)
				(filter_ratio 0.9)
				(enabled yes)
				(allow_two_segments yes)
				(prefer_zone_connections yes)
			)
		)
		(pad "5" smd roundrect
			(at -0.387 0.998 180)
			(size 0.25 0.55)
			(layers "F.Cu" "F.Mask" "F.Paste")
			(roundrect_rratio 0.25)
			(net 992 "unconnected-(U17-Pad5)")
			(pintype "passive+no_connect")
			(teardrops
				(best_length_ratio 0.2)
				(max_length 1)
				(best_width_ratio 0.9)
				(max_width 2)
				(curved_edges yes)
				(filter_ratio 0.9)
				(enabled yes)
				(allow_two_segments yes)
				(prefer_zone_connections yes)
			)
		)
		(pad "6" smd roundrect
			(at 0.385 0.998 180)
			(size 0.25 0.55)
			(layers "F.Cu" "F.Mask" "F.Paste")
			(roundrect_rratio 0.25)
			(net 997 "unconnected-(U17-Pad5)_1")
			(pintype "passive+no_connect")
			(teardrops
				(best_length_ratio 0.2)
				(max_length 1)
				(best_width_ratio 0.9)
				(max_width 2)
				(curved_edges yes)
				(filter_ratio 0.9)
				(enabled yes)
				(allow_two_segments yes)
				(prefer_zone_connections yes)
			)
		)
		(pad "7" smd roundrect
			(at 0.385 0.498 180)
			(size 0.25 0.55)
			(layers "F.Cu" "F.Mask" "F.Paste")
			(roundrect_rratio 0.25)
			(net 991 "unconnected-(U17-Pad4)")
			(pintype "passive+no_connect")
			(teardrops
				(best_length_ratio 0.2)
				(max_length 1)
				(best_width_ratio 0.9)
				(max_width 2)
				(curved_edges yes)
				(filter_ratio 0.9)
				(enabled yes)
				(allow_two_segments yes)
				(prefer_zone_connections yes)
			)
		)
		(pad "8" smd roundrect
			(at 0.385 0 180)
			(size 0.4 0.55)
			(layers "F.Cu" "F.Mask" "F.Paste")
			(roundrect_rratio 0.25)
			(net 1 "GND")
			(pintype "passive")
			(teardrops
				(best_length_ratio 0.2)
				(max_length 1)
				(best_width_ratio 0.9)
				(max_width 2)
				(curved_edges yes)
				(filter_ratio 0.9)
				(enabled yes)
				(allow_two_segments yes)
				(prefer_zone_connections yes)
			)
		)
		(pad "9" smd roundrect
			(at 0.385 -0.5 180)
			(size 0.25 0.55)
			(layers "F.Cu" "F.Mask" "F.Paste")
			(roundrect_rratio 0.25)
			(net 193 "/OCuLink/PCIe_{REF0}.CK-")
			(pintype "passive")
			(teardrops
				(best_length_ratio 0.2)
				(max_length 1)
				(best_width_ratio 0.9)
				(max_width 2)
				(curved_edges yes)
				(filter_ratio 0.9)
				(enabled yes)
				(allow_two_segments yes)
				(prefer_zone_connections yes)
			)
		)
		(pad "10" smd roundrect
			(at 0.385 -1 180)
			(size 0.25 0.55)
			(layers "F.Cu" "F.Mask" "F.Paste")
			(roundrect_rratio 0.25)
			(net 192 "/OCuLink/PCIe_{REF0}.CK+")
			(pintype "passive")
			(teardrops
				(best_length_ratio 0.2)
				(max_length 1)
				(best_width_ratio 0.9)
				(max_width 2)
				(curved_edges yes)
				(filter_ratio 0.9)
				(enabled yes)
				(allow_two_segments yes)
				(prefer_zone_connections yes)
			)
		)
	)
	(footprint "antmicro-footprints:R_0402_1005Metric"
		(layer "F.Cu")
		(at 190.054908 138.772113 -135)
		(descr "Resistor SMD 0402")
		(tags "resistor SMD 0402")
		(property "Reference" "R228"
			(at 1.069206 -0.415818 45)
			(layer "F.SilkS")
			(effects
				(font
					(size 0.7 0.7)
					(thickness 0.15)
				)
				(justify right bottom)
			)
		)
		(property "Value" "R_1k_0402"
			(at -1.011843 1.772046 45)
			(layer "F.Fab")
			(effects
				(font
					(size 0.7 0.7)
					(thickness 0.15)
				)
				(justify right bottom)
			)
		)
		(property "Datasheet" "https://www.bourns.com/docs/product-datasheets/cr.pdf"
			(at 0 0 45)
			(layer "B.Fab")
			(hide yes)
			(effects
				(font
					(size 1.27 1.27)
					(thickness 0.15)
				)
				(justify mirror)
			)
		)
		(property "Author" "Antmicro"
			(at 0 0 45)
			(layer "F.Fab")
			(hide yes)
			(effects
				(font
					(size 1 1)
					(thickness 0.15)
				)
			)
		)
		(property "License" "Apache-2.0"
			(at 0 0 45)
			(layer "F.Fab")
			(hide yes)
			(effects
				(font
					(size 1 1)
					(thickness 0.15)
				)
			)
		)
		(property "MPN" "CR0402-FX-1001GLF"
			(at 0 0 45)
			(layer "F.Fab")
			(hide yes)
			(effects
				(font
					(size 1 1)
					(thickness 0.15)
				)
			)
		)
		(property "Manufacturer" "Bourns"
			(at 0 0 45)
			(layer "F.Fab")
			(hide yes)
			(effects
				(font
					(size 1 1)
					(thickness 0.15)
				)
			)
		)
		(property "Public" "False"
			(at 0 0 45)
			(layer "F.Fab")
			(hide yes)
			(effects
				(font
					(size 1 1)
					(thickness 0.15)
				)
			)
		)
		(property "Tolerance" "1%"
			(at 0 0 45)
			(layer "F.Fab")
			(hide yes)
			(effects
				(font
					(size 1 1)
					(thickness 0.15)
				)
			)
		)
		(property "Val" "1k"
			(at 0 0 45)
			(layer "F.Fab")
			(hide yes)
			(effects
				(font
					(size 1 1)
					(thickness 0.15)
				)
			)
		)
		(sheetname "PCIe redriver")
		(sheetfile "pcie_redriver.kicad_sch")
		(attr smd)
		(fp_poly
			(pts
				(xy -0.925 -0.47) (xy 0.925 -0.47) (xy 0.925 0.47) (xy -0.925 0.47)
			)
			(stroke
				(width 0.05)
				(type default)
			)
			(fill no)
			(layer "F.CrtYd")
		)
		(fp_poly
			(pts
				(xy -0.5 -0.25) (xy 0.5 -0.25) (xy 0.5 0.25) (xy -0.5 0.25)
			)
			(stroke
				(width 0.15)
				(type solid)
			)
			(fill no)
			(layer "F.Fab")
		)
		(pad "1" smd roundrect
			(at -0.48 0 225)
			(size 0.59 0.64)
			(layers "F.Cu" "F.Mask" "F.Paste")
			(roundrect_rratio 0.25)
			(net 1 "GND")
			(pintype "passive")
			(teardrops
				(best_length_ratio 0.2)
				(max_length 1)
				(best_width_ratio 0.9)
				(max_width 2)
				(curved_edges yes)
				(filter_ratio 0.9)
				(enabled yes)
				(allow_two_segments yes)
				(prefer_zone_connections yes)
			)
		)
		(pad "2" smd roundrect
			(at 0.48 0 225)
			(size 0.59 0.64)
			(layers "F.Cu" "F.Mask" "F.Paste")
			(roundrect_rratio 0.25)
			(net 977 "/PCIe redriver/RX_EQ1")
			(pintype "passive")
			(teardrops
				(best_length_ratio 0.2)
				(max_length 1)
				(best_width_ratio 0.9)
				(max_width 2)
				(curved_edges yes)
				(filter_ratio 0.9)
				(enabled yes)
				(allow_two_segments yes)
				(prefer_zone_connections yes)
			)
		)
	)
	(footprint "antmicro-footprints:R_0201"
		(layer "F.Cu")
		(at 146.57 147.31 -90)
		(descr "Resistor SMD 0201")
		(tags "resistor SMD 0201")
		(property "Reference" "R274"
			(at 4.125 -0.28 270)
			(layer "F.SilkS")
			(effects
				(font
					(size 0.7 0.7)
					(thickness 0.15)
				)
				(justify left bottom)
			)
		)
		(property "Value" "R_0R_0201"
			(at 0 1.25 270)
			(layer "F.Fab")
			(effects
				(font
					(size 0.7 0.7)
					(thickness 0.15)
				)
				(justify left bottom)
			)
		)
		(property "Datasheet" "https://www.bourns.com/docs/product-datasheets/cr.pdf"
			(at 0 0 270)
			(layer "F.Fab")
			(hide yes)
			(effects
				(font
					(size 1.27 1.27)
					(thickness 0.15)
				)
			)
		)
		(property "Author" "Antmicro"
			(at -0.74 293.88 0)
			(layer "F.Fab")
			(hide yes)
			(effects
				(font
					(size 1 1)
					(thickness 0.15)
				)
			)
		)
		(property "License" "Apache-2.0"
			(at -0.74 293.88 0)
			(layer "F.Fab")
			(hide yes)
			(effects
				(font
					(size 1 1)
					(thickness 0.15)
				)
			)
		)
		(property "MPN" "CR0201-FX-0R00GLF"
			(at -0.74 293.88 0)
			(layer "F.Fab")
			(hide yes)
			(effects
				(font
					(size 1 1)
					(thickness 0.15)
				)
			)
		)
		(property "Manufacturer" "Bourns"
			(at -0.74 293.88 0)
			(layer "F.Fab")
			(hide yes)
			(effects
				(font
					(size 1 1)
					(thickness 0.15)
				)
			)
		)
		(property "Tolerance" "1%"
			(at -0.74 293.88 0)
			(layer "F.Fab")
			(hide yes)
			(effects
				(font
					(size 1 1)
					(thickness 0.15)
				)
			)
		)
		(property "Val" "0R"
			(at -0.74 293.88 0)
			(layer "F.Fab")
			(hide yes)
			(effects
				(font
					(size 1 1)
					(thickness 0.15)
				)
			)
		)
		(sheetname "KR to SFI #1")
		(sheetfile "kr_sfi.kicad_sch")
		(attr smd)
		(fp_rect
			(start -0.7 -0.35)
			(end 0.7 0.35)
			(stroke
				(width 0.05)
				(type default)
			)
			(fill no)
			(layer "F.CrtYd")
		)
		(fp_rect
			(start -0.3 -0.15)
			(end 0.298 0.148)
			(stroke
				(width 0.15)
				(type solid)
			)
			(fill no)
			(layer "F.Fab")
		)
		(pad "" smd roundrect
			(at -0.346 0 270)
			(size 0.318 0.36)
			(layers "F.Paste")
			(roundrect_rratio 0.25)
			(teardrops
				(best_length_ratio 0.2)
				(max_length 1)
				(best_width_ratio 0.9)
				(max_width 2)
				(curved_edges yes)
				(filter_ratio 0.9)
				(enabled yes)
				(allow_two_segments yes)
				(prefer_zone_connections yes)
			)
		)
		(pad "" smd roundrect
			(at 0.344 0 270)
			(size 0.318 0.36)
			(layers "F.Paste")
			(roundrect_rratio 0.25)
			(teardrops
				(best_length_ratio 0.2)
				(max_length 1)
				(best_width_ratio 0.9)
				(max_width 2)
				(curved_edges yes)
				(filter_ratio 0.9)
				(enabled yes)
				(allow_two_segments yes)
				(prefer_zone_connections yes)
			)
		)
		(pad "1" smd roundrect
			(at -0.32 0 270)
			(size 0.46 0.4)
			(layers "F.Cu" "F.Mask")
			(roundrect_rratio 0.25)
			(net 685 "/2xSFP+/KR to SFI #1/SFI_R.TX-")
			(pintype "passive")
			(teardrops
				(best_length_ratio 0.2)
				(max_length 1)
				(best_width_ratio 0.9)
				(max_width 2)
				(curved_edges yes)
				(filter_ratio 0.9)
				(enabled yes)
				(allow_two_segments yes)
				(prefer_zone_connections yes)
			)
		)
		(pad "2" smd roundrect
			(at 0.32 0 270)
			(size 0.46 0.4)
			(layers "F.Cu" "F.Mask")
			(roundrect_rratio 0.25)
			(net 173 "/2xSFP+/SFI0.TX-")
			(pintype "passive")
			(teardrops
				(best_length_ratio 0.2)
				(max_length 1)
				(best_width_ratio 0.9)
				(max_width 2)
				(curved_edges yes)
				(filter_ratio 0.9)
				(enabled yes)
				(allow_two_segments yes)
				(prefer_zone_connections yes)
			)
		)
	)
	(footprint "antmicro-footprints:TP_SMD_0.75mm"
		(layer "F.Cu")
		(at 150.5 128.71)
		(property "Reference" "TP73"
			(at 0.4 -3.3 90)
			(layer "F.SilkS")
			(effects
				(font
					(size 0.7 0.7)
					(thickness 0.15)
				)
				(justify left bottom)
			)
		)
		(property "Value" "TP_0.75mm_SMD"
			(at 0 1.2 0)
			(layer "F.Fab")
			(effects
				(font
					(size 0.7 0.7)
					(thickness 0.15)
				)
				(justify left bottom)
			)
		)
		(property "Author" "Antmicro"
			(at 0 0 0)
			(layer "F.Fab")
			(hide yes)
			(effects
				(font
					(size 1 1)
					(thickness 0.15)
				)
			)
		)
		(property "License" "Apache-2.0"
			(at 0 0 0)
			(layer "F.Fab")
			(hide yes)
			(effects
				(font
					(size 1 1)
					(thickness 0.15)
				)
			)
		)
		(property "MPN" ""
			(at 0 0 0)
			(layer "F.Fab")
			(hide yes)
			(effects
				(font
					(size 1 1)
					(thickness 0.15)
				)
			)
		)
		(property "Manufacturer" ""
			(at 0 0 0)
			(layer "F.Fab")
			(hide yes)
			(effects
				(font
					(size 1 1)
					(thickness 0.15)
				)
			)
		)
		(property "Public" "False"
			(at 0 0 0)
			(layer "F.Fab")
			(hide yes)
			(effects
				(font
					(size 1 1)
					(thickness 0.15)
				)
			)
		)
		(sheetname "KR to SFI #1")
		(sheetfile "kr_sfi.kicad_sch")
		(attr exclude_from_pos_files exclude_from_bom)
		(fp_circle
			(center 0 0)
			(end 0.475 0)
			(stroke
				(width 0.05)
				(type default)
			)
			(fill no)
			(layer "F.CrtYd")
		)
		(pad "1" smd circle
			(at 0 0)
			(size 0.75 0.75)
			(layers "F.Cu" "F.Mask")
			(net 736 "Net-(U43A-LS_OK_{OUT_A})")
			(pinfunction "1")
			(pintype "passive")
			(teardrops
				(best_length_ratio 0.4)
				(max_length 1)
				(best_width_ratio 0.9)
				(max_width 2)
				(curved_edges yes)
				(filter_ratio 0.9)
				(enabled yes)
				(allow_two_segments yes)
				(prefer_zone_connections yes)
			)
		)
	)
	(footprint "antmicro-footprints:C_0402_1005Metric"
		(layer "F.Cu")
		(at 192.841616 135.194859 135)
		(descr "Capacitor SMD 0402")
		(tags "capacitor SMD 0402")
		(property "Reference" "C134"
			(at 3.844168 0.249781 135)
			(layer "F.SilkS")
			(effects
				(font
					(size 0.7 0.7)
					(thickness 0.15)
				)
				(justify left top)
			)
		)
		(property "Value" "C_100n_0402"
			(at -1.022927 2.155213 135)
			(layer "F.Fab")
			(effects
				(font
					(size 0.7 0.7)
					(thickness 0.15)
				)
				(justify left top)
			)
		)
		(property "Datasheet" "https://www.murata.com/products/productdetail?partno=GRM155R61H104KE14%23"
			(at 0 0 135)
			(layer "B.Fab")
			(hide yes)
			(effects
				(font
					(size 1.27 1.27)
					(thickness 0.15)
				)
				(justify mirror)
			)
		)
		(property "Author" "Antmicro"
			(at 323.514 54.788 45)
			(layer "F.Fab")
			(hide yes)
			(effects
				(font
					(size 1 1)
					(thickness 0.15)
				)
			)
		)
		(property "Dielectric" "X5R"
			(at 323.514 54.788 45)
			(layer "F.Fab")
			(hide yes)
			(effects
				(font
					(size 1 1)
					(thickness 0.15)
				)
			)
		)
		(property "License" "Apache-2.0"
			(at 323.514 54.788 45)
			(layer "F.Fab")
			(hide yes)
			(effects
				(font
					(size 1 1)
					(thickness 0.15)
				)
			)
		)
		(property "MPN" "GRM155R61H104KE14D"
			(at 323.514 54.788 45)
			(layer "F.Fab")
			(hide yes)
			(effects
				(font
					(size 1 1)
					(thickness 0.15)
				)
			)
		)
		(property "Manufacturer" "Murata"
			(at 323.514 54.788 45)
			(layer "F.Fab")
			(hide yes)
			(effects
				(font
					(size 1 1)
					(thickness 0.15)
				)
			)
		)
		(property "Public" "False"
			(at 323.514 54.788 45)
			(layer "F.Fab")
			(hide yes)
			(effects
				(font
					(size 1 1)
					(thickness 0.15)
				)
			)
		)
		(property "Val" "100n"
			(at 323.514 54.788 45)
			(layer "F.Fab")
			(hide yes)
			(effects
				(font
					(size 1 1)
					(thickness 0.15)
				)
			)
		)
		(property "Voltage" "50V"
			(at 323.514 54.788 45)
			(layer "F.Fab")
			(hide yes)
			(effects
				(font
					(size 1 1)
					(thickness 0.15)
				)
			)
		)
		(sheetname "PCIe redriver")
		(sheetfile "pcie_redriver.kicad_sch")
		(attr smd)
		(fp_poly
			(pts
				(xy -0.925 -0.47) (xy 0.925 -0.47) (xy 0.925 0.47) (xy -0.925 0.47)
			)
			(stroke
				(width 0.05)
				(type default)
			)
			(fill no)
			(layer "F.CrtYd")
		)
		(fp_line
			(start 0.504 -0.25)
			(end 0.504 0.248)
			(stroke
				(width 0.15)
				(type solid)
			)
			(layer "F.Fab")
		)
		(fp_line
			(start 0.504 0.248)
			(end -0.494 0.248)
			(stroke
				(width 0.15)
				(type solid)
			)
			(layer "F.Fab")
		)
		(fp_line
			(start -0.494 -0.25)
			(end 0.504 -0.25)
			(stroke
				(width 0.15)
				(type solid)
			)
			(layer "F.Fab")
		)
		(fp_line
			(start -0.494 0.248)
			(end -0.494 -0.25)
			(stroke
				(width 0.15)
				(type solid)
			)
			(layer "F.Fab")
		)
		(pad "1" smd roundrect
			(at -0.48 0 135)
			(size 0.59 0.64)
			(layers "F.Cu" "F.Mask" "F.Paste")
			(roundrect_rratio 0.25)
			(net 1 "GND")
			(pintype "passive")
			(teardrops
				(best_length_ratio 0.2)
				(max_length 1)
				(best_width_ratio 0.9)
				(max_width 2)
				(curved_edges yes)
				(filter_ratio 0.9)
				(enabled yes)
				(allow_two_segments yes)
				(prefer_zone_connections yes)
			)
		)
		(pad "2" smd roundrect
			(at 0.48 0 135)
			(size 0.59 0.64)
			(layers "F.Cu" "F.Mask" "F.Paste")
			(roundrect_rratio 0.25)
			(net 2 "+3V3")
			(pintype "passive")
			(teardrops
				(best_length_ratio 0.2)
				(max_length 1)
				(best_width_ratio 0.9)
				(max_width 2)
				(curved_edges yes)
				(filter_ratio 0.9)
				(enabled yes)
				(allow_two_segments yes)
				(prefer_zone_connections yes)
			)
		)
	)
	(footprint "antmicro-footprints:R_0402_1005Metric"
		(layer "F.Cu")
		(at 136.6 109.22 180)
		(descr "Resistor SMD 0402")
		(tags "resistor SMD 0402")
		(property "Reference" "R16"
			(at -1.1 -1.4 0)
			(layer "F.SilkS")
			(effects
				(font
					(size 0.7 0.7)
					(thickness 0.15)
				)
				(justify right bottom)
			)
		)
		(property "Value" "R_75R_0402"
			(at -1.011843 1.772047 0)
			(layer "F.Fab")
			(effects
				(font
					(size 0.7 0.7)
					(thickness 0.15)
				)
				(justify right bottom)
			)
		)
		(property "Datasheet" "https://www.bourns.com/docs/product-datasheets/cr.pdf"
			(at 0 0 180)
			(layer "F.Fab")
			(hide yes)
			(effects
				(font
					(size 1.27 1.27)
					(thickness 0.15)
				)
			)
		)
		(property "Author" "Antmicro"
			(at 273.2 218.44 0)
			(layer "F.Fab")
			(hide yes)
			(effects
				(font
					(size 1 1)
					(thickness 0.15)
				)
			)
		)
		(property "License" "Apache-2.0"
			(at 273.2 218.44 0)
			(layer "F.Fab")
			(hide yes)
			(effects
				(font
					(size 1 1)
					(thickness 0.15)
				)
			)
		)
		(property "MPN" "CR0402-FX-75R0GLF"
			(at 273.2 218.44 0)
			(layer "F.Fab")
			(hide yes)
			(effects
				(font
					(size 1 1)
					(thickness 0.15)
				)
			)
		)
		(property "Manufacturer" "Bourns"
			(at 273.2 218.44 0)
			(layer "F.Fab")
			(hide yes)
			(effects
				(font
					(size 1 1)
					(thickness 0.15)
				)
			)
		)
		(property "Public" "False"
			(at 273.2 218.44 0)
			(layer "F.Fab")
			(hide yes)
			(effects
				(font
					(size 1 1)
					(thickness 0.15)
				)
			)
		)
		(property "Tolerance" "1%"
			(at 273.2 218.44 0)
			(layer "F.Fab")
			(hide yes)
			(effects
				(font
					(size 1 1)
					(thickness 0.15)
				)
			)
		)
		(property "Val" "75R"
			(at 273.2 218.44 0)
			(layer "F.Fab")
			(hide yes)
			(effects
				(font
					(size 1 1)
					(thickness 0.15)
				)
			)
		)
		(sheetname "2xUSB3.0+RJ45")
		(sheetfile "usb3+rj45.kicad_sch")
		(attr smd)
		(fp_rect
			(start -0.925 -0.47)
			(end 0.925 0.47)
			(stroke
				(width 0.05)
				(type default)
			)
			(fill no)
			(layer "F.CrtYd")
		)
		(fp_rect
			(start -0.5 -0.25)
			(end 0.5 0.25)
			(stroke
				(width 0.15)
				(type solid)
			)
			(fill no)
			(layer "F.Fab")
		)
		(pad "1" smd roundrect
			(at -0.48 0 180)
			(size 0.59 0.64)
			(layers "F.Cu" "F.Mask" "F.Paste")
			(roundrect_rratio 0.25)
			(net 50 "Net-(C12-Pad2)")
			(pintype "passive")
			(teardrops
				(best_length_ratio 0.2)
				(max_length 1)
				(best_width_ratio 0.9)
				(max_width 2)
				(curved_edges yes)
				(filter_ratio 0.9)
				(enabled yes)
				(allow_two_segments yes)
				(prefer_zone_connections yes)
			)
		)
		(pad "2" smd roundrect
			(at 0.48 0 180)
			(size 0.59 0.64)
			(layers "F.Cu" "F.Mask" "F.Paste")
			(roundrect_rratio 0.25)
			(net 551 "Net-(R16-Pad2)")
			(pintype "passive")
			(teardrops
				(best_length_ratio 0.2)
				(max_length 1)
				(best_width_ratio 0.9)
				(max_width 2)
				(curved_edges yes)
				(filter_ratio 0.9)
				(enabled yes)
				(allow_two_segments yes)
				(prefer_zone_connections yes)
			)
		)
	)
	(footprint "antmicro-footprints:C_0402_1005Metric"
		(layer "F.Cu")
		(at 291.75 101.86)
		(descr "Capacitor SMD 0402")
		(tags "capacitor SMD 0402")
		(property "Reference" "C70"
			(at 0.8 0.45 0)
			(layer "F.SilkS")
			(effects
				(font
					(size 0.7 0.7)
					(thickness 0.15)
				)
				(justify left bottom)
			)
		)
		(property "Value" "C_1u_0402"
			(at -1.022927 2.155213 0)
			(layer "F.Fab")
			(effects
				(font
					(size 0.7 0.7)
					(thickness 0.15)
				)
				(justify left bottom)
			)
		)
		(property "Datasheet" "https://product.tdk.com/en/search/capacitor/ceramic/mlcc/info?part_no=C1005X6S1A105K050BC"
			(at 0 0 0)
			(layer "F.Fab")
			(hide yes)
			(effects
				(font
					(size 1.27 1.27)
					(thickness 0.15)
				)
			)
		)
		(property "Author" "Antmicro"
			(at 0 0 0)
			(layer "F.Fab")
			(hide yes)
			(effects
				(font
					(size 1 1)
					(thickness 0.15)
				)
			)
		)
		(property "Dielectric" ""
			(at 0 0 0)
			(layer "F.Fab")
			(hide yes)
			(effects
				(font
					(size 1 1)
					(thickness 0.15)
				)
			)
		)
		(property "License" "Apache-2.0"
			(at 0 0 0)
			(layer "F.Fab")
			(hide yes)
			(effects
				(font
					(size 1 1)
					(thickness 0.15)
				)
			)
		)
		(property "MPN" "C1005X6S1A105K050BC"
			(at 0 0 0)
			(layer "F.Fab")
			(hide yes)
			(effects
				(font
					(size 1 1)
					(thickness 0.15)
				)
			)
		)
		(property "Manufacturer" "TDK"
			(at 0 0 0)
			(layer "F.Fab")
			(hide yes)
			(effects
				(font
					(size 1 1)
					(thickness 0.15)
				)
			)
		)
		(property "Public" "False"
			(at 0 0 0)
			(layer "F.Fab")
			(hide yes)
			(effects
				(font
					(size 1 1)
					(thickness 0.15)
				)
			)
		)
		(property "Val" "1u"
			(at 0 0 0)
			(layer "F.Fab")
			(hide yes)
			(effects
				(font
					(size 1 1)
					(thickness 0.15)
				)
			)
		)
		(property "Voltage" ""
			(at 0 0 0)
			(layer "F.Fab")
			(hide yes)
			(effects
				(font
					(size 1 1)
					(thickness 0.15)
				)
			)
		)
		(sheetname "Power")
		(sheetfile "power.kicad_sch")
		(attr smd)
		(fp_rect
			(start -0.925 -0.47)
			(end 0.925 0.47)
			(stroke
				(width 0.05)
				(type default)
			)
			(fill no)
			(layer "F.CrtYd")
		)
		(fp_line
			(start -0.494 -0.25)
			(end 0.504 -0.25)
			(stroke
				(width 0.15)
				(type solid)
			)
			(layer "F.Fab")
		)
		(fp_line
			(start -0.494 0.248)
			(end -0.494 -0.25)
			(stroke
				(width 0.15)
				(type solid)
			)
			(layer "F.Fab")
		)
		(fp_line
			(start 0.504 -0.25)
			(end 0.504 0.248)
			(stroke
				(width 0.15)
				(type solid)
			)
			(layer "F.Fab")
		)
		(fp_line
			(start 0.504 0.248)
			(end -0.494 0.248)
			(stroke
				(width 0.15)
				(type solid)
			)
			(layer "F.Fab")
		)
		(pad "1" smd roundrect
			(at -0.48 0)
			(size 0.59 0.64)
			(layers "F.Cu" "F.Mask" "F.Paste")
			(roundrect_rratio 0.25)
			(net 1 "GND")
			(pintype "passive")
			(teardrops
				(best_length_ratio 0.2)
				(max_length 1)
				(best_width_ratio 0.9)
				(max_width 2)
				(curved_edges yes)
				(filter_ratio 0.9)
				(enabled yes)
				(allow_two_segments yes)
				(prefer_zone_connections yes)
			)
		)
		(pad "2" smd roundrect
			(at 0.48 0)
			(size 0.59 0.64)
			(layers "F.Cu" "F.Mask" "F.Paste")
			(roundrect_rratio 0.25)
			(net 52 "+5V")
			(pintype "passive")
			(teardrops
				(best_length_ratio 0.2)
				(max_length 1)
				(best_width_ratio 0.9)
				(max_width 2)
				(curved_edges yes)
				(filter_ratio 0.9)
				(enabled yes)
				(allow_two_segments yes)
				(prefer_zone_connections yes)
			)
		)
	)
	(footprint "antmicro-footprints:C_0402_1005Metric"
		(layer "F.Cu")
		(at 248.695708 75.76)
		(descr "Capacitor SMD 0402")
		(tags "capacitor SMD 0402")
		(property "Reference" "C91"
			(at -2.975 0.45 0)
			(layer "F.SilkS")
			(effects
				(font
					(size 0.7 0.7)
					(thickness 0.15)
				)
				(justify left bottom)
			)
		)
		(property "Value" "C_100n_0402"
			(at -1.022927 2.155213 0)
			(layer "F.Fab")
			(effects
				(font
					(size 0.7 0.7)
					(thickness 0.15)
				)
				(justify left bottom)
			)
		)
		(property "Datasheet" "https://www.murata.com/products/productdetail?partno=GRM155R61H104KE14%23"
			(at 0 0 0)
			(layer "F.Fab")
			(hide yes)
			(effects
				(font
					(size 1.27 1.27)
					(thickness 0.15)
				)
			)
		)
		(property "Author" "Antmicro"
			(at 0 0 0)
			(layer "F.Fab")
			(hide yes)
			(effects
				(font
					(size 1 1)
					(thickness 0.15)
				)
			)
		)
		(property "Dielectric" "X5R"
			(at 0 0 0)
			(layer "F.Fab")
			(hide yes)
			(effects
				(font
					(size 1 1)
					(thickness 0.15)
				)
			)
		)
		(property "License" "Apache-2.0"
			(at 0 0 0)
			(layer "F.Fab")
			(hide yes)
			(effects
				(font
					(size 1 1)
					(thickness 0.15)
				)
			)
		)
		(property "MPN" "GRM155R61H104KE14D"
			(at 0 0 0)
			(layer "F.Fab")
			(hide yes)
			(effects
				(font
					(size 1 1)
					(thickness 0.15)
				)
			)
		)
		(property "Manufacturer" "Murata"
			(at 0 0 0)
			(layer "F.Fab")
			(hide yes)
			(effects
				(font
					(size 1 1)
					(thickness 0.15)
				)
			)
		)
		(property "Public" "False"
			(at 0 0 0)
			(layer "F.Fab")
			(hide yes)
			(effects
				(font
					(size 1 1)
					(thickness 0.15)
				)
			)
		)
		(property "Val" "100n"
			(at 0 0 0)
			(layer "F.Fab")
			(hide yes)
			(effects
				(font
					(size 1 1)
					(thickness 0.15)
				)
			)
		)
		(property "Voltage" "50V"
			(at 0 0 0)
			(layer "F.Fab")
			(hide yes)
			(effects
				(font
					(size 1 1)
					(thickness 0.15)
				)
			)
		)
		(sheetname "Misc")
		(sheetfile "misc.kicad_sch")
		(attr smd)
		(fp_rect
			(start -0.925 -0.47)
			(end 0.925 0.47)
			(stroke
				(width 0.05)
				(type default)
			)
			(fill no)
			(layer "F.CrtYd")
		)
		(fp_line
			(start -0.494 -0.25)
			(end 0.504 -0.25)
			(stroke
				(width 0.15)
				(type solid)
			)
			(layer "F.Fab")
		)
		(fp_line
			(start -0.494 0.248)
			(end -0.494 -0.25)
			(stroke
				(width 0.15)
				(type solid)
			)
			(layer "F.Fab")
		)
		(fp_line
			(start 0.504 -0.25)
			(end 0.504 0.248)
			(stroke
				(width 0.15)
				(type solid)
			)
			(layer "F.Fab")
		)
		(fp_line
			(start 0.504 0.248)
			(end -0.494 0.248)
			(stroke
				(width 0.15)
				(type solid)
			)
			(layer "F.Fab")
		)
		(pad "1" smd roundrect
			(at -0.48 0)
			(size 0.59 0.64)
			(layers "F.Cu" "F.Mask" "F.Paste")
			(roundrect_rratio 0.25)
			(net 1 "GND")
			(pintype "passive")
			(teardrops
				(best_length_ratio 0.2)
				(max_length 1)
				(best_width_ratio 0.9)
				(max_width 2)
				(curved_edges yes)
				(filter_ratio 0.9)
				(enabled yes)
				(allow_two_segments yes)
				(prefer_zone_connections yes)
			)
		)
		(pad "2" smd roundrect
			(at 0.48 0)
			(size 0.59 0.64)
			(layers "F.Cu" "F.Mask" "F.Paste")
			(roundrect_rratio 0.25)
			(net 52 "+5V")
			(pintype "passive")
			(teardrops
				(best_length_ratio 0.2)
				(max_length 1)
				(best_width_ratio 0.9)
				(max_width 2)
				(curved_edges yes)
				(filter_ratio 0.9)
				(enabled yes)
				(allow_two_segments yes)
				(prefer_zone_connections yes)
			)
		)
	)
	(footprint "antmicro-footprints:R_0402_1005Metric"
		(layer "F.Cu")
		(at 309.174999 104.35 -90)
		(descr "Resistor SMD 0402")
		(tags "resistor SMD 0402")
		(property "Reference" "R100"
			(at -0.54 0.224999 45)
			(layer "F.SilkS")
			(effects
				(font
					(size 0.7 0.7)
					(thickness 0.15)
				)
				(justify right bottom)
			)
		)
		(property "Value" "R_15k_0402"
			(at -1.011843 1.772047 90)
			(layer "F.Fab")
			(effects
				(font
					(size 0.7 0.7)
					(thickness 0.15)
				)
				(justify right bottom)
			)
		)
		(property "Datasheet" "https://www.bourns.com/docs/product-datasheets/cr.pdf"
			(at 0 0 270)
			(layer "F.Fab")
			(hide yes)
			(effects
				(font
					(size 1.27 1.27)
					(thickness 0.15)
				)
			)
		)
		(property "Author" "Antmicro"
			(at 204.824999 413.524999 0)
			(layer "F.Fab")
			(hide yes)
			(effects
				(font
					(size 1 1)
					(thickness 0.15)
				)
			)
		)
		(property "License" "Apache-2.0"
			(at 204.824999 413.524999 0)
			(layer "F.Fab")
			(hide yes)
			(effects
				(font
					(size 1 1)
					(thickness 0.15)
				)
			)
		)
		(property "MPN" "CR0402-FX-1502GLF"
			(at 204.824999 413.524999 0)
			(layer "F.Fab")
			(hide yes)
			(effects
				(font
					(size 1 1)
					(thickness 0.15)
				)
			)
		)
		(property "Manufacturer" "Bourns"
			(at 204.824999 413.524999 0)
			(layer "F.Fab")
			(hide yes)
			(effects
				(font
					(size 1 1)
					(thickness 0.15)
				)
			)
		)
		(property "Public" "False"
			(at 204.824999 413.524999 0)
			(layer "F.Fab")
			(hide yes)
			(effects
				(font
					(size 1 1)
					(thickness 0.15)
				)
			)
		)
		(property "Tolerance" "1%"
			(at 204.824999 413.524999 0)
			(layer "F.Fab")
			(hide yes)
			(effects
				(font
					(size 1 1)
					(thickness 0.15)
				)
			)
		)
		(property "Val" "15k"
			(at 204.824999 413.524999 0)
			(layer "F.Fab")
			(hide yes)
			(effects
				(font
					(size 1 1)
					(thickness 0.15)
				)
			)
		)
		(sheetname "Power")
		(sheetfile "power.kicad_sch")
		(attr smd)
		(fp_rect
			(start -0.925 -0.47)
			(end 0.925 0.47)
			(stroke
				(width 0.05)
				(type default)
			)
			(fill no)
			(layer "F.CrtYd")
		)
		(fp_rect
			(start -0.5 -0.25)
			(end 0.5 0.25)
			(stroke
				(width 0.15)
				(type solid)
			)
			(fill no)
			(layer "F.Fab")
		)
		(pad "1" smd roundrect
			(at -0.48 0 270)
			(size 0.59 0.64)
			(layers "F.Cu" "F.Mask" "F.Paste")
			(roundrect_rratio 0.25)
			(net 1 "GND")
			(pintype "passive")
			(teardrops
				(best_length_ratio 0.2)
				(max_length 1)
				(best_width_ratio 0.9)
				(max_width 2)
				(curved_edges yes)
				(filter_ratio 0.9)
				(enabled yes)
				(allow_two_segments yes)
				(prefer_zone_connections yes)
			)
		)
		(pad "2" smd roundrect
			(at 0.48 0 270)
			(size 0.59 0.64)
			(layers "F.Cu" "F.Mask" "F.Paste")
			(roundrect_rratio 0.25)
			(net 581 "Net-(U19-FB)")
			(pintype "passive")
			(teardrops
				(best_length_ratio 0.2)
				(max_length 1)
				(best_width_ratio 0.9)
				(max_width 2)
				(curved_edges yes)
				(filter_ratio 0.9)
				(enabled yes)
				(allow_two_segments yes)
				(prefer_zone_connections yes)
			)
		)
	)
	(footprint "antmicro-footprints:Trans_Eth_4.7x3.3mm"
		(layer "F.Cu")
		(at 130.63 104.35)
		(property "Reference" "T6"
			(at 4.92 0.15 0)
			(unlocked yes)
			(layer "F.SilkS")
			(effects
				(font
					(size 0.7 0.7)
					(thickness 0.15)
				)
				(justify left bottom)
			)
		)
		(property "Value" "Trans_SM453229-381N7Y"
			(at 2.39 11.52 0)
			(unlocked yes)
			(layer "F.Fab")
			(effects
				(font
					(size 0.7 0.7)
					(thickness 0.15)
				)
				(justify left bottom)
			)
		)
		(property "Datasheet" "https://eu.mouser.com/datasheet/2/54/bourns_02132019_SM453229-381N7Y_datasheet-1532071.pdf"
			(at 0 0 0)
			(layer "F.Fab")
			(hide yes)
			(effects
				(font
					(size 1.27 1.27)
					(thickness 0.15)
				)
			)
		)
		(property "Author" "Antmicro"
			(at 0 0 0)
			(layer "F.Fab")
			(hide yes)
			(effects
				(font
					(size 1 1)
					(thickness 0.15)
				)
			)
		)
		(property "License" "Apache-2.0"
			(at 0 0 0)
			(layer "F.Fab")
			(hide yes)
			(effects
				(font
					(size 1 1)
					(thickness 0.15)
				)
			)
		)
		(property "MPN" "SM453229-381N7Y"
			(at 0 0 0)
			(layer "F.Fab")
			(hide yes)
			(effects
				(font
					(size 1 1)
					(thickness 0.15)
				)
			)
		)
		(property "Manufacturer" "Bourns"
			(at 0 0 0)
			(layer "F.Fab")
			(hide yes)
			(effects
				(font
					(size 1 1)
					(thickness 0.15)
				)
			)
		)
		(sheetname "2xUSB3.0+RJ45")
		(sheetfile "usb3+rj45.kicad_sch")
		(attr smd)
		(fp_line
			(start -0.15 -0.6)
			(end -0.15 0.55)
			(stroke
				(width 0.1)
				(type default)
			)
			(layer "F.SilkS")
		)
		(fp_line
			(start 3.4 -1.6)
			(end 1 -1.6)
			(stroke
				(width 0.1)
				(type default)
			)
			(layer "F.SilkS")
		)
		(fp_line
			(start 3.4 1.7)
			(end 1 1.7)
			(stroke
				(width 0.1)
				(type default)
			)
			(layer "F.SilkS")
		)
		(fp_line
			(start 4.55 -0.25)
			(end 4.55 0.9)
			(stroke
				(width 0.1)
				(type default)
			)
			(layer "F.SilkS")
		)
		(fp_circle
			(center 0.1 2.3)
			(end 0.15 2.3)
			(stroke
				(width 0.15)
				(type solid)
			)
			(fill yes)
			(layer "F.SilkS")
		)
		(fp_rect
			(start -0.6 -1.9)
			(end 4.94 1.9)
			(stroke
				(width 0.05)
				(type solid)
			)
			(fill no)
			(layer "F.CrtYd")
		)
		(pad "1" smd roundrect
			(at 0.17 1.5)
			(size 0.96 0.27)
			(layers "F.Cu" "F.Mask" "F.Paste")
			(roundrect_rratio 0.25)
			(net 691 "/2xUSB3.0+RJ45/DB_FL+")
			(pinfunction "1")
			(pintype "passive")
			(teardrops
				(best_length_ratio 0.2)
				(max_length 1)
				(best_width_ratio 0.9)
				(max_width 2)
				(curved_edges yes)
				(filter_ratio 0.9)
				(enabled yes)
				(allow_two_segments yes)
				(prefer_zone_connections yes)
			)
		)
		(pad "2" smd roundrect
			(at 0.115 0.855)
			(size 0.85 0.28)
			(layers "F.Cu" "F.Mask" "F.Paste")
			(roundrect_rratio 0.25)
			(net 692 "/2xUSB3.0+RJ45/DB_FL-")
			(pinfunction "2")
			(pintype "passive")
			(teardrops
				(best_length_ratio 0.2)
				(max_length 1)
				(best_width_ratio 0.9)
				(max_width 2)
				(curved_edges yes)
				(filter_ratio 0.9)
				(enabled yes)
				(allow_two_segments yes)
				(prefer_zone_connections yes)
			)
		)
		(pad "3" smd roundrect
			(at 0.14 -1.21)
			(size 0.9 0.77)
			(layers "F.Cu" "F.Mask" "F.Paste")
			(roundrect_rratio 0.1)
			(net 51 "Net-(C13-Pad1)")
			(pinfunction "3")
			(pintype "passive")
			(teardrops
				(best_length_ratio 0.2)
				(max_length 1)
				(best_width_ratio 0.9)
				(max_width 2)
				(curved_edges yes)
				(filter_ratio 0.9)
				(enabled yes)
				(allow_two_segments yes)
				(prefer_zone_connections yes)
			)
		)
		(pad "5" smd roundrect
			(at 4.215 1.385)
			(size 0.95 0.5)
			(layers "F.Cu" "F.Mask" "F.Paste")
			(roundrect_rratio 0.1)
			(net 550 "Net-(R15-Pad2)")
			(pinfunction "5")
			(pintype "passive")
			(teardrops
				(best_length_ratio 0.2)
				(max_length 1)
				(best_width_ratio 0.9)
				(max_width 2)
				(curved_edges yes)
				(filter_ratio 0.9)
				(enabled yes)
				(allow_two_segments yes)
				(prefer_zone_connections yes)
			)
		)
		(pad "6" smd roundrect
			(at 4.265 -0.645)
			(size 0.85 0.34)
			(layers "F.Cu" "F.Mask" "F.Paste")
			(roundrect_rratio 0.1)
			(net 293 "/2xUSB3.0+RJ45/GbE.MDI1+")
			(pinfunction "6")
			(pintype "passive")
			(teardrops
				(best_length_ratio 0.2)
				(max_length 1)
				(best_width_ratio 0.9)
				(max_width 2)
				(curved_edges yes)
				(filter_ratio 0.9)
				(enabled yes)
				(allow_two_segments yes)
				(prefer_zone_connections yes)
			)
		)
		(pad "7" smd roundrect
			(at 4.205 -1.43)
			(size 0.97 0.33)
			(layers "F.Cu" "F.Mask" "F.Paste")
			(roundrect_rratio 0.1)
			(net 292 "/2xUSB3.0+RJ45/GbE.MDI1-")
			(pinfunction "7")
			(pintype "passive")
			(teardrops
				(best_length_ratio 0.2)
				(max_length 1)
				(best_width_ratio 0.9)
				(max_width 2)
				(curved_edges yes)
				(filter_ratio 0.9)
				(enabled yes)
				(allow_two_segments yes)
				(prefer_zone_connections yes)
			)
		)
	)
	(footprint "antmicro-footprints:Trans_Eth_4.7x3.3mm"
		(layer "F.Cu")
		(at 130.63 108.27)
		(property "Reference" "T7"
			(at 4.92 0.3 0)
			(unlocked yes)
			(layer "F.SilkS")
			(effects
				(font
					(size 0.7 0.7)
					(thickness 0.15)
				)
				(justify left bottom)
			)
		)
		(property "Value" "Trans_SM453229-381N7Y"
			(at 2.39 11.52 0)
			(unlocked yes)
			(layer "F.Fab")
			(effects
				(font
					(size 0.7 0.7)
					(thickness 0.15)
				)
				(justify left bottom)
			)
		)
		(property "Datasheet" "https://eu.mouser.com/datasheet/2/54/bourns_02132019_SM453229-381N7Y_datasheet-1532071.pdf"
			(at 0 0 0)
			(layer "F.Fab")
			(hide yes)
			(effects
				(font
					(size 1.27 1.27)
					(thickness 0.15)
				)
			)
		)
		(property "Author" "Antmicro"
			(at 0 0 0)
			(layer "F.Fab")
			(hide yes)
			(effects
				(font
					(size 1 1)
					(thickness 0.15)
				)
			)
		)
		(property "License" "Apache-2.0"
			(at 0 0 0)
			(layer "F.Fab")
			(hide yes)
			(effects
				(font
					(size 1 1)
					(thickness 0.15)
				)
			)
		)
		(property "MPN" "SM453229-381N7Y"
			(at 0 0 0)
			(layer "F.Fab")
			(hide yes)
			(effects
				(font
					(size 1 1)
					(thickness 0.15)
				)
			)
		)
		(property "Manufacturer" "Bourns"
			(at 0 0 0)
			(layer "F.Fab")
			(hide yes)
			(effects
				(font
					(size 1 1)
					(thickness 0.15)
				)
			)
		)
		(sheetname "2xUSB3.0+RJ45")
		(sheetfile "usb3+rj45.kicad_sch")
		(attr smd)
		(fp_line
			(start -0.15 -0.6)
			(end -0.15 0.55)
			(stroke
				(width 0.1)
				(type default)
			)
			(layer "F.SilkS")
		)
		(fp_line
			(start 3.4 -1.6)
			(end 1 -1.6)
			(stroke
				(width 0.1)
				(type default)
			)
			(layer "F.SilkS")
		)
		(fp_line
			(start 3.4 1.7)
			(end 1 1.7)
			(stroke
				(width 0.1)
				(type default)
			)
			(layer "F.SilkS")
		)
		(fp_line
			(start 4.55 -0.25)
			(end 4.55 0.9)
			(stroke
				(width 0.1)
				(type default)
			)
			(layer "F.SilkS")
		)
		(fp_circle
			(center 0.1 2.3)
			(end 0.15 2.3)
			(stroke
				(width 0.15)
				(type solid)
			)
			(fill yes)
			(layer "F.SilkS")
		)
		(fp_rect
			(start -0.6 -1.9)
			(end 4.94 1.9)
			(stroke
				(width 0.05)
				(type solid)
			)
			(fill no)
			(layer "F.CrtYd")
		)
		(pad "1" smd roundrect
			(at 0.17 1.5)
			(size 0.96 0.27)
			(layers "F.Cu" "F.Mask" "F.Paste")
			(roundrect_rratio 0.25)
			(net 693 "/2xUSB3.0+RJ45/DC_FL+")
			(pinfunction "1")
			(pintype "passive")
			(teardrops
				(best_length_ratio 0.2)
				(max_length 1)
				(best_width_ratio 0.9)
				(max_width 2)
				(curved_edges yes)
				(filter_ratio 0.9)
				(enabled yes)
				(allow_two_segments yes)
				(prefer_zone_connections yes)
			)
		)
		(pad "2" smd roundrect
			(at 0.115 0.855)
			(size 0.85 0.28)
			(layers "F.Cu" "F.Mask" "F.Paste")
			(roundrect_rratio 0.25)
			(net 694 "/2xUSB3.0+RJ45/DC_FL-")
			(pinfunction "2")
			(pintype "passive")
			(teardrops
				(best_length_ratio 0.2)
				(max_length 1)
				(best_width_ratio 0.9)
				(max_width 2)
				(curved_edges yes)
				(filter_ratio 0.9)
				(enabled yes)
				(allow_two_segments yes)
				(prefer_zone_connections yes)
			)
		)
		(pad "3" smd roundrect
			(at 0.14 -1.21)
			(size 0.9 0.77)
			(layers "F.Cu" "F.Mask" "F.Paste")
			(roundrect_rratio 0.1)
			(net 51 "Net-(C13-Pad1)")
			(pinfunction "3")
			(pintype "passive")
			(teardrops
				(best_length_ratio 0.2)
				(max_length 1)
				(best_width_ratio 0.9)
				(max_width 2)
				(curved_edges yes)
				(filter_ratio 0.9)
				(enabled yes)
				(allow_two_segments yes)
				(prefer_zone_connections yes)
			)
		)
		(pad "5" smd roundrect
			(at 4.215 1.385)
			(size 0.95 0.5)
			(layers "F.Cu" "F.Mask" "F.Paste")
			(roundrect_rratio 0.1)
			(net 551 "Net-(R16-Pad2)")
			(pinfunction "5")
			(pintype "passive")
			(teardrops
				(best_length_ratio 0.2)
				(max_length 1)
				(best_width_ratio 0.9)
				(max_width 2)
				(curved_edges yes)
				(filter_ratio 0.9)
				(enabled yes)
				(allow_two_segments yes)
				(prefer_zone_connections yes)
			)
		)
		(pad "6" smd roundrect
			(at 4.265 -0.645)
			(size 0.85 0.34)
			(layers "F.Cu" "F.Mask" "F.Paste")
			(roundrect_rratio 0.1)
			(net 290 "/2xUSB3.0+RJ45/GbE.MDI2+")
			(pinfunction "6")
			(pintype "passive")
			(teardrops
				(best_length_ratio 0.2)
				(max_length 1)
				(best_width_ratio 0.9)
				(max_width 2)
				(curved_edges yes)
				(filter_ratio 0.9)
				(enabled yes)
				(allow_two_segments yes)
				(prefer_zone_connections yes)
			)
		)
		(pad "7" smd roundrect
			(at 4.205 -1.43)
			(size 0.97 0.33)
			(layers "F.Cu" "F.Mask" "F.Paste")
			(roundrect_rratio 0.1)
			(net 289 "/2xUSB3.0+RJ45/GbE.MDI2-")
			(pinfunction "7")
			(pintype "passive")
			(teardrops
				(best_length_ratio 0.2)
				(max_length 1)
				(best_width_ratio 0.9)
				(max_width 2)
				(curved_edges yes)
				(filter_ratio 0.9)
				(enabled yes)
				(allow_two_segments yes)
				(prefer_zone_connections yes)
			)
		)
	)
	(footprint "antmicro-footprints:TP_SMD_0.75mm"
		(layer "F.Cu")
		(at 118.234999 76.15 90)
		(property "Reference" "TP10"
			(at 4.54 6.315001 0)
			(layer "F.SilkS")
			(effects
				(font
					(size 0.7 0.7)
					(thickness 0.15)
				)
				(justify left bottom)
			)
		)
		(property "Value" "TP_0.75mm_SMD"
			(at 0 1.2 90)
			(layer "F.Fab")
			(effects
				(font
					(size 0.7 0.7)
					(thickness 0.15)
				)
				(justify left bottom)
			)
		)
		(property "Author" "Antmicro"
			(at 194.384999 -42.084999 0)
			(layer "F.Fab")
			(hide yes)
			(effects
				(font
					(size 1 1)
					(thickness 0.15)
				)
			)
		)
		(property "License" "Apache-2.0"
			(at 194.384999 -42.084999 0)
			(layer "F.Fab")
			(hide yes)
			(effects
				(font
					(size 1 1)
					(thickness 0.15)
				)
			)
		)
		(property "MPN" ""
			(at 194.384999 -42.084999 0)
			(layer "F.Fab")
			(hide yes)
			(effects
				(font
					(size 1 1)
					(thickness 0.15)
				)
			)
		)
		(property "Manufacturer" ""
			(at 194.384999 -42.084999 0)
			(layer "F.Fab")
			(hide yes)
			(effects
				(font
					(size 1 1)
					(thickness 0.15)
				)
			)
		)
		(property "Public" "False"
			(at 194.384999 -42.084999 0)
			(layer "F.Fab")
			(hide yes)
			(effects
				(font
					(size 1 1)
					(thickness 0.15)
				)
			)
		)
		(sheetname "USB-C console")
		(sheetfile "usb-c_console.kicad_sch")
		(attr exclude_from_pos_files exclude_from_bom)
		(fp_circle
			(center 0 0)
			(end 0.475 0)
			(stroke
				(width 0.05)
				(type default)
			)
			(fill no)
			(layer "F.CrtYd")
		)
		(pad "1" smd circle
			(at 0 0 90)
			(size 0.75 0.75)
			(layers "F.Cu" "F.Mask")
			(net 702 "/USB-C console/FTDI_CBUS3")
			(pinfunction "1")
			(pintype "passive")
			(teardrops
				(best_length_ratio 0.4)
				(max_length 1)
				(best_width_ratio 0.9)
				(max_width 2)
				(curved_edges yes)
				(filter_ratio 0.9)
				(enabled yes)
				(allow_two_segments yes)
				(prefer_zone_connections yes)
			)
		)
	)
	(footprint "antmicro-footprints:R_0402_1005Metric"
		(layer "F.Cu")
		(at 186.70861 77.152163 90)
		(descr "Resistor SMD 0402")
		(tags "resistor SMD 0402")
		(property "Reference" "R324"
			(at -1.9 -0.5 90)
			(layer "F.SilkS")
			(effects
				(font
					(size 0.7 0.7)
					(thickness 0.15)
				)
				(justify left bottom)
			)
		)
		(property "Value" "R_2k2_0402"
			(at -1.011843 1.772047 90)
			(layer "F.Fab")
			(effects
				(font
					(size 0.7 0.7)
					(thickness 0.15)
				)
				(justify left bottom)
			)
		)
		(property "Datasheet" "https://www.bourns.com/docs/product-datasheets/cr.pdf"
			(at 0 0 90)
			(layer "F.Fab")
			(hide yes)
			(effects
				(font
					(size 1.27 1.27)
					(thickness 0.15)
				)
			)
		)
		(property "Author" "Antmicro"
			(at 263.860773 -109.556447 0)
			(layer "F.Fab")
			(hide yes)
			(effects
				(font
					(size 1 1)
					(thickness 0.15)
				)
			)
		)
		(property "License" "Apache-2.0"
			(at 263.860773 -109.556447 0)
			(layer "F.Fab")
			(hide yes)
			(effects
				(font
					(size 1 1)
					(thickness 0.15)
				)
			)
		)
		(property "MPN" "CR0402-FX-2201GLF"
			(at 263.860773 -109.556447 0)
			(layer "F.Fab")
			(hide yes)
			(effects
				(font
					(size 1 1)
					(thickness 0.15)
				)
			)
		)
		(property "Manufacturer" "Bourns"
			(at 263.860773 -109.556447 0)
			(layer "F.Fab")
			(hide yes)
			(effects
				(font
					(size 1 1)
					(thickness 0.15)
				)
			)
		)
		(property "Tolerance" "1%"
			(at 263.860773 -109.556447 0)
			(layer "F.Fab")
			(hide yes)
			(effects
				(font
					(size 1 1)
					(thickness 0.15)
				)
			)
		)
		(property "Val" "2k2"
			(at 263.860773 -109.556447 0)
			(layer "F.Fab")
			(hide yes)
			(effects
				(font
					(size 1 1)
					(thickness 0.15)
				)
			)
		)
		(sheetname "Power")
		(sheetfile "power.kicad_sch")
		(attr smd)
		(fp_rect
			(start -0.925 -0.47)
			(end 0.925 0.47)
			(stroke
				(width 0.05)
				(type default)
			)
			(fill no)
			(layer "F.CrtYd")
		)
		(fp_rect
			(start -0.5 -0.25)
			(end 0.5 0.25)
			(stroke
				(width 0.15)
				(type solid)
			)
			(fill no)
			(layer "F.Fab")
		)
		(pad "1" smd roundrect
			(at -0.48 0 90)
			(size 0.59 0.64)
			(layers "F.Cu" "F.Mask" "F.Paste")
			(roundrect_rratio 0.25)
			(net 1 "GND")
			(pintype "passive")
			(teardrops
				(best_length_ratio 0.2)
				(max_length 1)
				(best_width_ratio 0.9)
				(max_width 2)
				(curved_edges yes)
				(filter_ratio 0.9)
				(enabled yes)
				(allow_two_segments yes)
				(prefer_zone_connections yes)
			)
		)
		(pad "2" smd roundrect
			(at 0.48 0 90)
			(size 0.59 0.64)
			(layers "F.Cu" "F.Mask" "F.Paste")
			(roundrect_rratio 0.25)
			(net 983 "Net-(D31-C)")
			(pintype "passive")
			(teardrops
				(best_length_ratio 0.2)
				(max_length 1)
				(best_width_ratio 0.9)
				(max_width 2)
				(curved_edges yes)
				(filter_ratio 0.9)
				(enabled yes)
				(allow_two_segments yes)
				(prefer_zone_connections yes)
			)
		)
	)
	(footprint "antmicro-footprints:R_0402_1005Metric"
		(layer "F.Cu")
		(at 261.35 94.337)
		(descr "Resistor SMD 0402")
		(tags "resistor SMD 0402")
		(property "Reference" "R144"
			(at -1.45 1.423 0)
			(layer "F.SilkS")
			(effects
				(font
					(size 0.7 0.7)
					(thickness 0.15)
				)
				(justify left bottom)
			)
		)
		(property "Value" "R_100k_0402"
			(at -1.011843 1.772047 0)
			(layer "F.Fab")
			(effects
				(font
					(size 0.7 0.7)
					(thickness 0.15)
				)
				(justify left bottom)
			)
		)
		(property "Datasheet" "https://www.bourns.com/docs/product-datasheets/cr.pdf"
			(at 0 0 0)
			(layer "F.Fab")
			(hide yes)
			(effects
				(font
					(size 1.27 1.27)
					(thickness 0.15)
				)
			)
		)
		(property "Author" "Antmicro"
			(at 0 0 0)
			(layer "F.Fab")
			(hide yes)
			(effects
				(font
					(size 1 1)
					(thickness 0.15)
				)
			)
		)
		(property "License" "Apache-2.0"
			(at 0 0 0)
			(layer "F.Fab")
			(hide yes)
			(effects
				(font
					(size 1 1)
					(thickness 0.15)
				)
			)
		)
		(property "MPN" "CR0402-FX-1003GLF"
			(at 0 0 0)
			(layer "F.Fab")
			(hide yes)
			(effects
				(font
					(size 1 1)
					(thickness 0.15)
				)
			)
		)
		(property "Manufacturer" "Bourns"
			(at 0 0 0)
			(layer "F.Fab")
			(hide yes)
			(effects
				(font
					(size 1 1)
					(thickness 0.15)
				)
			)
		)
		(property "Public" "False"
			(at 0 0 0)
			(layer "F.Fab")
			(hide yes)
			(effects
				(font
					(size 1 1)
					(thickness 0.15)
				)
			)
		)
		(property "Tolerance" "1%"
			(at 0 0 0)
			(layer "F.Fab")
			(hide yes)
			(effects
				(font
					(size 1 1)
					(thickness 0.15)
				)
			)
		)
		(property "Val" "100k"
			(at 0 0 0)
			(layer "F.Fab")
			(hide yes)
			(effects
				(font
					(size 1 1)
					(thickness 0.15)
				)
			)
		)
		(sheetname "Misc")
		(sheetfile "misc.kicad_sch")
		(attr smd)
		(fp_rect
			(start -0.925 -0.47)
			(end 0.925 0.47)
			(stroke
				(width 0.05)
				(type default)
			)
			(fill no)
			(layer "F.CrtYd")
		)
		(fp_rect
			(start -0.5 -0.25)
			(end 0.5 0.25)
			(stroke
				(width 0.15)
				(type solid)
			)
			(fill no)
			(layer "F.Fab")
		)
		(pad "1" smd roundrect
			(at -0.48 0)
			(size 0.59 0.64)
			(layers "F.Cu" "F.Mask" "F.Paste")
			(roundrect_rratio 0.25)
			(net 538 "Net-(Q5-D)")
			(pintype "passive")
			(teardrops
				(best_length_ratio 0.2)
				(max_length 1)
				(best_width_ratio 0.9)
				(max_width 2)
				(curved_edges yes)
				(filter_ratio 0.9)
				(enabled yes)
				(allow_two_segments yes)
				(prefer_zone_connections yes)
			)
		)
		(pad "2" smd roundrect
			(at 0.48 0)
			(size 0.59 0.64)
			(layers "F.Cu" "F.Mask" "F.Paste")
			(roundrect_rratio 0.25)
			(net 2 "+3V3")
			(pintype "passive")
			(teardrops
				(best_length_ratio 0.2)
				(max_length 1)
				(best_width_ratio 0.9)
				(max_width 2)
				(curved_edges yes)
				(filter_ratio 0.9)
				(enabled yes)
				(allow_two_segments yes)
				(prefer_zone_connections yes)
			)
		)
	)
	(footprint "antmicro-footprints:R_0201"
		(layer "F.Cu")
		(at 135.17 147.31 90)
		(descr "Resistor SMD 0201")
		(tags "resistor SMD 0201")
		(property "Reference" "R290"
			(at -4.099 0.58 90)
			(layer "F.SilkS")
			(effects
				(font
					(size 0.7 0.7)
					(thickness 0.15)
				)
				(justify left bottom)
			)
		)
		(property "Value" "R_0R_0201"
			(at 0 1.25 90)
			(layer "F.Fab")
			(effects
				(font
					(size 0.7 0.7)
					(thickness 0.15)
				)
				(justify left bottom)
			)
		)
		(property "Datasheet" "https://www.bourns.com/docs/product-datasheets/cr.pdf"
			(at 0 0 90)
			(layer "F.Fab")
			(hide yes)
			(effects
				(font
					(size 1.27 1.27)
					(thickness 0.15)
				)
			)
		)
		(property "Author" "Antmicro"
			(at 282.48 12.14 0)
			(layer "F.Fab")
			(hide yes)
			(effects
				(font
					(size 1 1)
					(thickness 0.15)
				)
			)
		)
		(property "License" "Apache-2.0"
			(at 282.48 12.14 0)
			(layer "F.Fab")
			(hide yes)
			(effects
				(font
					(size 1 1)
					(thickness 0.15)
				)
			)
		)
		(property "MPN" "CR0201-FX-0R00GLF"
			(at 282.48 12.14 0)
			(layer "F.Fab")
			(hide yes)
			(effects
				(font
					(size 1 1)
					(thickness 0.15)
				)
			)
		)
		(property "Manufacturer" "Bourns"
			(at 282.48 12.14 0)
			(layer "F.Fab")
			(hide yes)
			(effects
				(font
					(size 1 1)
					(thickness 0.15)
				)
			)
		)
		(property "Tolerance" "1%"
			(at 282.48 12.14 0)
			(layer "F.Fab")
			(hide yes)
			(effects
				(font
					(size 1 1)
					(thickness 0.15)
				)
			)
		)
		(property "Val" "0R"
			(at 282.48 12.14 0)
			(layer "F.Fab")
			(hide yes)
			(effects
				(font
					(size 1 1)
					(thickness 0.15)
				)
			)
		)
		(sheetname "KR to SFI #2")
		(sheetfile "kr_sfi.kicad_sch")
		(attr smd)
		(fp_rect
			(start -0.7 -0.35)
			(end 0.7 0.35)
			(stroke
				(width 0.05)
				(type default)
			)
			(fill no)
			(layer "F.CrtYd")
		)
		(fp_rect
			(start -0.3 -0.15)
			(end 0.298 0.148)
			(stroke
				(width 0.15)
				(type solid)
			)
			(fill no)
			(layer "F.Fab")
		)
		(pad "" smd roundrect
			(at -0.346 0 90)
			(size 0.318 0.36)
			(layers "F.Paste")
			(roundrect_rratio 0.25)
			(teardrops
				(best_length_ratio 0.2)
				(max_length 1)
				(best_width_ratio 0.9)
				(max_width 2)
				(curved_edges yes)
				(filter_ratio 0.9)
				(enabled yes)
				(allow_two_segments yes)
				(prefer_zone_connections yes)
			)
		)
		(pad "" smd roundrect
			(at 0.344 0 90)
			(size 0.318 0.36)
			(layers "F.Paste")
			(roundrect_rratio 0.25)
			(teardrops
				(best_length_ratio 0.2)
				(max_length 1)
				(best_width_ratio 0.9)
				(max_width 2)
				(curved_edges yes)
				(filter_ratio 0.9)
				(enabled yes)
				(allow_two_segments yes)
				(prefer_zone_connections yes)
			)
		)
		(pad "1" smd roundrect
			(at -0.32 0 90)
			(size 0.46 0.4)
			(layers "F.Cu" "F.Mask")
			(roundrect_rratio 0.25)
			(net 427 "/2xSFP+/10GKR_SFP1.RX+")
			(pintype "passive")
			(teardrops
				(best_length_ratio 0.2)
				(max_length 1)
				(best_width_ratio 0.9)
				(max_width 2)
				(curved_edges yes)
				(filter_ratio 0.9)
				(enabled yes)
				(allow_two_segments yes)
				(prefer_zone_connections yes)
			)
		)
		(pad "2" smd roundrect
			(at 0.32 0 90)
			(size 0.46 0.4)
			(layers "F.Cu" "F.Mask")
			(roundrect_rratio 0.25)
			(net 687 "/2xSFP+/KR to SFI #2/KR_R.RX+")
			(pintype "passive")
			(teardrops
				(best_length_ratio 0.2)
				(max_length 1)
				(best_width_ratio 0.9)
				(max_width 2)
				(curved_edges yes)
				(filter_ratio 0.9)
				(enabled yes)
				(allow_two_segments yes)
				(prefer_zone_connections yes)
			)
		)
	)
	(footprint "antmicro-footprints:TP_SMD_0.75mm"
		(layer "F.Cu")
		(at 151.15 129.56)
		(property "Reference" "TP63"
			(at 0.45 -1.25 90)
			(layer "F.SilkS")
			(effects
				(font
					(size 0.7 0.7)
					(thickness 0.15)
				)
				(justify left bottom)
			)
		)
		(property "Value" "TP_0.75mm_SMD"
			(at 0 1.2 0)
			(layer "F.Fab")
			(effects
				(font
					(size 0.7 0.7)
					(thickness 0.15)
				)
				(justify left bottom)
			)
		)
		(property "Author" "Antmicro"
			(at 0 0 0)
			(layer "F.Fab")
			(hide yes)
			(effects
				(font
					(size 1 1)
					(thickness 0.15)
				)
			)
		)
		(property "License" "Apache-2.0"
			(at 0 0 0)
			(layer "F.Fab")
			(hide yes)
			(effects
				(font
					(size 1 1)
					(thickness 0.15)
				)
			)
		)
		(property "MPN" ""
			(at 0 0 0)
			(layer "F.Fab")
			(hide yes)
			(effects
				(font
					(size 1 1)
					(thickness 0.15)
				)
			)
		)
		(property "Manufacturer" ""
			(at 0 0 0)
			(layer "F.Fab")
			(hide yes)
			(effects
				(font
					(size 1 1)
					(thickness 0.15)
				)
			)
		)
		(property "Public" "False"
			(at 0 0 0)
			(layer "F.Fab")
			(hide yes)
			(effects
				(font
					(size 1 1)
					(thickness 0.15)
				)
			)
		)
		(sheetname "KR to SFI #1")
		(sheetfile "kr_sfi.kicad_sch")
		(attr exclude_from_pos_files exclude_from_bom)
		(fp_circle
			(center 0 0)
			(end 0.475 0)
			(stroke
				(width 0.05)
				(type default)
			)
			(fill no)
			(layer "F.CrtYd")
		)
		(pad "1" smd circle
			(at 0 0)
			(size 0.75 0.75)
			(layers "F.Cu" "F.Mask")
			(net 726 "/2xSFP+/KR to SFI #1/~{TRST}")
			(pinfunction "1")
			(pintype "passive")
			(teardrops
				(best_length_ratio 0.4)
				(max_length 1)
				(best_width_ratio 0.9)
				(max_width 2)
				(curved_edges yes)
				(filter_ratio 0.9)
				(enabled yes)
				(allow_two_segments yes)
				(prefer_zone_connections yes)
			)
		)
	)
	(footprint "antmicro-footprints:Conn_Molex_KK_1x4_0470531000"
		(layer "F.Cu")
		(at 266.240708 71.86 180)
		(property "Reference" "J9"
			(at 7.92 -3.85 0)
			(layer "F.SilkS")
			(effects
				(font
					(size 0.7 0.7)
					(thickness 0.15)
				)
				(justify right bottom)
			)
		)
		(property "Value" "Molex_KK_1x4_0470531000"
			(at 0 4.7 0)
			(layer "F.Fab")
			(effects
				(font
					(size 0.7 0.7)
					(thickness 0.15)
				)
				(justify right bottom)
			)
		)
		(property "Datasheet" "https://tools.molex.com/pdm_docs/sd/470531000_sd.pdf"
			(at 0 0 180)
			(layer "F.Fab")
			(hide yes)
			(effects
				(font
					(size 1.27 1.27)
					(thickness 0.15)
				)
			)
		)
		(property "Author" "Antmicro"
			(at 532.481416 143.72 0)
			(layer "F.Fab")
			(hide yes)
			(effects
				(font
					(size 1 1)
					(thickness 0.15)
				)
			)
		)
		(property "License" "Apache-2.0"
			(at 532.481416 143.72 0)
			(layer "F.Fab")
			(hide yes)
			(effects
				(font
					(size 1 1)
					(thickness 0.15)
				)
			)
		)
		(property "MPN" "0470531000"
			(at 532.481416 143.72 0)
			(layer "F.Fab")
			(hide yes)
			(effects
				(font
					(size 1 1)
					(thickness 0.15)
				)
			)
		)
		(property "Manufacturer" "Molex"
			(at 532.481416 143.72 0)
			(layer "F.Fab")
			(hide yes)
			(effects
				(font
					(size 1 1)
					(thickness 0.15)
				)
			)
		)
		(sheetname "Misc")
		(sheetfile "misc.kicad_sch")
		(attr through_hole)
		(fp_line
			(start 8.95 3.4)
			(end -1.35 3.4)
			(stroke
				(width 0.15)
				(type solid)
			)
			(layer "F.SilkS")
		)
		(fp_line
			(start 8.95 -2.55)
			(end 8.95 3.4)
			(stroke
				(width 0.15)
				(type solid)
			)
			(layer "F.SilkS")
		)
		(fp_line
			(start 5.75 -2.55)
			(end 8.95 -2.55)
			(stroke
				(width 0.15)
				(type solid)
			)
			(layer "F.SilkS")
		)
		(fp_line
			(start 5.08 2.29)
			(end 5.08 3.3)
			(stroke
				(width 0.15)
				(type solid)
			)
			(layer "F.SilkS")
		)
		(fp_line
			(start 0 3.3)
			(end 0 2.29)
			(stroke
				(width 0.15)
				(type solid)
			)
			(layer "F.SilkS")
		)
		(fp_line
			(start 0 2.29)
			(end 5.08 2.29)
			(stroke
				(width 0.15)
				(type solid)
			)
			(layer "F.SilkS")
		)
		(fp_line
			(start -1.35 3.4)
			(end -1.35 -2.6)
			(stroke
				(width 0.15)
				(type solid)
			)
			(layer "F.SilkS")
		)
		(fp_line
			(start -1.35 -2.6)
			(end 4.4 -2.6)
			(stroke
				(width 0.15)
				(type solid)
			)
			(layer "F.SilkS")
		)
		(fp_circle
			(center 0 -3)
			(end 0.05 -3)
			(stroke
				(width 0.15)
				(type solid)
			)
			(fill yes)
			(layer "F.SilkS")
		)
		(fp_rect
			(start -1.54 -2.96)
			(end 9.16 3.55)
			(stroke
				(width 0.05)
				(type solid)
			)
			(fill no)
			(layer "F.CrtYd")
		)
		(fp_line
			(start 8.85 3.3)
			(end -1.2 3.3)
			(stroke
				(width 0.15)
				(type solid)
			)
			(layer "F.Fab")
		)
		(fp_line
			(start 8.85 -2.5)
			(end 8.85 3.3)
			(stroke
				(width 0.15)
				(type solid)
			)
			(layer "F.Fab")
		)
		(fp_line
			(start 5.75 -2.5)
			(end 8.85 -2.5)
			(stroke
				(width 0.15)
				(type solid)
			)
			(layer "F.Fab")
		)
		(fp_line
			(start 5.1 3.3)
			(end 5.1 2.3)
			(stroke
				(width 0.15)
				(type solid)
			)
			(layer "F.Fab")
		)
		(fp_line
			(start 5.1 2.3)
			(end 0 2.3)
			(stroke
				(width 0.15)
				(type solid)
			)
			(layer "F.Fab")
		)
		(fp_line
			(start 0 2.3)
			(end 0 3.3)
			(stroke
				(width 0.15)
				(type solid)
			)
			(layer "F.Fab")
		)
		(fp_line
			(start -1.2 3.3)
			(end -1.25 3.3)
			(stroke
				(width 0.15)
				(type solid)
			)
			(layer "F.Fab")
		)
		(fp_line
			(start -1.25 3.3)
			(end -1.25 -2.5)
			(stroke
				(width 0.15)
				(type solid)
			)
			(layer "F.Fab")
		)
		(fp_line
			(start -1.25 -2.5)
			(end 4.4 -2.5)
			(stroke
				(width 0.15)
				(type solid)
			)
			(layer "F.Fab")
		)
		(pad "" np_thru_hole circle
			(at 5.08 -2.16 270)
			(size 1.1 1.1)
			(drill 1.1)
			(layers "*.Cu" "*.Mask")
		)
		(pad "1" thru_hole rect
			(at 0 0 270)
			(size 2.03 1.73)
			(drill 1.02)
			(layers "*.Cu" "*.Mask")
			(remove_unused_layers no)
			(net 1 "GND")
			(pintype "passive")
			(teardrops
				(best_length_ratio 0.2)
				(max_length 1)
				(best_width_ratio 0.9)
				(max_width 2)
				(curved_edges yes)
				(filter_ratio 0.9)
				(enabled yes)
				(allow_two_segments yes)
				(prefer_zone_connections yes)
			)
		)
		(pad "2" thru_hole oval
			(at 2.54 0 270)
			(size 2.03 1.73)
			(drill 1.02)
			(layers "*.Cu" "*.Mask")
			(remove_unused_layers no)
			(net 81 "/Misc/FAN_12V")
			(pintype "passive")
			(teardrops
				(best_length_ratio 0.2)
				(max_length 1)
				(best_width_ratio 0.9)
				(max_width 2)
				(curved_edges yes)
				(filter_ratio 0.9)
				(enabled yes)
				(allow_two_segments yes)
				(prefer_zone_connections yes)
			)
		)
		(pad "3" thru_hole oval
			(at 5.08 0 270)
			(size 2.03 1.73)
			(drill 1.02)
			(layers "*.Cu" "*.Mask")
			(remove_unused_layers no)
			(net 279 "/Misc/TACH_{A5V}")
			(pintype "passive")
			(teardrops
				(best_length_ratio 0.2)
				(max_length 1)
				(best_width_ratio 0.9)
				(max_width 2)
				(curved_edges yes)
				(filter_ratio 0.9)
				(enabled yes)
				(allow_two_segments yes)
				(prefer_zone_connections yes)
			)
		)
		(pad "4" thru_hole oval
			(at 7.62 0 270)
			(size 2.03 1.73)
			(drill 1.02)
			(layers "*.Cu" "*.Mask")
			(remove_unused_layers no)
			(net 280 "/Misc/PWM_{A5V}")
			(pintype "passive")
			(teardrops
				(best_length_ratio 0.2)
				(max_length 1)
				(best_width_ratio 0.9)
				(max_width 2)
				(curved_edges yes)
				(filter_ratio 0.9)
				(enabled yes)
				(allow_two_segments yes)
				(prefer_zone_connections yes)
			)
		)
	)
	(footprint "antmicro-footprints:R_0402_1005Metric"
		(layer "F.Cu")
		(at 126.425 84.060001 180)
		(descr "Resistor SMD 0402")
		(tags "resistor SMD 0402")
		(property "Reference" "R239"
			(at -1.575 -6.4 0)
			(layer "F.SilkS")
			(effects
				(font
					(size 0.7 0.7)
					(thickness 0.15)
				)
				(justify right bottom)
			)
		)
		(property "Value" "R_0R_0402"
			(at -1.011843 1.772047 0)
			(layer "F.Fab")
			(effects
				(font
					(size 0.7 0.7)
					(thickness 0.15)
				)
				(justify right bottom)
			)
		)
		(property "Datasheet" "https://industrial.panasonic.com/cdbs/www-data/pdf/RDA0000/AOA0000C301.pdf"
			(at 0 0 180)
			(layer "F.Fab")
			(hide yes)
			(effects
				(font
					(size 1.27 1.27)
					(thickness 0.15)
				)
			)
		)
		(property "Author" "Antmicro"
			(at 252.85 168.120002 0)
			(layer "F.Fab")
			(hide yes)
			(effects
				(font
					(size 1 1)
					(thickness 0.15)
				)
			)
		)
		(property "Current" "1A"
			(at 252.85 168.120002 0)
			(layer "F.Fab")
			(hide yes)
			(effects
				(font
					(size 1 1)
					(thickness 0.15)
				)
			)
		)
		(property "License" "Apache-2.0"
			(at 252.85 168.120002 0)
			(layer "F.Fab")
			(hide yes)
			(effects
				(font
					(size 1 1)
					(thickness 0.15)
				)
			)
		)
		(property "MPN" "ERJ2GE0R00X"
			(at 252.85 168.120002 0)
			(layer "F.Fab")
			(hide yes)
			(effects
				(font
					(size 1 1)
					(thickness 0.15)
				)
			)
		)
		(property "Manufacturer" "Panasonic"
			(at 252.85 168.120002 0)
			(layer "F.Fab")
			(hide yes)
			(effects
				(font
					(size 1 1)
					(thickness 0.15)
				)
			)
		)
		(property "Public" "False"
			(at 252.85 168.120002 0)
			(layer "F.Fab")
			(hide yes)
			(effects
				(font
					(size 1 1)
					(thickness 0.15)
				)
			)
		)
		(property "Tolerance" ""
			(at 252.85 168.120002 0)
			(layer "F.Fab")
			(hide yes)
			(effects
				(font
					(size 1 1)
					(thickness 0.15)
				)
			)
		)
		(property "Val" "0R"
			(at 252.85 168.120002 0)
			(layer "F.Fab")
			(hide yes)
			(effects
				(font
					(size 1 1)
					(thickness 0.15)
				)
			)
		)
		(sheetname "GPIO expander")
		(sheetfile "gpio_exp.kicad_sch")
		(attr smd)
		(fp_rect
			(start -0.925 -0.47)
			(end 0.925 0.47)
			(stroke
				(width 0.05)
				(type default)
			)
			(fill no)
			(layer "F.CrtYd")
		)
		(fp_rect
			(start -0.5 -0.25)
			(end 0.5 0.25)
			(stroke
				(width 0.15)
				(type solid)
			)
			(fill no)
			(layer "F.Fab")
		)
		(pad "1" smd roundrect
			(at -0.48 0 180)
			(size 0.59 0.64)
			(layers "F.Cu" "F.Mask" "F.Paste")
			(roundrect_rratio 0.25)
			(net 640 "Net-(U41-IO0_1)")
			(pintype "passive")
			(teardrops
				(best_length_ratio 0.2)
				(max_length 1)
				(best_width_ratio 0.9)
				(max_width 2)
				(curved_edges yes)
				(filter_ratio 0.9)
				(enabled yes)
				(allow_two_segments yes)
				(prefer_zone_connections yes)
			)
		)
		(pad "2" smd roundrect
			(at 0.48 0 180)
			(size 0.59 0.64)
			(layers "F.Cu" "F.Mask" "F.Paste")
			(roundrect_rratio 0.25)
			(net 943 "/GPIO expander/GPIOEX1")
			(pintype "passive")
			(teardrops
				(best_length_ratio 0.2)
				(max_length 1)
				(best_width_ratio 0.9)
				(max_width 2)
				(curved_edges yes)
				(filter_ratio 0.9)
				(enabled yes)
				(allow_two_segments yes)
				(prefer_zone_connections yes)
			)
		)
	)
	(footprint "antmicro-footprints:R_0402_1005Metric"
		(layer "F.Cu")
		(at 163.1 160.36)
		(descr "Resistor SMD 0402")
		(tags "resistor SMD 0402")
		(property "Reference" "R31"
			(at 0.8 0.48 0)
			(layer "F.SilkS")
			(effects
				(font
					(size 0.7 0.7)
					(thickness 0.15)
				)
				(justify left bottom)
			)
		)
		(property "Value" "R_0R_0402"
			(at -1.011843 1.772047 0)
			(layer "F.Fab")
			(effects
				(font
					(size 0.7 0.7)
					(thickness 0.15)
				)
				(justify left bottom)
			)
		)
		(property "Datasheet" "https://industrial.panasonic.com/cdbs/www-data/pdf/RDA0000/AOA0000C301.pdf"
			(at 0 0 0)
			(layer "F.Fab")
			(hide yes)
			(effects
				(font
					(size 1.27 1.27)
					(thickness 0.15)
				)
			)
		)
		(property "Author" "Antmicro"
			(at 0 0 0)
			(layer "F.Fab")
			(hide yes)
			(effects
				(font
					(size 1 1)
					(thickness 0.15)
				)
			)
		)
		(property "Current" "1A"
			(at 0 0 0)
			(layer "F.Fab")
			(hide yes)
			(effects
				(font
					(size 1 1)
					(thickness 0.15)
				)
			)
		)
		(property "License" "Apache-2.0"
			(at 0 0 0)
			(layer "F.Fab")
			(hide yes)
			(effects
				(font
					(size 1 1)
					(thickness 0.15)
				)
			)
		)
		(property "MPN" "ERJ2GE0R00X"
			(at 0 0 0)
			(layer "F.Fab")
			(hide yes)
			(effects
				(font
					(size 1 1)
					(thickness 0.15)
				)
			)
		)
		(property "Manufacturer" "Panasonic"
			(at 0 0 0)
			(layer "F.Fab")
			(hide yes)
			(effects
				(font
					(size 1 1)
					(thickness 0.15)
				)
			)
		)
		(property "Public" "False"
			(at 0 0 0)
			(layer "F.Fab")
			(hide yes)
			(effects
				(font
					(size 1 1)
					(thickness 0.15)
				)
			)
		)
		(property "Tolerance" ""
			(at 0 0 0)
			(layer "F.Fab")
			(hide yes)
			(effects
				(font
					(size 1 1)
					(thickness 0.15)
				)
			)
		)
		(property "Val" "0R"
			(at 0 0 0)
			(layer "F.Fab")
			(hide yes)
			(effects
				(font
					(size 1 1)
					(thickness 0.15)
				)
			)
		)
		(sheetname "2xSFP+")
		(sheetfile "2xSFP+.kicad_sch")
		(attr smd)
		(fp_rect
			(start -0.925 -0.47)
			(end 0.925 0.47)
			(stroke
				(width 0.05)
				(type default)
			)
			(fill no)
			(layer "F.CrtYd")
		)
		(fp_rect
			(start -0.5 -0.25)
			(end 0.5 0.25)
			(stroke
				(width 0.15)
				(type solid)
			)
			(fill no)
			(layer "F.Fab")
		)
		(pad "1" smd roundrect
			(at -0.48 0)
			(size 0.59 0.64)
			(layers "F.Cu" "F.Mask" "F.Paste")
			(roundrect_rratio 0.25)
			(net 557 "Net-(U5-A0)")
			(pintype "passive")
			(teardrops
				(best_length_ratio 0.2)
				(max_length 1)
				(best_width_ratio 0.9)
				(max_width 2)
				(curved_edges yes)
				(filter_ratio 0.9)
				(enabled yes)
				(allow_two_segments yes)
				(prefer_zone_connections yes)
			)
		)
		(pad "2" smd roundrect
			(at 0.48 0)
			(size 0.59 0.64)
			(layers "F.Cu" "F.Mask" "F.Paste")
			(roundrect_rratio 0.25)
			(net 2 "+3V3")
			(pintype "passive")
			(teardrops
				(best_length_ratio 0.2)
				(max_length 1)
				(best_width_ratio 0.9)
				(max_width 2)
				(curved_edges yes)
				(filter_ratio 0.9)
				(enabled yes)
				(allow_two_segments yes)
				(prefer_zone_connections yes)
			)
		)
	)
	(footprint "antmicro-footprints:R_0402_1005Metric"
		(layer "F.Cu")
		(at 214.98 135 -90)
		(descr "Resistor SMD 0402")
		(tags "resistor SMD 0402")
		(property "Reference" "R197"
			(at 0.81 -0.42 90)
			(layer "F.SilkS")
			(effects
				(font
					(size 0.7 0.7)
					(thickness 0.15)
				)
				(justify right bottom)
			)
		)
		(property "Value" "R_0R_0402"
			(at -1.011843 1.772047 90)
			(layer "F.Fab")
			(effects
				(font
					(size 0.7 0.7)
					(thickness 0.15)
				)
				(justify right bottom)
			)
		)
		(property "Datasheet" "https://industrial.panasonic.com/cdbs/www-data/pdf/RDA0000/AOA0000C301.pdf"
			(at 0 0 270)
			(layer "F.Fab")
			(hide yes)
			(effects
				(font
					(size 1.27 1.27)
					(thickness 0.15)
				)
			)
		)
		(property "Author" "Antmicro"
			(at 79.98 349.98 0)
			(layer "F.Fab")
			(hide yes)
			(effects
				(font
					(size 1 1)
					(thickness 0.15)
				)
			)
		)
		(property "Current" "1A"
			(at 79.98 349.98 0)
			(layer "F.Fab")
			(hide yes)
			(effects
				(font
					(size 1 1)
					(thickness 0.15)
				)
			)
		)
		(property "License" "Apache-2.0"
			(at 79.98 349.98 0)
			(layer "F.Fab")
			(hide yes)
			(effects
				(font
					(size 1 1)
					(thickness 0.15)
				)
			)
		)
		(property "MPN" "ERJ2GE0R00X"
			(at 79.98 349.98 0)
			(layer "F.Fab")
			(hide yes)
			(effects
				(font
					(size 1 1)
					(thickness 0.15)
				)
			)
		)
		(property "Manufacturer" "Panasonic"
			(at 79.98 349.98 0)
			(layer "F.Fab")
			(hide yes)
			(effects
				(font
					(size 1 1)
					(thickness 0.15)
				)
			)
		)
		(property "Public" "False"
			(at 79.98 349.98 0)
			(layer "F.Fab")
			(hide yes)
			(effects
				(font
					(size 1 1)
					(thickness 0.15)
				)
			)
		)
		(property "Tolerance" ""
			(at 79.98 349.98 0)
			(layer "F.Fab")
			(hide yes)
			(effects
				(font
					(size 1 1)
					(thickness 0.15)
				)
			)
		)
		(property "Val" "0R"
			(at 79.98 349.98 0)
			(layer "F.Fab")
			(hide yes)
			(effects
				(font
					(size 1 1)
					(thickness 0.15)
				)
			)
		)
		(sheetname "PCIe misc")
		(sheetfile "pcie_misc.kicad_sch")
		(attr smd)
		(fp_rect
			(start -0.925 -0.47)
			(end 0.925 0.47)
			(stroke
				(width 0.05)
				(type default)
			)
			(fill no)
			(layer "F.CrtYd")
		)
		(fp_rect
			(start -0.5 -0.25)
			(end 0.5 0.25)
			(stroke
				(width 0.15)
				(type solid)
			)
			(fill no)
			(layer "F.Fab")
		)
		(pad "1" smd roundrect
			(at -0.48 0 270)
			(size 0.59 0.64)
			(layers "F.Cu" "F.Mask" "F.Paste")
			(roundrect_rratio 0.25)
			(net 616 "/PCIe misc/DIF2-")
			(pintype "passive")
			(teardrops
				(best_length_ratio 0.2)
				(max_length 1)
				(best_width_ratio 0.9)
				(max_width 2)
				(curved_edges yes)
				(filter_ratio 0.9)
				(enabled yes)
				(allow_two_segments yes)
				(prefer_zone_connections yes)
			)
		)
		(pad "2" smd roundrect
			(at 0.48 0 270)
			(size 0.59 0.64)
			(layers "F.Cu" "F.Mask" "F.Paste")
			(roundrect_rratio 0.25)
			(net 19 "/M.2 key E/PCIE_{REF}.CK+")
			(pintype "passive")
			(teardrops
				(best_length_ratio 0.2)
				(max_length 1)
				(best_width_ratio 0.9)
				(max_width 2)
				(curved_edges yes)
				(filter_ratio 0.9)
				(enabled yes)
				(allow_two_segments yes)
				(prefer_zone_connections yes)
			)
		)
	)
	(footprint "antmicro-footprints:R_0402_1005Metric"
		(layer "F.Cu")
		(at 216.98 133.12 -90)
		(descr "Resistor SMD 0402")
		(tags "resistor SMD 0402")
		(property "Reference" "R199"
			(at 2.44 -5.32 90)
			(layer "F.SilkS")
			(effects
				(font
					(size 0.7 0.7)
					(thickness 0.15)
				)
				(justify right bottom)
			)
		)
		(property "Value" "R_0R_0402"
			(at -1.011843 1.772047 90)
			(layer "F.Fab")
			(effects
				(font
					(size 0.7 0.7)
					(thickness 0.15)
				)
				(justify right bottom)
			)
		)
		(property "Datasheet" "https://industrial.panasonic.com/cdbs/www-data/pdf/RDA0000/AOA0000C301.pdf"
			(at 0 0 270)
			(layer "F.Fab")
			(hide yes)
			(effects
				(font
					(size 1.27 1.27)
					(thickness 0.15)
				)
			)
		)
		(property "Author" "Antmicro"
			(at 83.86 350.1 0)
			(layer "F.Fab")
			(hide yes)
			(effects
				(font
					(size 1 1)
					(thickness 0.15)
				)
			)
		)
		(property "Current" "1A"
			(at 83.86 350.1 0)
			(layer "F.Fab")
			(hide yes)
			(effects
				(font
					(size 1 1)
					(thickness 0.15)
				)
			)
		)
		(property "License" "Apache-2.0"
			(at 83.86 350.1 0)
			(layer "F.Fab")
			(hide yes)
			(effects
				(font
					(size 1 1)
					(thickness 0.15)
				)
			)
		)
		(property "MPN" "ERJ2GE0R00X"
			(at 83.86 350.1 0)
			(layer "F.Fab")
			(hide yes)
			(effects
				(font
					(size 1 1)
					(thickness 0.15)
				)
			)
		)
		(property "Manufacturer" "Panasonic"
			(at 83.86 350.1 0)
			(layer "F.Fab")
			(hide yes)
			(effects
				(font
					(size 1 1)
					(thickness 0.15)
				)
			)
		)
		(property "Public" "False"
			(at 83.86 350.1 0)
			(layer "F.Fab")
			(hide yes)
			(effects
				(font
					(size 1 1)
					(thickness 0.15)
				)
			)
		)
		(property "Tolerance" ""
			(at 83.86 350.1 0)
			(layer "F.Fab")
			(hide yes)
			(effects
				(font
					(size 1 1)
					(thickness 0.15)
				)
			)
		)
		(property "Val" "0R"
			(at 83.86 350.1 0)
			(layer "F.Fab")
			(hide yes)
			(effects
				(font
					(size 1 1)
					(thickness 0.15)
				)
			)
		)
		(sheetname "PCIe misc")
		(sheetfile "pcie_misc.kicad_sch")
		(attr smd)
		(fp_rect
			(start -0.925 -0.47)
			(end 0.925 0.47)
			(stroke
				(width 0.05)
				(type default)
			)
			(fill no)
			(layer "F.CrtYd")
		)
		(fp_rect
			(start -0.5 -0.25)
			(end 0.5 0.25)
			(stroke
				(width 0.15)
				(type solid)
			)
			(fill no)
			(layer "F.Fab")
		)
		(pad "1" smd roundrect
			(at -0.48 0 270)
			(size 0.59 0.64)
			(layers "F.Cu" "F.Mask" "F.Paste")
			(roundrect_rratio 0.25)
			(net 618 "/PCIe misc/DIF3-")
			(pintype "passive")
			(teardrops
				(best_length_ratio 0.2)
				(max_length 1)
				(best_width_ratio 0.9)
				(max_width 2)
				(curved_edges yes)
				(filter_ratio 0.9)
				(enabled yes)
				(allow_two_segments yes)
				(prefer_zone_connections yes)
			)
		)
		(pad "2" smd roundrect
			(at 0.48 0 270)
			(size 0.59 0.64)
			(layers "F.Cu" "F.Mask" "F.Paste")
			(roundrect_rratio 0.25)
			(net 205 "/Backplane/PCIe_{REF}.CK-")
			(pintype "passive")
			(teardrops
				(best_length_ratio 0.2)
				(max_length 1)
				(best_width_ratio 0.9)
				(max_width 2)
				(curved_edges yes)
				(filter_ratio 0.9)
				(enabled yes)
				(allow_two_segments yes)
				(prefer_zone_connections yes)
			)
		)
	)
	(footprint "antmicro-footprints:R_0402_1005Metric"
		(layer "F.Cu")
		(at 287.95 101.86 180)
		(descr "Resistor SMD 0402")
		(tags "resistor SMD 0402")
		(property "Reference" "R116"
			(at 0.8 -0.4 0)
			(layer "F.SilkS")
			(effects
				(font
					(size 0.7 0.7)
					(thickness 0.15)
				)
				(justify right bottom)
			)
		)
		(property "Value" "R_10k_0402"
			(at -1.011843 1.772047 0)
			(layer "F.Fab")
			(effects
				(font
					(size 0.7 0.7)
					(thickness 0.15)
				)
				(justify right bottom)
			)
		)
		(property "Datasheet" "https://www.bourns.com/docs/product-datasheets/cr.pdf"
			(at 0 0 180)
			(layer "F.Fab")
			(hide yes)
			(effects
				(font
					(size 1.27 1.27)
					(thickness 0.15)
				)
			)
		)
		(property "Author" "Antmicro"
			(at 575.9 203.72 0)
			(layer "F.Fab")
			(hide yes)
			(effects
				(font
					(size 1 1)
					(thickness 0.15)
				)
			)
		)
		(property "License" "Apache-2.0"
			(at 575.9 203.72 0)
			(layer "F.Fab")
			(hide yes)
			(effects
				(font
					(size 1 1)
					(thickness 0.15)
				)
			)
		)
		(property "MPN" "CR0402-FX-1002GLF"
			(at 575.9 203.72 0)
			(layer "F.Fab")
			(hide yes)
			(effects
				(font
					(size 1 1)
					(thickness 0.15)
				)
			)
		)
		(property "Manufacturer" "Bourns"
			(at 575.9 203.72 0)
			(layer "F.Fab")
			(hide yes)
			(effects
				(font
					(size 1 1)
					(thickness 0.15)
				)
			)
		)
		(property "Public" "False"
			(at 575.9 203.72 0)
			(layer "F.Fab")
			(hide yes)
			(effects
				(font
					(size 1 1)
					(thickness 0.15)
				)
			)
		)
		(property "Tolerance" "1%"
			(at 575.9 203.72 0)
			(layer "F.Fab")
			(hide yes)
			(effects
				(font
					(size 1 1)
					(thickness 0.15)
				)
			)
		)
		(property "Val" "10k"
			(at 575.9 203.72 0)
			(layer "F.Fab")
			(hide yes)
			(effects
				(font
					(size 1 1)
					(thickness 0.15)
				)
			)
		)
		(sheetname "Power")
		(sheetfile "power.kicad_sch")
		(attr smd)
		(fp_rect
			(start -0.925 -0.47)
			(end 0.925 0.47)
			(stroke
				(width 0.05)
				(type default)
			)
			(fill no)
			(layer "F.CrtYd")
		)
		(fp_rect
			(start -0.5 -0.25)
			(end 0.5 0.25)
			(stroke
				(width 0.15)
				(type solid)
			)
			(fill no)
			(layer "F.Fab")
		)
		(pad "1" smd roundrect
			(at -0.48 0 180)
			(size 0.59 0.64)
			(layers "F.Cu" "F.Mask" "F.Paste")
			(roundrect_rratio 0.25)
			(net 535 "Net-(Q3-G)")
			(pintype "passive")
			(teardrops
				(best_length_ratio 0.2)
				(max_length 1)
				(best_width_ratio 0.9)
				(max_width 2)
				(curved_edges yes)
				(filter_ratio 0.9)
				(enabled yes)
				(allow_two_segments yes)
				(prefer_zone_connections yes)
			)
		)
		(pad "2" smd roundrect
			(at 0.48 0 180)
			(size 0.59 0.64)
			(layers "F.Cu" "F.Mask" "F.Paste")
			(roundrect_rratio 0.25)
			(net 65 "+12V")
			(pintype "passive")
			(teardrops
				(best_length_ratio 0.2)
				(max_length 1)
				(best_width_ratio 0.9)
				(max_width 2)
				(curved_edges yes)
				(filter_ratio 0.9)
				(enabled yes)
				(allow_two_segments yes)
				(prefer_zone_connections yes)
			)
		)
	)
	(footprint "antmicro-footprints:C_0402_1005Metric"
		(layer "F.Cu")
		(at 159.55 156.81 -90)
		(descr "Capacitor SMD 0402")
		(tags "capacitor SMD 0402")
		(property "Reference" "C21"
			(at -3.013 -0.449 90)
			(layer "F.SilkS")
			(effects
				(font
					(size 0.7 0.7)
					(thickness 0.15)
				)
				(justify right bottom)
			)
		)
		(property "Value" "C_100n_0402"
			(at -1.022927 2.155213 90)
			(layer "F.Fab")
			(effects
				(font
					(size 0.7 0.7)
					(thickness 0.15)
				)
				(justify right bottom)
			)
		)
		(property "Datasheet" "https://www.murata.com/products/productdetail?partno=GRM155R61H104KE14%23"
			(at 0 0 270)
			(layer "F.Fab")
			(hide yes)
			(effects
				(font
					(size 1.27 1.27)
					(thickness 0.15)
				)
			)
		)
		(property "Author" "Antmicro"
			(at 2.74 316.36 0)
			(layer "F.Fab")
			(hide yes)
			(effects
				(font
					(size 1 1)
					(thickness 0.15)
				)
			)
		)
		(property "Dielectric" "X5R"
			(at 2.74 316.36 0)
			(layer "F.Fab")
			(hide yes)
			(effects
				(font
					(size 1 1)
					(thickness 0.15)
				)
			)
		)
		(property "License" "Apache-2.0"
			(at 2.74 316.36 0)
			(layer "F.Fab")
			(hide yes)
			(effects
				(font
					(size 1 1)
					(thickness 0.15)
				)
			)
		)
		(property "MPN" "GRM155R61H104KE14D"
			(at 2.74 316.36 0)
			(layer "F.Fab")
			(hide yes)
			(effects
				(font
					(size 1 1)
					(thickness 0.15)
				)
			)
		)
		(property "Manufacturer" "Murata"
			(at 2.74 316.36 0)
			(layer "F.Fab")
			(hide yes)
			(effects
				(font
					(size 1 1)
					(thickness 0.15)
				)
			)
		)
		(property "Public" "False"
			(at 2.74 316.36 0)
			(layer "F.Fab")
			(hide yes)
			(effects
				(font
					(size 1 1)
					(thickness 0.15)
				)
			)
		)
		(property "Val" "100n"
			(at 2.74 316.36 0)
			(layer "F.Fab")
			(hide yes)
			(effects
				(font
					(size 1 1)
					(thickness 0.15)
				)
			)
		)
		(property "Voltage" "50V"
			(at 2.74 316.36 0)
			(layer "F.Fab")
			(hide yes)
			(effects
				(font
					(size 1 1)
					(thickness 0.15)
				)
			)
		)
		(sheetname "2xSFP+")
		(sheetfile "2xSFP+.kicad_sch")
		(attr smd)
		(fp_rect
			(start -0.925 -0.47)
			(end 0.925 0.47)
			(stroke
				(width 0.05)
				(type default)
			)
			(fill no)
			(layer "F.CrtYd")
		)
		(fp_line
			(start -0.494 0.248)
			(end -0.494 -0.25)
			(stroke
				(width 0.15)
				(type solid)
			)
			(layer "F.Fab")
		)
		(fp_line
			(start 0.504 0.248)
			(end -0.494 0.248)
			(stroke
				(width 0.15)
				(type solid)
			)
			(layer "F.Fab")
		)
		(fp_line
			(start -0.494 -0.25)
			(end 0.504 -0.25)
			(stroke
				(width 0.15)
				(type solid)
			)
			(layer "F.Fab")
		)
		(fp_line
			(start 0.504 -0.25)
			(end 0.504 0.248)
			(stroke
				(width 0.15)
				(type solid)
			)
			(layer "F.Fab")
		)
		(pad "1" smd roundrect
			(at -0.48 0 270)
			(size 0.59 0.64)
			(layers "F.Cu" "F.Mask" "F.Paste")
			(roundrect_rratio 0.25)
			(net 1 "GND")
			(pintype "passive")
			(teardrops
				(best_length_ratio 0.2)
				(max_length 1)
				(best_width_ratio 0.9)
				(max_width 2)
				(curved_edges yes)
				(filter_ratio 0.9)
				(enabled yes)
				(allow_two_segments yes)
				(prefer_zone_connections yes)
			)
		)
		(pad "2" smd roundrect
			(at 0.48 0 270)
			(size 0.59 0.64)
			(layers "F.Cu" "F.Mask" "F.Paste")
			(roundrect_rratio 0.25)
			(net 2 "+3V3")
			(pintype "passive")
			(teardrops
				(best_length_ratio 0.2)
				(max_length 1)
				(best_width_ratio 0.9)
				(max_width 2)
				(curved_edges yes)
				(filter_ratio 0.9)
				(enabled yes)
				(allow_two_segments yes)
				(prefer_zone_connections yes)
			)
		)
	)
	(footprint "antmicro-footprints:C_0603_1608Metric"
		(layer "F.Cu")
		(at 219.3 159.9 180)
		(descr "Capacitor SMD 0603")
		(tags "capacitor 0603")
		(property "Reference" "C95"
			(at -3.42 0.39 0)
			(layer "F.SilkS")
			(effects
				(font
					(size 0.7 0.7)
					(thickness 0.15)
				)
				(justify right top)
			)
		)
		(property "Value" "C_22u_16V_0603"
			(at -54.09257 -1.454712 0)
			(layer "F.Fab")
			(hide yes)
			(effects
				(font
					(size 0.7 0.7)
					(thickness 0.15)
				)
				(justify right top)
			)
		)
		(property "Datasheet" "https://product.samsungsem.com/mlcc/CL10A226MO7JZN.do"
			(at 0 0 0)
			(layer "F.Fab")
			(hide yes)
			(effects
				(font
					(size 1.27 1.27)
					(thickness 0.15)
				)
			)
		)
		(property "Author" "Antmicro"
			(at 348.085 -28.515 90)
			(layer "F.Fab")
			(hide yes)
			(effects
				(font
					(size 1 1)
					(thickness 0.15)
				)
			)
		)
		(property "Dielectric" ""
			(at 348.085 -28.515 90)
			(layer "F.Fab")
			(hide yes)
			(effects
				(font
					(size 1 1)
					(thickness 0.15)
				)
			)
		)
		(property "License" "Apache-2.0"
			(at 348.085 -28.515 90)
			(layer "F.Fab")
			(hide yes)
			(effects
				(font
					(size 1 1)
					(thickness 0.15)
				)
			)
		)
		(property "MPN" "CL10A226MO7JZNC"
			(at 348.085 -28.515 90)
			(layer "F.Fab")
			(hide yes)
			(effects
				(font
					(size 1 1)
					(thickness 0.15)
				)
			)
		)
		(property "Manufacturer" "Samsung Electro-Mechanics"
			(at 348.085 -28.515 90)
			(layer "F.Fab")
			(hide yes)
			(effects
				(font
					(size 1 1)
					(thickness 0.15)
				)
			)
		)
		(property "Public" "False"
			(at 348.085 -28.515 90)
			(layer "F.Fab")
			(hide yes)
			(effects
				(font
					(size 1 1)
					(thickness 0.15)
				)
			)
		)
		(property "Val" "22u"
			(at 348.085 -28.515 90)
			(layer "F.Fab")
			(hide yes)
			(effects
				(font
					(size 1 1)
					(thickness 0.15)
				)
			)
		)
		(property "Voltage" "16V"
			(at 348.085 -28.515 90)
			(layer "F.Fab")
			(hide yes)
			(effects
				(font
					(size 1 1)
					(thickness 0.15)
				)
			)
		)
		(sheetname "Com Express 7 MGMT")
		(sheetfile "com_express_7_mgmt.kicad_sch")
		(attr smd)
		(fp_line
			(start -0.15 0.4)
			(end 0.15 0.4)
			(stroke
				(width 0.15)
				(type solid)
			)
			(layer "F.SilkS")
		)
		(fp_line
			(start -0.15 -0.4)
			(end 0.15 -0.4)
			(stroke
				(width 0.15)
				(type solid)
			)
			(layer "F.SilkS")
		)
		(fp_rect
			(start -1.25 -0.65)
			(end 1.25 0.65)
			(stroke
				(width 0.05)
				(type solid)
			)
			(fill no)
			(layer "F.CrtYd")
		)
		(fp_rect
			(start -0.8 -0.4)
			(end 0.8 0.4)
			(stroke
				(width 0.15)
				(type solid)
			)
			(fill no)
			(layer "F.Fab")
		)
		(pad "1" smd roundrect
			(at -0.7 0 180)
			(size 0.8 1)
			(layers "F.Cu" "F.Mask" "F.Paste")
			(roundrect_rratio 0.2)
			(net 1 "GND")
			(pintype "passive")
			(teardrops
				(best_length_ratio 0.2)
				(max_length 1)
				(best_width_ratio 0.9)
				(max_width 2)
				(curved_edges yes)
				(filter_ratio 0.9)
				(enabled yes)
				(allow_two_segments yes)
				(prefer_zone_connections yes)
			)
		)
		(pad "2" smd roundrect
			(at 0.7 0 180)
			(size 0.8 1)
			(layers "F.Cu" "F.Mask" "F.Paste")
			(roundrect_rratio 0.2)
			(net 77 "+5V_AON")
			(pintype "passive")
			(teardrops
				(best_length_ratio 0.2)
				(max_length 1)
				(best_width_ratio 0.9)
				(max_width 2)
				(curved_edges yes)
				(filter_ratio 0.9)
				(enabled yes)
				(allow_two_segments yes)
				(prefer_zone_connections yes)
			)
		)
	)
	(footprint "antmicro-footprints:R_0402_1005Metric"
		(layer "F.Cu")
		(at 124.21 145.05)
		(descr "Resistor SMD 0402")
		(tags "resistor SMD 0402")
		(property "Reference" "R282"
			(at -3.61 0.46 0)
			(layer "F.SilkS")
			(effects
				(font
					(size 0.7 0.7)
					(thickness 0.15)
				)
				(justify left bottom)
			)
		)
		(property "Value" "R_0R_0402"
			(at -1.011843 1.772047 0)
			(layer "F.Fab")
			(effects
				(font
					(size 0.7 0.7)
					(thickness 0.15)
				)
				(justify left bottom)
			)
		)
		(property "Datasheet" "https://industrial.panasonic.com/cdbs/www-data/pdf/RDA0000/AOA0000C301.pdf"
			(at 0 0 0)
			(layer "F.Fab")
			(hide yes)
			(effects
				(font
					(size 1.27 1.27)
					(thickness 0.15)
				)
			)
		)
		(property "Author" "Antmicro"
			(at 0 0 0)
			(layer "F.Fab")
			(hide yes)
			(effects
				(font
					(size 1 1)
					(thickness 0.15)
				)
			)
		)
		(property "Current" "1A"
			(at 0 0 0)
			(layer "F.Fab")
			(hide yes)
			(effects
				(font
					(size 1 1)
					(thickness 0.15)
				)
			)
		)
		(property "License" "Apache-2.0"
			(at 0 0 0)
			(layer "F.Fab")
			(hide yes)
			(effects
				(font
					(size 1 1)
					(thickness 0.15)
				)
			)
		)
		(property "MPN" "ERJ2GE0R00X"
			(at 0 0 0)
			(layer "F.Fab")
			(hide yes)
			(effects
				(font
					(size 1 1)
					(thickness 0.15)
				)
			)
		)
		(property "Manufacturer" "Panasonic"
			(at 0 0 0)
			(layer "F.Fab")
			(hide yes)
			(effects
				(font
					(size 1 1)
					(thickness 0.15)
				)
			)
		)
		(property "Public" "False"
			(at 0 0 0)
			(layer "F.Fab")
			(hide yes)
			(effects
				(font
					(size 1 1)
					(thickness 0.15)
				)
			)
		)
		(property "Tolerance" ""
			(at 0 0 0)
			(layer "F.Fab")
			(hide yes)
			(effects
				(font
					(size 1 1)
					(thickness 0.15)
				)
			)
		)
		(property "Val" "0R"
			(at 0 0 0)
			(layer "F.Fab")
			(hide yes)
			(effects
				(font
					(size 1 1)
					(thickness 0.15)
				)
			)
		)
		(sheetname "KR to SFI #2")
		(sheetfile "kr_sfi.kicad_sch")
		(attr smd)
		(fp_rect
			(start -0.925 -0.47)
			(end 0.925 0.47)
			(stroke
				(width 0.05)
				(type default)
			)
			(fill no)
			(layer "F.CrtYd")
		)
		(fp_rect
			(start -0.5 -0.25)
			(end 0.5 0.25)
			(stroke
				(width 0.15)
				(type solid)
			)
			(fill no)
			(layer "F.Fab")
		)
		(pad "1" smd roundrect
			(at -0.48 0)
			(size 0.59 0.64)
			(layers "F.Cu" "F.Mask" "F.Paste")
			(roundrect_rratio 0.25)
			(net 671 "/2xSFP+/KR to SFI #2/MDC_R")
			(pintype "passive")
			(teardrops
				(best_length_ratio 0.2)
				(max_length 1)
				(best_width_ratio 0.9)
				(max_width 2)
				(curved_edges yes)
				(filter_ratio 0.9)
				(enabled yes)
				(allow_two_segments yes)
				(prefer_zone_connections yes)
			)
		)
		(pad "2" smd roundrect
			(at 0.48 0)
			(size 0.59 0.64)
			(layers "F.Cu" "F.Mask" "F.Paste")
			(roundrect_rratio 0.25)
			(net 672 "/2xSFP+/KR to SFI #2/MDC")
			(pintype "passive")
			(teardrops
				(best_length_ratio 0.2)
				(max_length 1)
				(best_width_ratio 0.9)
				(max_width 2)
				(curved_edges yes)
				(filter_ratio 0.9)
				(enabled yes)
				(allow_two_segments yes)
				(prefer_zone_connections yes)
			)
		)
	)
	(footprint "antmicro-footprints:Conn_Molex_KK_1x4_0470531000"
		(layer "F.Cu")
		(at 238.780707 71.86 180)
		(property "Reference" "J11"
			(at 7.159999 -3.8 0)
			(layer "F.SilkS")
			(effects
				(font
					(size 0.7 0.7)
					(thickness 0.15)
				)
				(justify right bottom)
			)
		)
		(property "Value" "Molex_KK_1x4_0470531000"
			(at 0 4.7 0)
			(layer "F.Fab")
			(effects
				(font
					(size 0.7 0.7)
					(thickness 0.15)
				)
				(justify right bottom)
			)
		)
		(property "Datasheet" "https://tools.molex.com/pdm_docs/sd/470531000_sd.pdf"
			(at 0 0 180)
			(layer "F.Fab")
			(hide yes)
			(effects
				(font
					(size 1.27 1.27)
					(thickness 0.15)
				)
			)
		)
		(property "Author" "Antmicro"
			(at 477.561414 143.72 0)
			(layer "F.Fab")
			(hide yes)
			(effects
				(font
					(size 1 1)
					(thickness 0.15)
				)
			)
		)
		(property "License" "Apache-2.0"
			(at 477.561414 143.72 0)
			(layer "F.Fab")
			(hide yes)
			(effects
				(font
					(size 1 1)
					(thickness 0.15)
				)
			)
		)
		(property "MPN" "0470531000"
			(at 477.561414 143.72 0)
			(layer "F.Fab")
			(hide yes)
			(effects
				(font
					(size 1 1)
					(thickness 0.15)
				)
			)
		)
		(property "Manufacturer" "Molex"
			(at 477.561414 143.72 0)
			(layer "F.Fab")
			(hide yes)
			(effects
				(font
					(size 1 1)
					(thickness 0.15)
				)
			)
		)
		(sheetname "Misc")
		(sheetfile "misc.kicad_sch")
		(attr through_hole)
		(fp_line
			(start 8.95 3.4)
			(end -1.35 3.4)
			(stroke
				(width 0.15)
				(type solid)
			)
			(layer "F.SilkS")
		)
		(fp_line
			(start 8.95 -2.55)
			(end 8.95 3.4)
			(stroke
				(width 0.15)
				(type solid)
			)
			(layer "F.SilkS")
		)
		(fp_line
			(start 5.75 -2.55)
			(end 8.95 -2.55)
			(stroke
				(width 0.15)
				(type solid)
			)
			(layer "F.SilkS")
		)
		(fp_line
			(start 5.08 2.29)
			(end 5.08 3.3)
			(stroke
				(width 0.15)
				(type solid)
			)
			(layer "F.SilkS")
		)
		(fp_line
			(start 0 3.3)
			(end 0 2.29)
			(stroke
				(width 0.15)
				(type solid)
			)
			(layer "F.SilkS")
		)
		(fp_line
			(start 0 2.29)
			(end 5.08 2.29)
			(stroke
				(width 0.15)
				(type solid)
			)
			(layer "F.SilkS")
		)
		(fp_line
			(start -1.35 3.4)
			(end -1.35 -2.6)
			(stroke
				(width 0.15)
				(type solid)
			)
			(layer "F.SilkS")
		)
		(fp_line
			(start -1.35 -2.6)
			(end 4.4 -2.6)
			(stroke
				(width 0.15)
				(type solid)
			)
			(layer "F.SilkS")
		)
		(fp_circle
			(center 0 -3)
			(end 0.05 -3)
			(stroke
				(width 0.15)
				(type solid)
			)
			(fill yes)
			(layer "F.SilkS")
		)
		(fp_rect
			(start -1.54 -2.96)
			(end 9.16 3.55)
			(stroke
				(width 0.05)
				(type solid)
			)
			(fill no)
			(layer "F.CrtYd")
		)
		(fp_line
			(start 8.85 3.3)
			(end -1.2 3.3)
			(stroke
				(width 0.15)
				(type solid)
			)
			(layer "F.Fab")
		)
		(fp_line
			(start 8.85 -2.5)
			(end 8.85 3.3)
			(stroke
				(width 0.15)
				(type solid)
			)
			(layer "F.Fab")
		)
		(fp_line
			(start 5.75 -2.5)
			(end 8.85 -2.5)
			(stroke
				(width 0.15)
				(type solid)
			)
			(layer "F.Fab")
		)
		(fp_line
			(start 5.1 3.3)
			(end 5.1 2.3)
			(stroke
				(width 0.15)
				(type solid)
			)
			(layer "F.Fab")
		)
		(fp_line
			(start 5.1 2.3)
			(end 0 2.3)
			(stroke
				(width 0.15)
				(type solid)
			)
			(layer "F.Fab")
		)
		(fp_line
			(start 0 2.3)
			(end 0 3.3)
			(stroke
				(width 0.15)
				(type solid)
			)
			(layer "F.Fab")
		)
		(fp_line
			(start -1.2 3.3)
			(end -1.25 3.3)
			(stroke
				(width 0.15)
				(type solid)
			)
			(layer "F.Fab")
		)
		(fp_line
			(start -1.25 3.3)
			(end -1.25 -2.5)
			(stroke
				(width 0.15)
				(type solid)
			)
			(layer "F.Fab")
		)
		(fp_line
			(start -1.25 -2.5)
			(end 4.4 -2.5)
			(stroke
				(width 0.15)
				(type solid)
			)
			(layer "F.Fab")
		)
		(pad "" np_thru_hole circle
			(at 5.08 -2.16 270)
			(size 1.1 1.1)
			(drill 1.1)
			(layers "*.Cu" "*.Mask")
		)
		(pad "1" thru_hole rect
			(at 0 0 270)
			(size 2.03 1.73)
			(drill 1.02)
			(layers "*.Cu" "*.Mask")
			(remove_unused_layers no)
			(net 1 "GND")
			(pintype "passive")
			(teardrops
				(best_length_ratio 0.2)
				(max_length 1)
				(best_width_ratio 0.9)
				(max_width 2)
				(curved_edges yes)
				(filter_ratio 0.9)
				(enabled yes)
				(allow_two_segments yes)
				(prefer_zone_connections yes)
			)
		)
		(pad "2" thru_hole oval
			(at 2.54 0 270)
			(size 2.03 1.73)
			(drill 1.02)
			(layers "*.Cu" "*.Mask")
			(remove_unused_layers no)
			(net 81 "/Misc/FAN_12V")
			(pintype "passive")
			(teardrops
				(best_length_ratio 0.2)
				(max_length 1)
				(best_width_ratio 0.9)
				(max_width 2)
				(curved_edges yes)
				(filter_ratio 0.9)
				(enabled yes)
				(allow_two_segments yes)
				(prefer_zone_connections yes)
			)
		)
		(pad "3" thru_hole oval
			(at 5.08 0 270)
			(size 2.03 1.73)
			(drill 1.02)
			(layers "*.Cu" "*.Mask")
			(remove_unused_layers no)
			(net 283 "/Misc/TACH_{C5V}")
			(pintype "passive")
			(teardrops
				(best_length_ratio 0.2)
				(max_length 1)
				(best_width_ratio 0.9)
				(max_width 2)
				(curved_edges yes)
				(filter_ratio 0.9)
				(enabled yes)
				(allow_two_segments yes)
				(prefer_zone_connections yes)
			)
		)
		(pad "4" thru_hole oval
			(at 7.62 0 270)
			(size 2.03 1.73)
			(drill 1.02)
			(layers "*.Cu" "*.Mask")
			(remove_unused_layers no)
			(net 284 "/Misc/PWM_{C5V}")
			(pintype "passive")
			(teardrops
				(best_length_ratio 0.2)
				(max_length 1)
				(best_width_ratio 0.9)
				(max_width 2)
				(curved_edges yes)
				(filter_ratio 0.9)
				(enabled yes)
				(allow_two_segments yes)
				(prefer_zone_connections yes)
			)
		)
	)
	(footprint "antmicro-footprints:TP_SMD_0.75mm"
		(layer "F.Cu")
		(at 134.94 128.71)
		(property "Reference" "TP79"
			(at 0.51 -3.3 90)
			(layer "F.SilkS")
			(effects
				(font
					(size 0.7 0.7)
					(thickness 0.15)
				)
				(justify left bottom)
			)
		)
		(property "Value" "TP_0.75mm_SMD"
			(at 0 1.2 0)
			(layer "F.Fab")
			(effects
				(font
					(size 0.7 0.7)
					(thickness 0.15)
				)
				(justify left bottom)
			)
		)
		(property "Author" "Antmicro"
			(at 0 0 0)
			(layer "F.Fab")
			(hide yes)
			(effects
				(font
					(size 1 1)
					(thickness 0.15)
				)
			)
		)
		(property "License" "Apache-2.0"
			(at 0 0 0)
			(layer "F.Fab")
			(hide yes)
			(effects
				(font
					(size 1 1)
					(thickness 0.15)
				)
			)
		)
		(property "MPN" ""
			(at 0 0 0)
			(layer "F.Fab")
			(hide yes)
			(effects
				(font
					(size 1 1)
					(thickness 0.15)
				)
			)
		)
		(property "Manufacturer" ""
			(at 0 0 0)
			(layer "F.Fab")
			(hide yes)
			(effects
				(font
					(size 1 1)
					(thickness 0.15)
				)
			)
		)
		(property "Public" "False"
			(at 0 0 0)
			(layer "F.Fab")
			(hide yes)
			(effects
				(font
					(size 1 1)
					(thickness 0.15)
				)
			)
		)
		(sheetname "KR to SFI #2")
		(sheetfile "kr_sfi.kicad_sch")
		(attr exclude_from_pos_files exclude_from_bom)
		(fp_circle
			(center 0 0)
			(end 0.475 0)
			(stroke
				(width 0.05)
				(type default)
			)
			(fill no)
			(layer "F.CrtYd")
		)
		(pad "1" smd circle
			(at 0 0)
			(size 0.75 0.75)
			(layers "F.Cu" "F.Mask")
			(net 742 "/2xSFP+/KR to SFI #2/TDI")
			(pinfunction "1")
			(pintype "passive")
			(teardrops
				(best_length_ratio 0.4)
				(max_length 1)
				(best_width_ratio 0.9)
				(max_width 2)
				(curved_edges yes)
				(filter_ratio 0.9)
				(enabled yes)
				(allow_two_segments yes)
				(prefer_zone_connections yes)
			)
		)
	)
	(footprint "antmicro-footprints:R_0402_1005Metric"
		(layer "F.Cu")
		(at 292.5 96.16)
		(descr "Resistor SMD 0402")
		(tags "resistor SMD 0402")
		(property "Reference" "R118"
			(at -1.4 -0.5 0)
			(layer "F.SilkS")
			(effects
				(font
					(size 0.7 0.7)
					(thickness 0.15)
				)
				(justify left bottom)
			)
		)
		(property "Value" "R_100k_0402"
			(at -1.011843 1.772047 0)
			(layer "F.Fab")
			(effects
				(font
					(size 0.7 0.7)
					(thickness 0.15)
				)
				(justify left bottom)
			)
		)
		(property "Datasheet" "https://www.bourns.com/docs/product-datasheets/cr.pdf"
			(at 0 0 0)
			(layer "F.Fab")
			(hide yes)
			(effects
				(font
					(size 1.27 1.27)
					(thickness 0.15)
				)
			)
		)
		(property "Author" "Antmicro"
			(at 0 0 0)
			(layer "F.Fab")
			(hide yes)
			(effects
				(font
					(size 1 1)
					(thickness 0.15)
				)
			)
		)
		(property "License" "Apache-2.0"
			(at 0 0 0)
			(layer "F.Fab")
			(hide yes)
			(effects
				(font
					(size 1 1)
					(thickness 0.15)
				)
			)
		)
		(property "MPN" "CR0402-FX-1003GLF"
			(at 0 0 0)
			(layer "F.Fab")
			(hide yes)
			(effects
				(font
					(size 1 1)
					(thickness 0.15)
				)
			)
		)
		(property "Manufacturer" "Bourns"
			(at 0 0 0)
			(layer "F.Fab")
			(hide yes)
			(effects
				(font
					(size 1 1)
					(thickness 0.15)
				)
			)
		)
		(property "Public" "False"
			(at 0 0 0)
			(layer "F.Fab")
			(hide yes)
			(effects
				(font
					(size 1 1)
					(thickness 0.15)
				)
			)
		)
		(property "Tolerance" "1%"
			(at 0 0 0)
			(layer "F.Fab")
			(hide yes)
			(effects
				(font
					(size 1 1)
					(thickness 0.15)
				)
			)
		)
		(property "Val" "100k"
			(at 0 0 0)
			(layer "F.Fab")
			(hide yes)
			(effects
				(font
					(size 1 1)
					(thickness 0.15)
				)
			)
		)
		(sheetname "Power")
		(sheetfile "power.kicad_sch")
		(attr smd)
		(fp_rect
			(start -0.925 -0.47)
			(end 0.925 0.47)
			(stroke
				(width 0.05)
				(type default)
			)
			(fill no)
			(layer "F.CrtYd")
		)
		(fp_rect
			(start -0.5 -0.25)
			(end 0.5 0.25)
			(stroke
				(width 0.15)
				(type solid)
			)
			(fill no)
			(layer "F.Fab")
		)
		(pad "1" smd roundrect
			(at -0.48 0)
			(size 0.59 0.64)
			(layers "F.Cu" "F.Mask" "F.Paste")
			(roundrect_rratio 0.25)
			(net 536 "Net-(Q3-D)")
			(pintype "passive")
			(teardrops
				(best_length_ratio 0.2)
				(max_length 1)
				(best_width_ratio 0.9)
				(max_width 2)
				(curved_edges yes)
				(filter_ratio 0.9)
				(enabled yes)
				(allow_two_segments yes)
				(prefer_zone_connections yes)
			)
		)
		(pad "2" smd roundrect
			(at 0.48 0)
			(size 0.59 0.64)
			(layers "F.Cu" "F.Mask" "F.Paste")
			(roundrect_rratio 0.25)
			(net 77 "+5V_AON")
			(pintype "passive")
			(teardrops
				(best_length_ratio 0.2)
				(max_length 1)
				(best_width_ratio 0.9)
				(max_width 2)
				(curved_edges yes)
				(filter_ratio 0.9)
				(enabled yes)
				(allow_two_segments yes)
				(prefer_zone_connections yes)
			)
		)
	)
	(footprint "antmicro-footprints:R_0402_1005Metric"
		(layer "F.Cu")
		(at 306.14 131.04 180)
		(descr "Resistor SMD 0402")
		(tags "resistor SMD 0402")
		(property "Reference" "R102"
			(at -1.66 -1.37 0)
			(layer "F.SilkS")
			(effects
				(font
					(size 0.7 0.7)
					(thickness 0.15)
				)
				(justify right bottom)
			)
		)
		(property "Value" "R_0R_0402"
			(at -1.011843 1.772047 0)
			(layer "F.Fab")
			(effects
				(font
					(size 0.7 0.7)
					(thickness 0.15)
				)
				(justify right bottom)
			)
		)
		(property "Datasheet" "https://industrial.panasonic.com/cdbs/www-data/pdf/RDA0000/AOA0000C301.pdf"
			(at 0 0 180)
			(layer "F.Fab")
			(hide yes)
			(effects
				(font
					(size 1.27 1.27)
					(thickness 0.15)
				)
			)
		)
		(property "Author" "Antmicro"
			(at 612.28 262.08 0)
			(layer "F.Fab")
			(hide yes)
			(effects
				(font
					(size 1 1)
					(thickness 0.15)
				)
			)
		)
		(property "Current" "1A"
			(at 612.28 262.08 0)
			(layer "F.Fab")
			(hide yes)
			(effects
				(font
					(size 1 1)
					(thickness 0.15)
				)
			)
		)
		(property "License" "Apache-2.0"
			(at 612.28 262.08 0)
			(layer "F.Fab")
			(hide yes)
			(effects
				(font
					(size 1 1)
					(thickness 0.15)
				)
			)
		)
		(property "MPN" "ERJ2GE0R00X"
			(at 612.28 262.08 0)
			(layer "F.Fab")
			(hide yes)
			(effects
				(font
					(size 1 1)
					(thickness 0.15)
				)
			)
		)
		(property "Manufacturer" "Panasonic"
			(at 612.28 262.08 0)
			(layer "F.Fab")
			(hide yes)
			(effects
				(font
					(size 1 1)
					(thickness 0.15)
				)
			)
		)
		(property "Public" "False"
			(at 612.28 262.08 0)
			(layer "F.Fab")
			(hide yes)
			(effects
				(font
					(size 1 1)
					(thickness 0.15)
				)
			)
		)
		(property "Tolerance" ""
			(at 612.28 262.08 0)
			(layer "F.Fab")
			(hide yes)
			(effects
				(font
					(size 1 1)
					(thickness 0.15)
				)
			)
		)
		(property "Val" "0R"
			(at 612.28 262.08 0)
			(layer "F.Fab")
			(hide yes)
			(effects
				(font
					(size 1 1)
					(thickness 0.15)
				)
			)
		)
		(sheetname "Power")
		(sheetfile "power.kicad_sch")
		(attr smd)
		(fp_rect
			(start -0.925 -0.47)
			(end 0.925 0.47)
			(stroke
				(width 0.05)
				(type default)
			)
			(fill no)
			(layer "F.CrtYd")
		)
		(fp_rect
			(start -0.5 -0.25)
			(end 0.5 0.25)
			(stroke
				(width 0.15)
				(type solid)
			)
			(fill no)
			(layer "F.Fab")
		)
		(pad "1" smd roundrect
			(at -0.48 0 180)
			(size 0.59 0.64)
			(layers "F.Cu" "F.Mask" "F.Paste")
			(roundrect_rratio 0.25)
			(net 578 "/Power/PG_{1V0}")
			(pintype "passive")
			(teardrops
				(best_length_ratio 0.2)
				(max_length 1)
				(best_width_ratio 0.9)
				(max_width 2)
				(curved_edges yes)
				(filter_ratio 0.9)
				(enabled yes)
				(allow_two_segments yes)
				(prefer_zone_connections yes)
			)
		)
		(pad "2" smd roundrect
			(at 0.48 0 180)
			(size 0.59 0.64)
			(layers "F.Cu" "F.Mask" "F.Paste")
			(roundrect_rratio 0.25)
			(net 582 "Net-(U20-~{MR})")
			(pintype "passive")
			(teardrops
				(best_length_ratio 0.2)
				(max_length 1)
				(best_width_ratio 0.9)
				(max_width 2)
				(curved_edges yes)
				(filter_ratio 0.9)
				(enabled yes)
				(allow_two_segments yes)
				(prefer_zone_connections yes)
			)
		)
	)
	(footprint "antmicro-footprints:R_0402_1005Metric"
		(layer "F.Cu")
		(at 211.28 130.425 180)
		(descr "Resistor SMD 0402")
		(tags "resistor SMD 0402")
		(property "Reference" "R195"
			(at 0.83 -0.735 0)
			(layer "F.SilkS")
			(effects
				(font
					(size 0.7 0.7)
					(thickness 0.15)
				)
				(justify right bottom)
			)
		)
		(property "Value" "R_0R_0402"
			(at -1.011843 1.772047 0)
			(layer "F.Fab")
			(effects
				(font
					(size 0.7 0.7)
					(thickness 0.15)
				)
				(justify right bottom)
			)
		)
		(property "Datasheet" "https://industrial.panasonic.com/cdbs/www-data/pdf/RDA0000/AOA0000C301.pdf"
			(at 0 0 180)
			(layer "F.Fab")
			(hide yes)
			(effects
				(font
					(size 1.27 1.27)
					(thickness 0.15)
				)
			)
		)
		(property "Author" "Antmicro"
			(at 422.56 260.85 0)
			(layer "F.Fab")
			(hide yes)
			(effects
				(font
					(size 1 1)
					(thickness 0.15)
				)
			)
		)
		(property "Current" "1A"
			(at 422.56 260.85 0)
			(layer "F.Fab")
			(hide yes)
			(effects
				(font
					(size 1 1)
					(thickness 0.15)
				)
			)
		)
		(property "License" "Apache-2.0"
			(at 422.56 260.85 0)
			(layer "F.Fab")
			(hide yes)
			(effects
				(font
					(size 1 1)
					(thickness 0.15)
				)
			)
		)
		(property "MPN" "ERJ2GE0R00X"
			(at 422.56 260.85 0)
			(layer "F.Fab")
			(hide yes)
			(effects
				(font
					(size 1 1)
					(thickness 0.15)
				)
			)
		)
		(property "Manufacturer" "Panasonic"
			(at 422.56 260.85 0)
			(layer "F.Fab")
			(hide yes)
			(effects
				(font
					(size 1 1)
					(thickness 0.15)
				)
			)
		)
		(property "Public" "False"
			(at 422.56 260.85 0)
			(layer "F.Fab")
			(hide yes)
			(effects
				(font
					(size 1 1)
					(thickness 0.15)
				)
			)
		)
		(property "Tolerance" ""
			(at 422.56 260.85 0)
			(layer "F.Fab")
			(hide yes)
			(effects
				(font
					(size 1 1)
					(thickness 0.15)
				)
			)
		)
		(property "Val" "0R"
			(at 422.56 260.85 0)
			(layer "F.Fab")
			(hide yes)
			(effects
				(font
					(size 1 1)
					(thickness 0.15)
				)
			)
		)
		(sheetname "PCIe misc")
		(sheetfile "pcie_misc.kicad_sch")
		(attr smd)
		(fp_rect
			(start -0.925 -0.47)
			(end 0.925 0.47)
			(stroke
				(width 0.05)
				(type default)
			)
			(fill no)
			(layer "F.CrtYd")
		)
		(fp_rect
			(start -0.5 -0.25)
			(end 0.5 0.25)
			(stroke
				(width 0.15)
				(type solid)
			)
			(fill no)
			(layer "F.Fab")
		)
		(pad "1" smd roundrect
			(at -0.48 0 180)
			(size 0.59 0.64)
			(layers "F.Cu" "F.Mask" "F.Paste")
			(roundrect_rratio 0.25)
			(net 614 "/PCIe misc/DIF1-")
			(pintype "passive")
			(teardrops
				(best_length_ratio 0.2)
				(max_length 1)
				(best_width_ratio 0.9)
				(max_width 2)
				(curved_edges yes)
				(filter_ratio 0.9)
				(enabled yes)
				(allow_two_segments yes)
				(prefer_zone_connections yes)
			)
		)
		(pad "2" smd roundrect
			(at 0.48 0 180)
			(size 0.59 0.64)
			(layers "F.Cu" "F.Mask" "F.Paste")
			(roundrect_rratio 0.25)
			(net 192 "/OCuLink/PCIe_{REF0}.CK+")
			(pintype "passive")
			(teardrops
				(best_length_ratio 0.2)
				(max_length 1)
				(best_width_ratio 0.9)
				(max_width 2)
				(curved_edges yes)
				(filter_ratio 0.9)
				(enabled yes)
				(allow_two_segments yes)
				(prefer_zone_connections yes)
			)
		)
	)
	(footprint "antmicro-footprints:VSSOP-8_2.3x2mm_P0.5mm"
		(layer "F.Cu")
		(at 249.725 131.51 -90)
		(property "Reference" "U33"
			(at 2.75 -1.125 180)
			(layer "F.SilkS")
			(effects
				(font
					(size 0.7 0.7)
					(thickness 0.15)
				)
				(justify right bottom)
			)
		)
		(property "Value" "74AUP2G132"
			(at 0 2.258 90)
			(layer "F.Fab")
			(effects
				(font
					(size 0.7 0.7)
					(thickness 0.15)
				)
				(justify right bottom)
			)
		)
		(property "Datasheet" "https://assets.nexperia.com/documents/data-sheet/74AUP2G132.pdf"
			(at 0 0 270)
			(layer "F.Fab")
			(hide yes)
			(effects
				(font
					(size 1.27 1.27)
					(thickness 0.15)
				)
			)
		)
		(property "Author" "Antmicro"
			(at 118.215 381.235 0)
			(layer "F.Fab")
			(hide yes)
			(effects
				(font
					(size 1 1)
					(thickness 0.15)
				)
			)
		)
		(property "License" "Apache-2.0"
			(at 118.215 381.235 0)
			(layer "F.Fab")
			(hide yes)
			(effects
				(font
					(size 1 1)
					(thickness 0.15)
				)
			)
		)
		(property "MPN" "74AUP2G132"
			(at 118.215 381.235 0)
			(layer "F.Fab")
			(hide yes)
			(effects
				(font
					(size 1 1)
					(thickness 0.15)
				)
			)
		)
		(property "Manufacturer" "Nexperia"
			(at 118.215 381.235 0)
			(layer "F.Fab")
			(hide yes)
			(effects
				(font
					(size 1 1)
					(thickness 0.15)
				)
			)
		)
		(sheetname "Com Express 7 MGMT")
		(sheetfile "com_express_7_mgmt.kicad_sch")
		(attr smd)
		(fp_line
			(start 0.825 1.007)
			(end -0.82 1.007)
			(stroke
				(width 0.15)
				(type solid)
			)
			(layer "F.SilkS")
		)
		(fp_line
			(start -0.82 -0.992)
			(end 0.825 -0.992)
			(stroke
				(width 0.15)
				(type solid)
			)
			(layer "F.SilkS")
		)
		(fp_circle
			(center -1.402 -1.192)
			(end -1.352 -1.192)
			(stroke
				(width 0.15)
				(type solid)
			)
			(fill yes)
			(layer "F.SilkS")
		)
		(fp_rect
			(start 1.8 1.35)
			(end -1.8 -1.35)
			(stroke
				(width 0.05)
				(type solid)
			)
			(fill no)
			(layer "F.CrtYd")
		)
		(fp_line
			(start -0.7 -0.99)
			(end -1.14 -0.55)
			(stroke
				(width 0.15)
				(type solid)
			)
			(layer "F.Fab")
		)
		(fp_rect
			(start -1.147 -0.992)
			(end 1.151 1.007)
			(stroke
				(width 0.15)
				(type solid)
			)
			(fill no)
			(layer "F.Fab")
		)
		(pad "1" smd rect
			(at -1.372 -0.742 270)
			(size 0.75 0.4)
			(layers "F.Cu" "F.Mask" "F.Paste")
			(net 138 "Net-(U33-1A)")
			(pinfunction "1A")
			(pintype "input")
			(teardrops
				(best_length_ratio 0.2)
				(max_length 1)
				(best_width_ratio 0.9)
				(max_width 2)
				(curved_edges yes)
				(filter_ratio 0.9)
				(enabled yes)
				(allow_two_segments yes)
				(prefer_zone_connections yes)
			)
		)
		(pad "2" smd rect
			(at -1.372 -0.244 270)
			(size 0.75 0.3)
			(layers "F.Cu" "F.Mask" "F.Paste")
			(net 138 "Net-(U33-1A)")
			(pinfunction "1B")
			(pintype "input")
			(teardrops
				(best_length_ratio 0.2)
				(max_length 1)
				(best_width_ratio 0.9)
				(max_width 2)
				(curved_edges yes)
				(filter_ratio 0.9)
				(enabled yes)
				(allow_two_segments yes)
				(prefer_zone_connections yes)
			)
		)
		(pad "3" smd rect
			(at -1.372 0.256 270)
			(size 0.75 0.3)
			(layers "F.Cu" "F.Mask" "F.Paste")
			(net 546 "/Com Express 7 MGMT/~{COM7}")
			(pinfunction "2Y")
			(pintype "output")
			(teardrops
				(best_length_ratio 0.2)
				(max_length 1)
				(best_width_ratio 0.9)
				(max_width 2)
				(curved_edges yes)
				(filter_ratio 0.9)
				(enabled yes)
				(allow_two_segments yes)
				(prefer_zone_connections yes)
			)
		)
		(pad "4" smd rect
			(at -1.372 0.757 270)
			(size 0.75 0.4)
			(layers "F.Cu" "F.Mask" "F.Paste")
			(net 1 "GND")
			(pinfunction "GND")
			(pintype "power_in")
			(teardrops
				(best_length_ratio 0.2)
				(max_length 1)
				(best_width_ratio 0.9)
				(max_width 2)
				(curved_edges yes)
				(filter_ratio 0.9)
				(enabled yes)
				(allow_two_segments yes)
				(prefer_zone_connections yes)
			)
		)
		(pad "5" smd rect
			(at 1.377 0.757 270)
			(size 0.75 0.4)
			(layers "F.Cu" "F.Mask" "F.Paste")
			(net 785 "Net-(U33-1Y)")
			(pinfunction "2A")
			(pintype "input")
			(teardrops
				(best_length_ratio 0.2)
				(max_length 1)
				(best_width_ratio 0.9)
				(max_width 2)
				(curved_edges yes)
				(filter_ratio 0.9)
				(enabled yes)
				(allow_two_segments yes)
				(prefer_zone_connections yes)
			)
		)
		(pad "6" smd rect
			(at 1.377 0.256 270)
			(size 0.75 0.3)
			(layers "F.Cu" "F.Mask" "F.Paste")
			(net 434 "/Com Express 7 MGMT/~{TYPE1}")
			(pinfunction "2B")
			(pintype "input")
			(teardrops
				(best_length_ratio 0.2)
				(max_length 1)
				(best_width_ratio 0.9)
				(max_width 2)
				(curved_edges yes)
				(filter_ratio 0.9)
				(enabled yes)
				(allow_two_segments yes)
				(prefer_zone_connections yes)
			)
		)
		(pad "7" smd rect
			(at 1.377 -0.244 270)
			(size 0.75 0.3)
			(layers "F.Cu" "F.Mask" "F.Paste")
			(net 785 "Net-(U33-1Y)")
			(pinfunction "1Y")
			(pintype "output")
			(teardrops
				(best_length_ratio 0.2)
				(max_length 1)
				(best_width_ratio 0.9)
				(max_width 2)
				(curved_edges yes)
				(filter_ratio 0.9)
				(enabled yes)
				(allow_two_segments yes)
				(prefer_zone_connections yes)
			)
		)
		(pad "8" smd rect
			(at 1.377 -0.742 270)
			(size 0.75 0.4)
			(layers "F.Cu" "F.Mask" "F.Paste")
			(net 73 "+3V3_AON")
			(pinfunction "VCC")
			(pintype "power_in")
			(teardrops
				(best_length_ratio 0.2)
				(max_length 1)
				(best_width_ratio 0.9)
				(max_width 2)
				(curved_edges yes)
				(filter_ratio 0.9)
				(enabled yes)
				(allow_two_segments yes)
				(prefer_zone_connections yes)
			)
		)
	)
	(footprint "antmicro-footprints:R_0402_1005Metric"
		(layer "F.Cu")
		(at 314.765499 97.4365 -90)
		(descr "Resistor SMD 0402")
		(tags "resistor SMD 0402")
		(property "Reference" "R110"
			(at -10.1265 -4.734501 90)
			(layer "F.SilkS")
			(effects
				(font
					(size 0.7 0.7)
					(thickness 0.15)
				)
				(justify right bottom)
			)
		)
		(property "Value" "R_15k_0402"
			(at -1.011843 1.772047 90)
			(layer "F.Fab")
			(effects
				(font
					(size 0.7 0.7)
					(thickness 0.15)
				)
				(justify right bottom)
			)
		)
		(property "Datasheet" "https://www.bourns.com/docs/product-datasheets/cr.pdf"
			(at 0 0 270)
			(layer "F.Fab")
			(hide yes)
			(effects
				(font
					(size 1.27 1.27)
					(thickness 0.15)
				)
			)
		)
		(property "Author" "Antmicro"
			(at 217.328999 412.201999 0)
			(layer "F.Fab")
			(hide yes)
			(effects
				(font
					(size 1 1)
					(thickness 0.15)
				)
			)
		)
		(property "License" "Apache-2.0"
			(at 217.328999 412.201999 0)
			(layer "F.Fab")
			(hide yes)
			(effects
				(font
					(size 1 1)
					(thickness 0.15)
				)
			)
		)
		(property "MPN" "CR0402-FX-1502GLF"
			(at 217.328999 412.201999 0)
			(layer "F.Fab")
			(hide yes)
			(effects
				(font
					(size 1 1)
					(thickness 0.15)
				)
			)
		)
		(property "Manufacturer" "Bourns"
			(at 217.328999 412.201999 0)
			(layer "F.Fab")
			(hide yes)
			(effects
				(font
					(size 1 1)
					(thickness 0.15)
				)
			)
		)
		(property "Public" "False"
			(at 217.328999 412.201999 0)
			(layer "F.Fab")
			(hide yes)
			(effects
				(font
					(size 1 1)
					(thickness 0.15)
				)
			)
		)
		(property "Tolerance" "1%"
			(at 217.328999 412.201999 0)
			(layer "F.Fab")
			(hide yes)
			(effects
				(font
					(size 1 1)
					(thickness 0.15)
				)
			)
		)
		(property "Val" "15k"
			(at 217.328999 412.201999 0)
			(layer "F.Fab")
			(hide yes)
			(effects
				(font
					(size 1 1)
					(thickness 0.15)
				)
			)
		)
		(sheetname "Power")
		(sheetfile "power.kicad_sch")
		(attr smd)
		(fp_rect
			(start -0.925 -0.47)
			(end 0.925 0.47)
			(stroke
				(width 0.05)
				(type default)
			)
			(fill no)
			(layer "F.CrtYd")
		)
		(fp_rect
			(start -0.5 -0.25)
			(end 0.5 0.25)
			(stroke
				(width 0.15)
				(type solid)
			)
			(fill no)
			(layer "F.Fab")
		)
		(pad "1" smd roundrect
			(at -0.48 0 270)
			(size 0.59 0.64)
			(layers "F.Cu" "F.Mask" "F.Paste")
			(roundrect_rratio 0.25)
			(net 1 "GND")
			(pintype "passive")
			(teardrops
				(best_length_ratio 0.2)
				(max_length 1)
				(best_width_ratio 0.9)
				(max_width 2)
				(curved_edges yes)
				(filter_ratio 0.9)
				(enabled yes)
				(allow_two_segments yes)
				(prefer_zone_connections yes)
			)
		)
		(pad "2" smd roundrect
			(at 0.48 0 270)
			(size 0.59 0.64)
			(layers "F.Cu" "F.Mask" "F.Paste")
			(roundrect_rratio 0.25)
			(net 585 "Net-(U21-FB)")
			(pintype "passive")
			(teardrops
				(best_length_ratio 0.2)
				(max_length 1)
				(best_width_ratio 0.9)
				(max_width 2)
				(curved_edges yes)
				(filter_ratio 0.9)
				(enabled yes)
				(allow_two_segments yes)
				(prefer_zone_connections yes)
			)
		)
	)
	(footprint "antmicro-footprints:SOD-523"
		(layer "F.Cu")
		(at 113.2 86.41 -90)
		(property "Reference" "D1"
			(at -2.45 -0.45 90)
			(layer "F.SilkS")
			(effects
				(font
					(size 0.7 0.7)
					(thickness 0.15)
				)
				(justify right bottom)
			)
		)
		(property "Value" "PESD5Z5_0F"
			(at 0 1.499 90)
			(layer "F.Fab")
			(effects
				(font
					(size 0.7 0.7)
					(thickness 0.15)
				)
				(justify right bottom)
			)
		)
		(property "Datasheet" "https://assets.nexperia.com/documents/data-sheet/PESD5Z5_0.pdf"
			(at 0 0 270)
			(layer "F.Fab")
			(hide yes)
			(effects
				(font
					(size 1.27 1.27)
					(thickness 0.15)
				)
			)
		)
		(property "Author" "Antmicro"
			(at 26.79 199.61 0)
			(layer "F.Fab")
			(hide yes)
			(effects
				(font
					(size 1 1)
					(thickness 0.15)
				)
			)
		)
		(property "License" "Apache-2.0"
			(at 26.79 199.61 0)
			(layer "F.Fab")
			(hide yes)
			(effects
				(font
					(size 1 1)
					(thickness 0.15)
				)
			)
		)
		(property "MPN" "PESD5Z5.0F"
			(at 26.79 199.61 0)
			(layer "F.Fab")
			(hide yes)
			(effects
				(font
					(size 1 1)
					(thickness 0.15)
				)
			)
		)
		(property "Manufacturer" "Nexperia"
			(at 26.79 199.61 0)
			(layer "F.Fab")
			(hide yes)
			(effects
				(font
					(size 1 1)
					(thickness 0.15)
				)
			)
		)
		(property "Public" "False"
			(at 26.79 199.61 0)
			(layer "F.Fab")
			(hide yes)
			(effects
				(font
					(size 1 1)
					(thickness 0.15)
				)
			)
		)
		(sheetname "2xUSB3.0+RJ45")
		(sheetfile "usb3+rj45.kicad_sch")
		(attr smd)
		(fp_line
			(start -0.35 -0.5)
			(end -0.35 0.5)
			(stroke
				(width 0.15)
				(type solid)
			)
			(layer "F.SilkS")
		)
		(fp_rect
			(start -1 -0.6)
			(end 1 0.6)
			(stroke
				(width 0.05)
				(type solid)
			)
			(fill no)
			(layer "F.CrtYd")
		)
		(fp_line
			(start -0.652 0.423)
			(end 0.65 0.423)
			(stroke
				(width 0.15)
				(type solid)
			)
			(layer "F.Fab")
		)
		(fp_line
			(start -0.652 0.423)
			(end -0.652 -0.425)
			(stroke
				(width 0.15)
				(type solid)
			)
			(layer "F.Fab")
		)
		(fp_line
			(start -0.35 -0.4)
			(end -0.35 0.4)
			(stroke
				(width 0.15)
				(type solid)
			)
			(layer "F.Fab")
		)
		(fp_line
			(start -0.652 -0.425)
			(end 0.65 -0.425)
			(stroke
				(width 0.15)
				(type solid)
			)
			(layer "F.Fab")
		)
		(fp_line
			(start 0.65 -0.425)
			(end 0.65 0.423)
			(stroke
				(width 0.15)
				(type solid)
			)
			(layer "F.Fab")
		)
		(pad "1" smd roundrect
			(at -0.701 0 270)
			(size 0.5 0.6)
			(layers "F.Cu" "F.Mask" "F.Paste")
			(roundrect_rratio 0.25)
			(net 42 "/2xUSB3.0+RJ45/P1_VBUS")
			(pinfunction "C")
			(pintype "passive")
			(teardrops
				(best_length_ratio 0.2)
				(max_length 1)
				(best_width_ratio 0.9)
				(max_width 2)
				(curved_edges yes)
				(filter_ratio 0.9)
				(enabled yes)
				(allow_two_segments yes)
				(prefer_zone_connections yes)
			)
		)
		(pad "2" smd roundrect
			(at 0.699 0 270)
			(size 0.5 0.6)
			(layers "F.Cu" "F.Mask" "F.Paste")
			(roundrect_rratio 0.25)
			(net 1 "GND")
			(pinfunction "A")
			(pintype "passive")
			(teardrops
				(best_length_ratio 0.2)
				(max_length 1)
				(best_width_ratio 0.9)
				(max_width 2)
				(curved_edges yes)
				(filter_ratio 0.9)
				(enabled yes)
				(allow_two_segments yes)
				(prefer_zone_connections yes)
			)
		)
	)
	(footprint "antmicro-footprints:R_0402_1005Metric"
		(layer "F.Cu")
		(at 156.15 84.06)
		(descr "Resistor SMD 0402")
		(tags "resistor SMD 0402")
		(property "Reference" "R136"
			(at -1.35 -0.5 0)
			(layer "F.SilkS")
			(effects
				(font
					(size 0.7 0.7)
					(thickness 0.15)
				)
				(justify left bottom)
			)
		)
		(property "Value" "R_10k_0402"
			(at -1.011843 1.772047 0)
			(layer "F.Fab")
			(effects
				(font
					(size 0.7 0.7)
					(thickness 0.15)
				)
				(justify left bottom)
			)
		)
		(property "Datasheet" "https://www.bourns.com/docs/product-datasheets/cr.pdf"
			(at 0 0 0)
			(layer "F.Fab")
			(hide yes)
			(effects
				(font
					(size 1.27 1.27)
					(thickness 0.15)
				)
			)
		)
		(property "Author" "Antmicro"
			(at 0 0 0)
			(layer "F.Fab")
			(hide yes)
			(effects
				(font
					(size 1 1)
					(thickness 0.15)
				)
			)
		)
		(property "License" "Apache-2.0"
			(at 0 0 0)
			(layer "F.Fab")
			(hide yes)
			(effects
				(font
					(size 1 1)
					(thickness 0.15)
				)
			)
		)
		(property "MPN" "CR0402-FX-1002GLF"
			(at 0 0 0)
			(layer "F.Fab")
			(hide yes)
			(effects
				(font
					(size 1 1)
					(thickness 0.15)
				)
			)
		)
		(property "Manufacturer" "Bourns"
			(at 0 0 0)
			(layer "F.Fab")
			(hide yes)
			(effects
				(font
					(size 1 1)
					(thickness 0.15)
				)
			)
		)
		(property "Public" "False"
			(at 0 0 0)
			(layer "F.Fab")
			(hide yes)
			(effects
				(font
					(size 1 1)
					(thickness 0.15)
				)
			)
		)
		(property "Tolerance" "1%"
			(at 0 0 0)
			(layer "F.Fab")
			(hide yes)
			(effects
				(font
					(size 1 1)
					(thickness 0.15)
				)
			)
		)
		(property "Val" "10k"
			(at 0 0 0)
			(layer "F.Fab")
			(hide yes)
			(effects
				(font
					(size 1 1)
					(thickness 0.15)
				)
			)
		)
		(sheetname "M.2 key E")
		(sheetfile "m2keye.kicad_sch")
		(attr smd)
		(fp_rect
			(start -0.925 -0.47)
			(end 0.925 0.47)
			(stroke
				(width 0.05)
				(type default)
			)
			(fill no)
			(layer "F.CrtYd")
		)
		(fp_rect
			(start -0.5 -0.25)
			(end 0.5 0.25)
			(stroke
				(width 0.15)
				(type solid)
			)
			(fill no)
			(layer "F.Fab")
		)
		(pad "1" smd roundrect
			(at -0.48 0)
			(size 0.59 0.64)
			(layers "F.Cu" "F.Mask" "F.Paste")
			(roundrect_rratio 0.25)
			(net 24 "/M.2 key E/~{CLKREQ}")
			(pintype "passive")
			(teardrops
				(best_length_ratio 0.2)
				(max_length 1)
				(best_width_ratio 0.9)
				(max_width 2)
				(curved_edges yes)
				(filter_ratio 0.9)
				(enabled yes)
				(allow_two_segments yes)
				(prefer_zone_connections yes)
			)
		)
		(pad "2" smd roundrect
			(at 0.48 0)
			(size 0.59 0.64)
			(layers "F.Cu" "F.Mask" "F.Paste")
			(roundrect_rratio 0.25)
			(net 2 "+3V3")
			(pintype "passive")
			(teardrops
				(best_length_ratio 0.2)
				(max_length 1)
				(best_width_ratio 0.9)
				(max_width 2)
				(curved_edges yes)
				(filter_ratio 0.9)
				(enabled yes)
				(allow_two_segments yes)
				(prefer_zone_connections yes)
			)
		)
	)
	(footprint "antmicro-footprints:PinHeader_1x3_P2.54mm_Drill1.1mm"
		(layer "F.Cu")
		(at 206.42 70.61)
		(property "Reference" "J14"
			(at -1.67 1.46 90)
			(layer "F.SilkS")
			(effects
				(font
					(size 0.7 0.7)
					(thickness 0.15)
				)
				(justify left bottom)
			)
		)
		(property "Value" "PinHeader_1x3_P2.54mm_Drill1.1mm"
			(at -1.6 2.7 0)
			(layer "F.Fab")
			(effects
				(font
					(size 0.7 0.7)
					(thickness 0.15)
				)
				(justify left bottom)
			)
		)
		(property "Datasheet" "https://katalog.we-online.de/em/datasheet/6130xx11121.pdf"
			(at 0 0 0)
			(layer "F.Fab")
			(hide yes)
			(effects
				(font
					(size 1.27 1.27)
					(thickness 0.15)
				)
			)
		)
		(property "Author" "Antmicro"
			(at 0 0 0)
			(layer "F.Fab")
			(hide yes)
			(effects
				(font
					(size 1 1)
					(thickness 0.15)
				)
			)
		)
		(property "License" "Apache-2.0"
			(at 0 0 0)
			(layer "F.Fab")
			(hide yes)
			(effects
				(font
					(size 1 1)
					(thickness 0.15)
				)
			)
		)
		(property "MPN" "61300311121"
			(at 0 0 0)
			(layer "F.Fab")
			(hide yes)
			(effects
				(font
					(size 1 1)
					(thickness 0.15)
				)
			)
		)
		(property "Manufacturer" "Würth Elektronik"
			(at 0 0 0)
			(layer "F.Fab")
			(hide yes)
			(effects
				(font
					(size 1 1)
					(thickness 0.15)
				)
			)
		)
		(sheetname "Com Express 7 MGMT")
		(sheetfile "com_express_7_mgmt.kicad_sch")
		(attr through_hole)
		(fp_line
			(start -1.401 -1.401)
			(end -1.401 -0.902)
			(stroke
				(width 0.15)
				(type solid)
			)
			(layer "F.SilkS")
		)
		(fp_line
			(start -1.401 -1.401)
			(end -0.902 -1.401)
			(stroke
				(width 0.15)
				(type solid)
			)
			(layer "F.SilkS")
		)
		(fp_line
			(start -1.401 1.398)
			(end -1.401 0.9)
			(stroke
				(width 0.15)
				(type solid)
			)
			(layer "F.SilkS")
		)
		(fp_line
			(start -1.401 1.398)
			(end -0.902 1.398)
			(stroke
				(width 0.15)
				(type solid)
			)
			(layer "F.SilkS")
		)
		(fp_line
			(start 6.499 -1.401)
			(end 5.999 -1.401)
			(stroke
				(width 0.15)
				(type solid)
			)
			(layer "F.SilkS")
		)
		(fp_line
			(start 6.499 -1.401)
			(end 6.499 -0.902)
			(stroke
				(width 0.15)
				(type solid)
			)
			(layer "F.SilkS")
		)
		(fp_line
			(start 6.499 1.398)
			(end 5.999 1.398)
			(stroke
				(width 0.15)
				(type solid)
			)
			(layer "F.SilkS")
		)
		(fp_line
			(start 6.499 1.398)
			(end 6.499 0.9)
			(stroke
				(width 0.15)
				(type solid)
			)
			(layer "F.SilkS")
		)
		(fp_line
			(start -1.52 -1.52)
			(end -1.52 1.5)
			(stroke
				(width 0.05)
				(type solid)
			)
			(layer "F.CrtYd")
		)
		(fp_line
			(start -1.52 -1.52)
			(end 6.58 -1.52)
			(stroke
				(width 0.05)
				(type solid)
			)
			(layer "F.CrtYd")
		)
		(fp_line
			(start -1.52 1.5)
			(end 6.58 1.5)
			(stroke
				(width 0.05)
				(type solid)
			)
			(layer "F.CrtYd")
		)
		(fp_line
			(start 6.58 -1.52)
			(end 6.58 1.5)
			(stroke
				(width 0.05)
				(type solid)
			)
			(layer "F.CrtYd")
		)
		(fp_line
			(start -1.27 -1.27)
			(end -1.27 1.269)
			(stroke
				(width 0.15)
				(type solid)
			)
			(layer "F.Fab")
		)
		(fp_line
			(start -1.27 -1.27)
			(end 6.349 -1.27)
			(stroke
				(width 0.15)
				(type solid)
			)
			(layer "F.Fab")
		)
		(fp_line
			(start -1.27 1.269)
			(end 6.349 1.269)
			(stroke
				(width 0.15)
				(type solid)
			)
			(layer "F.Fab")
		)
		(fp_line
			(start 6.349 -1.27)
			(end 6.349 1.269)
			(stroke
				(width 0.15)
				(type solid)
			)
			(layer "F.Fab")
		)
		(pad "1" thru_hole rect
			(at 0 0)
			(size 1.7 1.7)
			(drill 1.1)
			(layers "*.Cu" "*.Mask")
			(remove_unused_layers no)
			(net 524 "unconnected-(J14-Pad1)")
			(pintype "passive+no_connect")
			(teardrops
				(best_length_ratio 0.2)
				(max_length 1)
				(best_width_ratio 0.9)
				(max_width 2)
				(curved_edges yes)
				(filter_ratio 0.9)
				(enabled yes)
				(allow_two_segments yes)
				(prefer_zone_connections yes)
			)
		)
		(pad "2" thru_hole circle
			(at 2.539 0)
			(size 1.7 1.7)
			(drill 1.1)
			(layers "*.Cu" "*.Mask")
			(remove_unused_layers no)
			(net 525 "Net-(J14-Pad2)")
			(pintype "passive")
			(teardrops
				(best_length_ratio 0.4)
				(max_length 1)
				(best_width_ratio 0.9)
				(max_width 2)
				(curved_edges yes)
				(filter_ratio 0.9)
				(enabled yes)
				(allow_two_segments yes)
				(prefer_zone_connections yes)
			)
		)
		(pad "3" thru_hole circle
			(at 5.078 0)
			(size 1.7 1.7)
			(drill 1.1)
			(layers "*.Cu" "*.Mask")
			(remove_unused_layers no)
			(net 1 "GND")
			(pintype "passive")
			(teardrops
				(best_length_ratio 0.4)
				(max_length 1)
				(best_width_ratio 0.9)
				(max_width 2)
				(curved_edges yes)
				(filter_ratio 0.9)
				(enabled yes)
				(allow_two_segments yes)
				(prefer_zone_connections yes)
			)
		)
	)
	(footprint "antmicro-footprints:R_0402_1005Metric"
		(layer "F.Cu")
		(at 202.00239 83.347837 180)
		(descr "Resistor SMD 0402")
		(tags "resistor SMD 0402")
		(property "Reference" "R328"
			(at -1.275 -1.4 0)
			(layer "F.SilkS")
			(effects
				(font
					(size 0.7 0.7)
					(thickness 0.15)
				)
				(justify right bottom)
			)
		)
		(property "Value" "R_5k1_0402"
			(at -1.011843 1.772047 0)
			(layer "F.Fab")
			(effects
				(font
					(size 0.7 0.7)
					(thickness 0.15)
				)
				(justify right bottom)
			)
		)
		(property "Datasheet" "https://www.bourns.com/docs/product-datasheets/cr.pdf"
			(at 0 0 180)
			(layer "F.Fab")
			(hide yes)
			(effects
				(font
					(size 1.27 1.27)
					(thickness 0.15)
				)
			)
		)
		(property "Author" "Antmicro"
			(at 396.412 166.56 0)
			(layer "F.Fab")
			(hide yes)
			(effects
				(font
					(size 1 1)
					(thickness 0.15)
				)
			)
		)
		(property "License" "Apache-2.0"
			(at 396.412 166.56 0)
			(layer "F.Fab")
			(hide yes)
			(effects
				(font
					(size 1 1)
					(thickness 0.15)
				)
			)
		)
		(property "MPN" "CR0402-FX-5101GLF"
			(at 396.412 166.56 0)
			(layer "F.Fab")
			(hide yes)
			(effects
				(font
					(size 1 1)
					(thickness 0.15)
				)
			)
		)
		(property "Manufacturer" "Bourns"
			(at 396.412 166.56 0)
			(layer "F.Fab")
			(hide yes)
			(effects
				(font
					(size 1 1)
					(thickness 0.15)
				)
			)
		)
		(property "Tolerance" "1%"
			(at 396.412 166.56 0)
			(layer "F.Fab")
			(hide yes)
			(effects
				(font
					(size 1 1)
					(thickness 0.15)
				)
			)
		)
		(property "Val" "5k1"
			(at 396.412 166.56 0)
			(layer "F.Fab")
			(hide yes)
			(effects
				(font
					(size 1 1)
					(thickness 0.15)
				)
			)
		)
		(sheetname "Power")
		(sheetfile "power.kicad_sch")
		(attr smd)
		(fp_rect
			(start -0.925 -0.47)
			(end 0.925 0.47)
			(stroke
				(width 0.05)
				(type default)
			)
			(fill no)
			(layer "F.CrtYd")
		)
		(fp_rect
			(start -0.5 -0.25)
			(end 0.5 0.25)
			(stroke
				(width 0.15)
				(type solid)
			)
			(fill no)
			(layer "F.Fab")
		)
		(pad "1" smd roundrect
			(at -0.48 0 180)
			(size 0.59 0.64)
			(layers "F.Cu" "F.Mask" "F.Paste")
			(roundrect_rratio 0.25)
			(net 74 "+1V0")
			(pintype "passive")
			(teardrops
				(best_length_ratio 0.2)
				(max_length 1)
				(best_width_ratio 0.9)
				(max_width 2)
				(curved_edges yes)
				(filter_ratio 0.9)
				(enabled yes)
				(allow_two_segments yes)
				(prefer_zone_connections yes)
			)
		)
		(pad "2" smd roundrect
			(at 0.48 0 180)
			(size 0.59 0.64)
			(layers "F.Cu" "F.Mask" "F.Paste")
			(roundrect_rratio 0.25)
			(net 987 "Net-(Q13-B)")
			(pintype "passive")
			(teardrops
				(best_length_ratio 0.2)
				(max_length 1)
				(best_width_ratio 0.9)
				(max_width 2)
				(curved_edges yes)
				(filter_ratio 0.9)
				(enabled yes)
				(allow_two_segments yes)
				(prefer_zone_connections yes)
			)
		)
	)
	(footprint "antmicro-footprints:R_0805_2012Metric"
		(layer "F.Cu")
		(at 310.85 144.71 90)
		(property "Reference" "R85"
			(at -1.05 1.85 90)
			(layer "F.SilkS")
			(effects
				(font
					(size 0.7 0.7)
					(thickness 0.15)
				)
				(justify left bottom)
			)
		)
		(property "Value" "R_0R001_0805"
			(at 0 1.8 90)
			(layer "F.Fab")
			(effects
				(font
					(size 0.7 0.7)
					(thickness 0.15)
				)
				(justify left bottom)
			)
		)
		(property "Datasheet" "https://www.eaton.com/content/dam/eaton/products/electronic-components/resources/data-sheet/eaton-msma-automotive-smd-current-sense-resistor-metal-strip-data-sheet-elx1179.pdf"
			(at 0 0 90)
			(layer "F.Fab")
			(hide yes)
			(effects
				(font
					(size 1.27 1.27)
					(thickness 0.15)
				)
			)
		)
		(property "Author" "Antmicro"
			(at 455.56 -166.14 0)
			(layer "F.Fab")
			(hide yes)
			(effects
				(font
					(size 1 1)
					(thickness 0.15)
				)
			)
		)
		(property "License" "Apache-2.0"
			(at 455.56 -166.14 0)
			(layer "F.Fab")
			(hide yes)
			(effects
				(font
					(size 1 1)
					(thickness 0.15)
				)
			)
		)
		(property "MPN" "MSMA0805R0010FSM"
			(at 455.56 -166.14 0)
			(layer "F.Fab")
			(hide yes)
			(effects
				(font
					(size 1 1)
					(thickness 0.15)
				)
			)
		)
		(property "Manufacturer" "Eaton"
			(at 455.56 -166.14 0)
			(layer "F.Fab")
			(hide yes)
			(effects
				(font
					(size 1 1)
					(thickness 0.15)
				)
			)
		)
		(property "Public" "False"
			(at 455.56 -166.14 0)
			(layer "F.Fab")
			(hide yes)
			(effects
				(font
					(size 1 1)
					(thickness 0.15)
				)
			)
		)
		(property "Tolerance" "1%"
			(at 455.56 -166.14 0)
			(layer "F.Fab")
			(hide yes)
			(effects
				(font
					(size 1 1)
					(thickness 0.15)
				)
			)
		)
		(property "Val" "0R001"
			(at 455.56 -166.14 0)
			(layer "F.Fab")
			(hide yes)
			(effects
				(font
					(size 1 1)
					(thickness 0.15)
				)
			)
		)
		(sheetname "Power")
		(sheetfile "power.kicad_sch")
		(attr smd)
		(fp_line
			(start -0.3 -0.701)
			(end 0.298 -0.701)
			(stroke
				(width 0.15)
				(type solid)
			)
			(layer "F.SilkS")
		)
		(fp_line
			(start -0.32 0.699)
			(end 0.28 0.699)
			(stroke
				(width 0.15)
				(type solid)
			)
			(layer "F.SilkS")
		)
		(fp_rect
			(start 1.95 -0.9)
			(end -1.95 0.9)
			(stroke
				(width 0.05)
				(type default)
			)
			(fill no)
			(layer "F.CrtYd")
		)
		(fp_line
			(start -0.951 -0.682)
			(end 0.949 -0.682)
			(stroke
				(width 0.15)
				(type solid)
			)
			(layer "F.Fab")
		)
		(fp_line
			(start 0.949 -0.677)
			(end 0.949 0.675)
			(stroke
				(width 0.15)
				(type solid)
			)
			(layer "F.Fab")
		)
		(fp_line
			(start -0.951 -0.677)
			(end -0.951 0.675)
			(stroke
				(width 0.15)
				(type solid)
			)
			(layer "F.Fab")
		)
		(fp_line
			(start -0.951 0.68)
			(end 0.949 0.68)
			(stroke
				(width 0.15)
				(type solid)
			)
			(layer "F.Fab")
		)
		(pad "1" smd roundrect
			(at -1.1 0 90)
			(size 1.2 1.3)
			(layers "F.Cu" "F.Mask" "F.Paste")
			(roundrect_rratio 0.25)
			(net 145 "Net-(D24-C)")
			(pintype "passive")
			(teardrops
				(best_length_ratio 0.2)
				(max_length 1)
				(best_width_ratio 0.9)
				(max_width 2)
				(curved_edges yes)
				(filter_ratio 0.9)
				(enabled yes)
				(allow_two_segments yes)
				(prefer_zone_connections yes)
			)
		)
		(pad "2" smd roundrect
			(at 1.1 0 90)
			(size 1.2 1.3)
			(layers "F.Cu" "F.Mask" "F.Paste")
			(roundrect_rratio 0.25)
			(net 62 "+12V_AON")
			(pintype "passive")
			(teardrops
				(best_length_ratio 0.2)
				(max_length 1)
				(best_width_ratio 0.9)
				(max_width 2)
				(curved_edges yes)
				(filter_ratio 0.9)
				(enabled yes)
				(allow_two_segments yes)
				(prefer_zone_connections yes)
			)
		)
	)
	(footprint "antmicro-footprints:PCB-Edge_Samtec_HSEC8_2x20_HSEC8-120-01-S-D-EM2"
		(layer "F.Cu")
		(at 317.95 160.51 -90)
		(property "Reference" "J16"
			(at -7.31 2.62 0)
			(unlocked yes)
			(layer "F.SilkS")
			(effects
				(font
					(size 0.7 0.7)
					(thickness 0.15)
				)
				(justify left bottom)
			)
		)
		(property "Value" "PCB-Edge_Samtec_HSEC8_2x20_HSEC8-120-01-S-D-EM2"
			(at 0 4 270)
			(unlocked yes)
			(layer "F.Fab")
			(effects
				(font
					(size 0.7 0.7)
					(thickness 0.15)
				)
				(justify left bottom)
			)
		)
		(property "Datasheet" "https://suddendocs.samtec.com/prints/hsec8-1xxx-xx-xx-dv-x-xx-footprint.pdf"
			(at 0 0 90)
			(layer "F.Fab")
			(hide yes)
			(effects
				(font
					(size 1.27 1.27)
					(thickness 0.15)
				)
			)
		)
		(property "Author" "Antmicro"
			(at 0 0 270)
			(unlocked yes)
			(layer "F.Fab")
			(hide yes)
			(effects
				(font
					(size 1 1)
					(thickness 0.15)
				)
			)
		)
		(property "License" "Apache-2.0"
			(at 0 0 270)
			(unlocked yes)
			(layer "F.Fab")
			(hide yes)
			(effects
				(font
					(size 1 1)
					(thickness 0.15)
				)
			)
		)
		(property "Public" "False"
			(at 0 0 270)
			(unlocked yes)
			(layer "F.Fab")
			(hide yes)
			(effects
				(font
					(size 1 1)
					(thickness 0.15)
				)
			)
		)
		(sheetname "Backplane")
		(sheetfile "backplane.kicad_sch")
		(attr exclude_from_pos_files exclude_from_bom)
		(fp_poly
			(pts
				(xy -7.6 0.6) (xy -8 1.2) (xy -7.2 1.2)
			)
			(stroke
				(width 0.1)
				(type solid)
			)
			(fill yes)
			(layer "B.SilkS")
		)
		(fp_line
			(start -9.725 2.52)
			(end -11.225 2.52)
			(stroke
				(width 0.05)
				(type default)
			)
			(layer "Edge.Cuts")
		)
		(fp_line
			(start 9.525 2.52)
			(end 11.025 2.52)
			(stroke
				(width 0.05)
				(type default)
			)
			(layer "Edge.Cuts")
		)
		(fp_line
			(start -8.725 1.52)
			(end -8.725 0)
			(stroke
				(width 0.05)
				(type default)
			)
			(layer "Edge.Cuts")
		)
		(fp_line
			(start 8.525 1.52)
			(end 8.525 0)
			(stroke
				(width 0.05)
				(type default)
			)
			(layer "Edge.Cuts")
		)
		(fp_line
			(start -8.725 -4)
			(end -8.725 0)
			(stroke
				(width 0.05)
				(type default)
			)
			(layer "Edge.Cuts")
		)
		(fp_line
			(start -8.725 -4)
			(end 8.525 -4)
			(stroke
				(width 0.05)
				(type default)
			)
			(layer "Edge.Cuts")
		)
		(fp_line
			(start 8.525 -4)
			(end 8.525 0)
			(stroke
				(width 0.05)
				(type default)
			)
			(layer "Edge.Cuts")
		)
		(fp_arc
			(start 9.525 2.52)
			(mid 8.817999 2.227001)
			(end 8.525 1.52)
			(stroke
				(width 0.05)
				(type default)
			)
			(layer "Edge.Cuts")
		)
		(fp_arc
			(start -8.725 1.52)
			(mid -9.018 2.227)
			(end -9.725 2.52)
			(stroke
				(width 0.05)
				(type default)
			)
			(layer "Edge.Cuts")
		)
		(pad "1" smd roundrect
			(at -7.6 -1.5 180)
			(size 3 0.55)
			(layers "B.Cu" "B.Mask")
			(roundrect_rratio 0.25)
			(net 144 "VCC")
			(pintype "passive")
			(teardrops
				(best_length_ratio 0.2)
				(max_length 1)
				(best_width_ratio 0.9)
				(max_width 2)
				(curved_edges yes)
				(filter_ratio 0.9)
				(enabled yes)
				(allow_two_segments yes)
				(prefer_zone_connections yes)
			)
		)
		(pad "2" smd roundrect
			(at -7.6 -1.5)
			(size 3 0.55)
			(layers "F.Cu" "F.Mask")
			(roundrect_rratio 0.25)
			(net 144 "VCC")
			(pintype "passive")
			(teardrops
				(best_length_ratio 0.2)
				(max_length 1)
				(best_width_ratio 0.9)
				(max_width 2)
				(curved_edges yes)
				(filter_ratio 0.9)
				(enabled yes)
				(allow_two_segments yes)
				(prefer_zone_connections yes)
			)
		)
		(pad "3" smd roundrect
			(at -6.8 -1.5 180)
			(size 3 0.55)
			(layers "B.Cu" "B.Mask")
			(roundrect_rratio 0.25)
			(net 144 "VCC")
			(pintype "passive")
			(teardrops
				(best_length_ratio 0.2)
				(max_length 1)
				(best_width_ratio 0.9)
				(max_width 2)
				(curved_edges yes)
				(filter_ratio 0.9)
				(enabled yes)
				(allow_two_segments yes)
				(prefer_zone_connections yes)
			)
		)
		(pad "4" smd roundrect
			(at -6.8 -1.5)
			(size 3 0.55)
			(layers "F.Cu" "F.Mask")
			(roundrect_rratio 0.25)
			(net 144 "VCC")
			(pintype "passive")
			(teardrops
				(best_length_ratio 0.2)
				(max_length 1)
				(best_width_ratio 0.9)
				(max_width 2)
				(curved_edges yes)
				(filter_ratio 0.9)
				(enabled yes)
				(allow_two_segments yes)
				(prefer_zone_connections yes)
			)
		)
		(pad "5" smd roundrect
			(at -6 -1.5 180)
			(size 3 0.55)
			(layers "B.Cu" "B.Mask")
			(roundrect_rratio 0.25)
			(net 144 "VCC")
			(pintype "passive")
			(teardrops
				(best_length_ratio 0.2)
				(max_length 1)
				(best_width_ratio 0.9)
				(max_width 2)
				(curved_edges yes)
				(filter_ratio 0.9)
				(enabled yes)
				(allow_two_segments yes)
				(prefer_zone_connections yes)
			)
		)
		(pad "6" smd roundrect
			(at -6 -1.5)
			(size 3 0.55)
			(layers "F.Cu" "F.Mask")
			(roundrect_rratio 0.25)
			(net 144 "VCC")
			(pintype "passive")
			(teardrops
				(best_length_ratio 0.2)
				(max_length 1)
				(best_width_ratio 0.9)
				(max_width 2)
				(curved_edges yes)
				(filter_ratio 0.9)
				(enabled yes)
				(allow_two_segments yes)
				(prefer_zone_connections yes)
			)
		)
		(pad "7" smd roundrect
			(at -5.2 -1.5 180)
			(size 3 0.55)
			(layers "B.Cu" "B.Mask")
			(roundrect_rratio 0.25)
			(net 144 "VCC")
			(pintype "passive")
			(teardrops
				(best_length_ratio 0.2)
				(max_length 1)
				(best_width_ratio 0.9)
				(max_width 2)
				(curved_edges yes)
				(filter_ratio 0.9)
				(enabled yes)
				(allow_two_segments yes)
				(prefer_zone_connections yes)
			)
		)
		(pad "8" smd roundrect
			(at -5.2 -1.5)
			(size 3 0.55)
			(layers "F.Cu" "F.Mask")
			(roundrect_rratio 0.25)
			(net 144 "VCC")
			(pintype "passive")
			(teardrops
				(best_length_ratio 0.2)
				(max_length 1)
				(best_width_ratio 0.9)
				(max_width 2)
				(curved_edges yes)
				(filter_ratio 0.9)
				(enabled yes)
				(allow_two_segments yes)
				(prefer_zone_connections yes)
			)
		)
		(pad "9" smd roundrect
			(at -4.4 -1.5 180)
			(size 3 0.55)
			(layers "B.Cu" "B.Mask")
			(roundrect_rratio 0.25)
			(net 144 "VCC")
			(pintype "passive")
			(teardrops
				(best_length_ratio 0.2)
				(max_length 1)
				(best_width_ratio 0.9)
				(max_width 2)
				(curved_edges yes)
				(filter_ratio 0.9)
				(enabled yes)
				(allow_two_segments yes)
				(prefer_zone_connections yes)
			)
		)
		(pad "10" smd roundrect
			(at -4.4 -1.5)
			(size 3 0.55)
			(layers "F.Cu" "F.Mask")
			(roundrect_rratio 0.25)
			(net 144 "VCC")
			(pintype "passive")
			(teardrops
				(best_length_ratio 0.2)
				(max_length 1)
				(best_width_ratio 0.9)
				(max_width 2)
				(curved_edges yes)
				(filter_ratio 0.9)
				(enabled yes)
				(allow_two_segments yes)
				(prefer_zone_connections yes)
			)
		)
		(pad "11" smd roundrect
			(at -3.6 -1.5 180)
			(size 3 0.55)
			(layers "B.Cu" "B.Mask")
			(roundrect_rratio 0.25)
			(net 1 "GND")
			(pintype "passive")
			(teardrops
				(best_length_ratio 0.2)
				(max_length 1)
				(best_width_ratio 0.9)
				(max_width 2)
				(curved_edges yes)
				(filter_ratio 0.9)
				(enabled yes)
				(allow_two_segments yes)
				(prefer_zone_connections yes)
			)
		)
		(pad "12" smd roundrect
			(at -3.6 -1.5)
			(size 3 0.55)
			(layers "F.Cu" "F.Mask")
			(roundrect_rratio 0.25)
			(net 1 "GND")
			(pintype "passive")
			(teardrops
				(best_length_ratio 0.2)
				(max_length 1)
				(best_width_ratio 0.9)
				(max_width 2)
				(curved_edges yes)
				(filter_ratio 0.9)
				(enabled yes)
				(allow_two_segments yes)
				(prefer_zone_connections yes)
			)
		)
		(pad "13" smd roundrect
			(at -2.8 -1.5 180)
			(size 3 0.55)
			(layers "B.Cu" "B.Mask")
			(roundrect_rratio 0.25)
			(net 1 "GND")
			(pintype "passive")
			(teardrops
				(best_length_ratio 0.2)
				(max_length 1)
				(best_width_ratio 0.9)
				(max_width 2)
				(curved_edges yes)
				(filter_ratio 0.9)
				(enabled yes)
				(allow_two_segments yes)
				(prefer_zone_connections yes)
			)
		)
		(pad "14" smd roundrect
			(at -2.8 -1.5)
			(size 3 0.55)
			(layers "F.Cu" "F.Mask")
			(roundrect_rratio 0.25)
			(net 1 "GND")
			(pintype "passive")
			(teardrops
				(best_length_ratio 0.2)
				(max_length 1)
				(best_width_ratio 0.9)
				(max_width 2)
				(curved_edges yes)
				(filter_ratio 0.9)
				(enabled yes)
				(allow_two_segments yes)
				(prefer_zone_connections yes)
			)
		)
		(pad "15" smd roundrect
			(at -2 -1.5 180)
			(size 3 0.55)
			(layers "B.Cu" "B.Mask")
			(roundrect_rratio 0.25)
			(net 1 "GND")
			(pintype "passive")
			(teardrops
				(best_length_ratio 0.2)
				(max_length 1)
				(best_width_ratio 0.9)
				(max_width 2)
				(curved_edges yes)
				(filter_ratio 0.9)
				(enabled yes)
				(allow_two_segments yes)
				(prefer_zone_connections yes)
			)
		)
		(pad "16" smd roundrect
			(at -2 -1.5)
			(size 3 0.55)
			(layers "F.Cu" "F.Mask")
			(roundrect_rratio 0.25)
			(net 1 "GND")
			(pintype "passive")
			(teardrops
				(best_length_ratio 0.2)
				(max_length 1)
				(best_width_ratio 0.9)
				(max_width 2)
				(curved_edges yes)
				(filter_ratio 0.9)
				(enabled yes)
				(allow_two_segments yes)
				(prefer_zone_connections yes)
			)
		)
		(pad "17" smd roundrect
			(at -1.2 -1.5 180)
			(size 3 0.55)
			(layers "B.Cu" "B.Mask")
			(roundrect_rratio 0.25)
			(net 866 "/Backplane/PCIe_{x2}.TX0+")
			(pintype "passive")
			(teardrops
				(best_length_ratio 0.2)
				(max_length 1)
				(best_width_ratio 0.9)
				(max_width 2)
				(curved_edges yes)
				(filter_ratio 0.9)
				(enabled yes)
				(allow_two_segments yes)
				(prefer_zone_connections yes)
			)
		)
		(pad "18" smd roundrect
			(at -1.2 -1.5)
			(size 3 0.55)
			(layers "F.Cu" "F.Mask")
			(roundrect_rratio 0.25)
			(net 532 "/Backplane/PCIe_{x2}.RX0+")
			(pintype "passive")
			(teardrops
				(best_length_ratio 0.2)
				(max_length 1)
				(best_width_ratio 0.9)
				(max_width 2)
				(curved_edges yes)
				(filter_ratio 0.9)
				(enabled yes)
				(allow_two_segments yes)
				(prefer_zone_connections yes)
			)
		)
		(pad "19" smd roundrect
			(at -0.4 -1.5 180)
			(size 3 0.55)
			(layers "B.Cu" "B.Mask")
			(roundrect_rratio 0.25)
			(net 867 "/Backplane/PCIe_{x2}.TX0-")
			(pintype "passive")
			(teardrops
				(best_length_ratio 0.2)
				(max_length 1)
				(best_width_ratio 0.9)
				(max_width 2)
				(curved_edges yes)
				(filter_ratio 0.9)
				(enabled yes)
				(allow_two_segments yes)
				(prefer_zone_connections yes)
			)
		)
		(pad "20" smd roundrect
			(at -0.4 -1.5)
			(size 3 0.55)
			(layers "F.Cu" "F.Mask")
			(roundrect_rratio 0.25)
			(net 537 "/Backplane/PCIe_{x2}.RX0-")
			(pintype "passive")
			(teardrops
				(best_length_ratio 0.2)
				(max_length 1)
				(best_width_ratio 0.9)
				(max_width 2)
				(curved_edges yes)
				(filter_ratio 0.9)
				(enabled yes)
				(allow_two_segments yes)
				(prefer_zone_connections yes)
			)
		)
		(pad "21" smd roundrect
			(at 0.4 -1.5 180)
			(size 3 0.55)
			(layers "B.Cu" "B.Mask")
			(roundrect_rratio 0.25)
			(net 1 "GND")
			(pintype "passive")
			(teardrops
				(best_length_ratio 0.2)
				(max_length 1)
				(best_width_ratio 0.9)
				(max_width 2)
				(curved_edges yes)
				(filter_ratio 0.9)
				(enabled yes)
				(allow_two_segments yes)
				(prefer_zone_connections yes)
			)
		)
		(pad "22" smd roundrect
			(at 0.4 -1.5)
			(size 3 0.55)
			(layers "F.Cu" "F.Mask")
			(roundrect_rratio 0.25)
			(net 1 "GND")
			(pintype "passive")
			(teardrops
				(best_length_ratio 0.2)
				(max_length 1)
				(best_width_ratio 0.9)
				(max_width 2)
				(curved_edges yes)
				(filter_ratio 0.9)
				(enabled yes)
				(allow_two_segments yes)
				(prefer_zone_connections yes)
			)
		)
		(pad "23" smd roundrect
			(at 1.2 -1.5 180)
			(size 3 0.55)
			(layers "B.Cu" "B.Mask")
			(roundrect_rratio 0.25)
			(net 868 "/Backplane/PCIe_{x2}.TX1+")
			(pintype "passive")
			(teardrops
				(best_length_ratio 0.2)
				(max_length 1)
				(best_width_ratio 0.9)
				(max_width 2)
				(curved_edges yes)
				(filter_ratio 0.9)
				(enabled yes)
				(allow_two_segments yes)
				(prefer_zone_connections yes)
			)
		)
		(pad "24" smd roundrect
			(at 1.2 -1.5)
			(size 3 0.55)
			(layers "F.Cu" "F.Mask")
			(roundrect_rratio 0.25)
			(net 771 "/Backplane/PCIe_{x2}.RX1+")
			(pintype "passive")
			(teardrops
				(best_length_ratio 0.2)
				(max_length 1)
				(best_width_ratio 0.9)
				(max_width 2)
				(curved_edges yes)
				(filter_ratio 0.9)
				(enabled yes)
				(allow_two_segments yes)
				(prefer_zone_connections yes)
			)
		)
		(pad "25" smd roundrect
			(at 2 -1.5 180)
			(size 3 0.55)
			(layers "B.Cu" "B.Mask")
			(roundrect_rratio 0.25)
			(net 869 "/Backplane/PCIe_{x2}.TX1-")
			(pintype "passive")
			(teardrops
				(best_length_ratio 0.2)
				(max_length 1)
				(best_width_ratio 0.9)
				(max_width 2)
				(curved_edges yes)
				(filter_ratio 0.9)
				(enabled yes)
				(allow_two_segments yes)
				(prefer_zone_connections yes)
			)
		)
		(pad "26" smd roundrect
			(at 2 -1.5)
			(size 3 0.55)
			(layers "F.Cu" "F.Mask")
			(roundrect_rratio 0.25)
			(net 772 "/Backplane/PCIe_{x2}.RX1-")
			(pintype "passive")
			(teardrops
				(best_length_ratio 0.2)
				(max_length 1)
				(best_width_ratio 0.9)
				(max_width 2)
				(curved_edges yes)
				(filter_ratio 0.9)
				(enabled yes)
				(allow_two_segments yes)
				(prefer_zone_connections yes)
			)
		)
		(pad "27" smd roundrect
			(at 2.8 -1.5 180)
			(size 3 0.55)
			(layers "B.Cu" "B.Mask")
			(roundrect_rratio 0.25)
			(net 1 "GND")
			(pintype "passive")
			(teardrops
				(best_length_ratio 0.2)
				(max_length 1)
				(best_width_ratio 0.9)
				(max_width 2)
				(curved_edges yes)
				(filter_ratio 0.9)
				(enabled yes)
				(allow_two_segments yes)
				(prefer_zone_connections yes)
			)
		)
		(pad "28" smd roundrect
			(at 2.8 -1.5)
			(size 3 0.55)
			(layers "F.Cu" "F.Mask")
			(roundrect_rratio 0.25)
			(net 1 "GND")
			(pintype "passive")
			(teardrops
				(best_length_ratio 0.2)
				(max_length 1)
				(best_width_ratio 0.9)
				(max_width 2)
				(curved_edges yes)
				(filter_ratio 0.9)
				(enabled yes)
				(allow_two_segments yes)
				(prefer_zone_connections yes)
			)
		)
		(pad "29" smd roundrect
			(at 3.6 -1.5 180)
			(size 3 0.55)
			(layers "B.Cu" "B.Mask")
			(roundrect_rratio 0.25)
			(net 203 "/Backplane/PCIe_{REF}.CK+")
			(pintype "passive")
			(teardrops
				(best_length_ratio 0.2)
				(max_length 1)
				(best_width_ratio 0.9)
				(max_width 2)
				(curved_edges yes)
				(filter_ratio 0.9)
				(enabled yes)
				(allow_two_segments yes)
				(prefer_zone_connections yes)
			)
		)
		(pad "30" smd roundrect
			(at 3.6 -1.5)
			(size 3 0.55)
			(layers "F.Cu" "F.Mask")
			(roundrect_rratio 0.25)
			(net 528 "/Backplane/~{PERST}")
			(pintype "passive")
			(teardrops
				(best_length_ratio 0.2)
				(max_length 1)
				(best_width_ratio 0.9)
				(max_width 2)
				(curved_edges yes)
				(filter_ratio 0.9)
				(enabled yes)
				(allow_two_segments yes)
				(prefer_zone_connections yes)
			)
		)
		(pad "31" smd roundrect
			(at 4.4 -1.5 180)
			(size 3 0.55)
			(layers "B.Cu" "B.Mask")
			(roundrect_rratio 0.25)
			(net 205 "/Backplane/PCIe_{REF}.CK-")
			(pintype "passive")
			(teardrops
				(best_length_ratio 0.2)
				(max_length 1)
				(best_width_ratio 0.9)
				(max_width 2)
				(curved_edges yes)
				(filter_ratio 0.9)
				(enabled yes)
				(allow_two_segments yes)
				(prefer_zone_connections yes)
			)
		)
		(pad "32" smd roundrect
			(at 4.4 -1.5)
			(size 3 0.55)
			(layers "F.Cu" "F.Mask")
			(roundrect_rratio 0.25)
			(net 526 "/Backplane/~{PRSNT}")
			(pintype "passive")
			(teardrops
				(best_length_ratio 0.2)
				(max_length 1)
				(best_width_ratio 0.9)
				(max_width 2)
				(curved_edges yes)
				(filter_ratio 0.9)
				(enabled yes)
				(allow_two_segments yes)
				(prefer_zone_connections yes)
			)
		)
		(pad "33" smd roundrect
			(at 5.2 -1.5 180)
			(size 3 0.55)
			(layers "B.Cu" "B.Mask")
			(roundrect_rratio 0.25)
			(net 1 "GND")
			(pintype "passive")
			(teardrops
				(best_length_ratio 0.2)
				(max_length 1)
				(best_width_ratio 0.9)
				(max_width 2)
				(curved_edges yes)
				(filter_ratio 0.9)
				(enabled yes)
				(allow_two_segments yes)
				(prefer_zone_connections yes)
			)
		)
		(pad "34" smd roundrect
			(at 5.2 -1.5)
			(size 3 0.55)
			(layers "F.Cu" "F.Mask")
			(roundrect_rratio 0.25)
			(net 527 "/Backplane/GPIO")
			(pintype "passive")
			(teardrops
				(best_length_ratio 0.2)
				(max_length 1)
				(best_width_ratio 0.9)
				(max_width 2)
				(curved_edges yes)
				(filter_ratio 0.9)
				(enabled yes)
				(allow_two_segments yes)
				(prefer_zone_connections yes)
			)
		)
		(pad "35" smd roundrect
			(at 6 -1.5 180)
			(size 3 0.55)
			(layers "B.Cu" "B.Mask")
			(roundrect_rratio 0.25)
			(net 206 "/Backplane/USB.D+")
			(pintype "passive")
			(teardrops
				(best_length_ratio 0.2)
				(max_length 1)
				(best_width_ratio 0.9)
				(max_width 2)
				(curved_edges yes)
				(filter_ratio 0.9)
				(enabled yes)
				(allow_two_segments yes)
				(prefer_zone_connections yes)
			)
		)
		(pad "36" smd roundrect
			(at 6 -1.5)
			(size 3 0.55)
			(layers "F.Cu" "F.Mask")
			(roundrect_rratio 0.25)
			(net 208 "/Backplane/UART.RX")
			(pintype "passive")
			(teardrops
				(best_length_ratio 0.2)
				(max_length 1)
				(best_width_ratio 0.9)
				(max_width 2)
				(curved_edges yes)
				(filter_ratio 0.9)
				(enabled yes)
				(allow_two_segments yes)
				(prefer_zone_connections yes)
			)
		)
		(pad "37" smd roundrect
			(at 6.8 -1.5 180)
			(size 3 0.55)
			(layers "B.Cu" "B.Mask")
			(roundrect_rratio 0.25)
			(net 204 "/Backplane/USB.D-")
			(pintype "passive")
			(teardrops
				(best_length_ratio 0.2)
				(max_length 1)
				(best_width_ratio 0.9)
				(max_width 2)
				(curved_edges yes)
				(filter_ratio 0.9)
				(enabled yes)
				(allow_two_segments yes)
				(prefer_zone_connections yes)
			)
		)
		(pad "38" smd roundrect
			(at 6.8 -1.5)
			(size 3 0.55)
			(layers "F.Cu" "F.Mask")
			(roundrect_rratio 0.25)
			(net 207 "/Backplane/UART.TX")
			(pintype "passive")
			(teardrops
				(best_length_ratio 0.2)
				(max_length 1)
				(best_width_ratio 0.9)
				(max_width 2)
				(curved_edges yes)
				(filter_ratio 0.9)
				(enabled yes)
				(allow_two_segments yes)
				(prefer_zone_connections yes)
			)
		)
		(pad "39" smd roundrect
			(at 7.6 -1.5 180)
			(size 3 0.55)
			(layers "B.Cu" "B.Mask")
			(roundrect_rratio 0.25)
			(net 1 "GND")
			(pintype "passive")
			(teardrops
				(best_length_ratio 0.2)
				(max_length 1)
				(best_width_ratio 0.9)
				(max_width 2)
				(curved_edges yes)
				(filter_ratio 0.9)
				(enabled yes)
				(allow_two_segments yes)
				(prefer_zone_connections yes)
			)
		)
		(pad "40" smd roundrect
			(at 7.6 -1.5)
			(size 3 0.55)
			(layers "F.Cu" "F.Mask")
			(roundrect_rratio 0.25)
			(net 1 "GND")
			(pintype "passive")
			(teardrops
				(best_length_ratio 0.2)
				(max_length 1)
				(best_width_ratio 0.9)
				(max_width 2)
				(curved_edges yes)
				(filter_ratio 0.9)
				(enabled yes)
				(allow_two_segments yes)
				(prefer_zone_connections yes)
			)
		)
	)
	(footprint "antmicro-footprints:TP_SMD_0.75mm"
		(layer "F.Cu")
		(at 148.55 129.56)
		(property "Reference" "TP68"
			(at 0.45 -1.25 90)
			(layer "F.SilkS")
			(effects
				(font
					(size 0.7 0.7)
					(thickness 0.15)
				)
				(justify left bottom)
			)
		)
		(property "Value" "TP_0.75mm_SMD"
			(at 0 1.2 0)
			(layer "F.Fab")
			(effects
				(font
					(size 0.7 0.7)
					(thickness 0.15)
				)
				(justify left bottom)
			)
		)
		(property "Author" "Antmicro"
			(at 0 0 0)
			(layer "F.Fab")
			(hide yes)
			(effects
				(font
					(size 1 1)
					(thickness 0.15)
				)
			)
		)
		(property "License" "Apache-2.0"
			(at 0 0 0)
			(layer "F.Fab")
			(hide yes)
			(effects
				(font
					(size 1 1)
					(thickness 0.15)
				)
			)
		)
		(property "MPN" ""
			(at 0 0 0)
			(layer "F.Fab")
			(hide yes)
			(effects
				(font
					(size 1 1)
					(thickness 0.15)
				)
			)
		)
		(property "Manufacturer" ""
			(at 0 0 0)
			(layer "F.Fab")
			(hide yes)
			(effects
				(font
					(size 1 1)
					(thickness 0.15)
				)
			)
		)
		(property "Public" "False"
			(at 0 0 0)
			(layer "F.Fab")
			(hide yes)
			(effects
				(font
					(size 1 1)
					(thickness 0.15)
				)
			)
		)
		(sheetname "KR to SFI #1")
		(sheetfile "kr_sfi.kicad_sch")
		(attr exclude_from_pos_files exclude_from_bom)
		(fp_circle
			(center 0 0)
			(end 0.475 0)
			(stroke
				(width 0.05)
				(type default)
			)
			(fill no)
			(layer "F.CrtYd")
		)
		(pad "1" smd circle
			(at 0 0)
			(size 0.75 0.75)
			(layers "F.Cu" "F.Mask")
			(net 731 "Net-(U43C-CLKOUTA-)")
			(pinfunction "1")
			(pintype "passive")
			(teardrops
				(best_length_ratio 0.4)
				(max_length 1)
				(best_width_ratio 0.9)
				(max_width 2)
				(curved_edges yes)
				(filter_ratio 0.9)
				(enabled yes)
				(allow_two_segments yes)
				(prefer_zone_connections yes)
			)
		)
	)
	(footprint "antmicro-footprints:Trans_Eth_4.7x3.3mm"
		(layer "F.Cu")
		(at 130.63 100.46)
		(property "Reference" "T8"
			(at 4.92 0.25 0)
			(unlocked yes)
			(layer "F.SilkS")
			(effects
				(font
					(size 0.7 0.7)
					(thickness 0.15)
				)
				(justify left bottom)
			)
		)
		(property "Value" "Trans_SM453229-381N7Y"
			(at 2.39 11.52 0)
			(unlocked yes)
			(layer "F.Fab")
			(effects
				(font
					(size 0.7 0.7)
					(thickness 0.15)
				)
				(justify left bottom)
			)
		)
		(property "Datasheet" "https://eu.mouser.com/datasheet/2/54/bourns_02132019_SM453229-381N7Y_datasheet-1532071.pdf"
			(at 0 0 0)
			(layer "F.Fab")
			(hide yes)
			(effects
				(font
					(size 1.27 1.27)
					(thickness 0.15)
				)
			)
		)
		(property "Author" "Antmicro"
			(at 0 0 0)
			(layer "F.Fab")
			(hide yes)
			(effects
				(font
					(size 1 1)
					(thickness 0.15)
				)
			)
		)
		(property "License" "Apache-2.0"
			(at 0 0 0)
			(layer "F.Fab")
			(hide yes)
			(effects
				(font
					(size 1 1)
					(thickness 0.15)
				)
			)
		)
		(property "MPN" "SM453229-381N7Y"
			(at 0 0 0)
			(layer "F.Fab")
			(hide yes)
			(effects
				(font
					(size 1 1)
					(thickness 0.15)
				)
			)
		)
		(property "Manufacturer" "Bourns"
			(at 0 0 0)
			(layer "F.Fab")
			(hide yes)
			(effects
				(font
					(size 1 1)
					(thickness 0.15)
				)
			)
		)
		(sheetname "2xUSB3.0+RJ45")
		(sheetfile "usb3+rj45.kicad_sch")
		(attr smd)
		(fp_line
			(start -0.15 -0.6)
			(end -0.15 0.55)
			(stroke
				(width 0.1)
				(type default)
			)
			(layer "F.SilkS")
		)
		(fp_line
			(start 3.4 -1.6)
			(end 1 -1.6)
			(stroke
				(width 0.1)
				(type default)
			)
			(layer "F.SilkS")
		)
		(fp_line
			(start 3.4 1.7)
			(end 1 1.7)
			(stroke
				(width 0.1)
				(type default)
			)
			(layer "F.SilkS")
		)
		(fp_line
			(start 4.55 -0.25)
			(end 4.55 0.9)
			(stroke
				(width 0.1)
				(type default)
			)
			(layer "F.SilkS")
		)
		(fp_circle
			(center 0.1 2.3)
			(end 0.15 2.3)
			(stroke
				(width 0.15)
				(type solid)
			)
			(fill yes)
			(layer "F.SilkS")
		)
		(fp_rect
			(start -0.6 -1.9)
			(end 4.94 1.9)
			(stroke
				(width 0.05)
				(type solid)
			)
			(fill no)
			(layer "F.CrtYd")
		)
		(pad "1" smd roundrect
			(at 0.17 1.5)
			(size 0.96 0.27)
			(layers "F.Cu" "F.Mask" "F.Paste")
			(roundrect_rratio 0.25)
			(net 695 "/2xUSB3.0+RJ45/DD_FL+")
			(pinfunction "1")
			(pintype "passive")
			(teardrops
				(best_length_ratio 0.2)
				(max_length 1)
				(best_width_ratio 0.9)
				(max_width 2)
				(curved_edges yes)
				(filter_ratio 0.9)
				(enabled yes)
				(allow_two_segments yes)
				(prefer_zone_connections yes)
			)
		)
		(pad "2" smd roundrect
			(at 0.115 0.855)
			(size 0.85 0.28)
			(layers "F.Cu" "F.Mask" "F.Paste")
			(roundrect_rratio 0.25)
			(net 696 "/2xUSB3.0+RJ45/DD_FL-")
			(pinfunction "2")
			(pintype "passive")
			(teardrops
				(best_length_ratio 0.2)
				(max_length 1)
				(best_width_ratio 0.9)
				(max_width 2)
				(curved_edges yes)
				(filter_ratio 0.9)
				(enabled yes)
				(allow_two_segments yes)
				(prefer_zone_connections yes)
			)
		)
		(pad "3" smd roundrect
			(at 0.14 -1.21)
			(size 0.9 0.77)
			(layers "F.Cu" "F.Mask" "F.Paste")
			(roundrect_rratio 0.1)
			(net 51 "Net-(C13-Pad1)")
			(pinfunction "3")
			(pintype "passive")
			(teardrops
				(best_length_ratio 0.2)
				(max_length 1)
				(best_width_ratio 0.9)
				(max_width 2)
				(curved_edges yes)
				(filter_ratio 0.9)
				(enabled yes)
				(allow_two_segments yes)
				(prefer_zone_connections yes)
			)
		)
		(pad "5" smd roundrect
			(at 4.215 1.385)
			(size 0.95 0.5)
			(layers "F.Cu" "F.Mask" "F.Paste")
			(roundrect_rratio 0.1)
			(net 552 "Net-(R17-Pad2)")
			(pinfunction "5")
			(pintype "passive")
			(teardrops
				(best_length_ratio 0.2)
				(max_length 1)
				(best_width_ratio 0.9)
				(max_width 2)
				(curved_edges yes)
				(filter_ratio 0.9)
				(enabled yes)
				(allow_two_segments yes)
				(prefer_zone_connections yes)
			)
		)
		(pad "6" smd roundrect
			(at 4.265 -0.645)
			(size 0.85 0.34)
			(layers "F.Cu" "F.Mask" "F.Paste")
			(roundrect_rratio 0.1)
			(net 286 "/2xUSB3.0+RJ45/GbE.MDI3+")
			(pinfunction "6")
			(pintype "passive")
			(teardrops
				(best_length_ratio 0.2)
				(max_length 1)
				(best_width_ratio 0.9)
				(max_width 2)
				(curved_edges yes)
				(filter_ratio 0.9)
				(enabled yes)
				(allow_two_segments yes)
				(prefer_zone_connections yes)
			)
		)
		(pad "7" smd roundrect
			(at 4.205 -1.43)
			(size 0.97 0.33)
			(layers "F.Cu" "F.Mask" "F.Paste")
			(roundrect_rratio 0.1)
			(net 285 "/2xUSB3.0+RJ45/GbE.MDI3-")
			(pinfunction "7")
			(pintype "passive")
			(teardrops
				(best_length_ratio 0.2)
				(max_length 1)
				(best_width_ratio 0.9)
				(max_width 2)
				(curved_edges yes)
				(filter_ratio 0.9)
				(enabled yes)
				(allow_two_segments yes)
				(prefer_zone_connections yes)
			)
		)
	)
	(footprint "antmicro-footprints:R_0402_1005Metric"
		(layer "F.Cu")
		(at 111.206999 75.326)
		(descr "Resistor SMD 0402")
		(tags "resistor SMD 0402")
		(property "Reference" "R69"
			(at -1.106999 -0.466 0)
			(layer "F.SilkS")
			(effects
				(font
					(size 0.7 0.7)
					(thickness 0.15)
				)
				(justify left bottom)
			)
		)
		(property "Value" "R_27R_0402"
			(at -1.011843 1.772047 0)
			(layer "F.Fab")
			(effects
				(font
					(size 0.7 0.7)
					(thickness 0.15)
				)
				(justify left bottom)
			)
		)
		(property "Datasheet" "https://www.bourns.com/docs/product-datasheets/cr.pdf"
			(at 0 0 0)
			(layer "F.Fab")
			(hide yes)
			(effects
				(font
					(size 1.27 1.27)
					(thickness 0.15)
				)
			)
		)
		(property "Author" "Antmicro"
			(at 0 0 0)
			(layer "F.Fab")
			(hide yes)
			(effects
				(font
					(size 1 1)
					(thickness 0.15)
				)
			)
		)
		(property "License" "Apache-2.0"
			(at 0 0 0)
			(layer "F.Fab")
			(hide yes)
			(effects
				(font
					(size 1 1)
					(thickness 0.15)
				)
			)
		)
		(property "MPN" "CR0402-FX-27R0GLF"
			(at 0 0 0)
			(layer "F.Fab")
			(hide yes)
			(effects
				(font
					(size 1 1)
					(thickness 0.15)
				)
			)
		)
		(property "Manufacturer" "Bourns"
			(at 0 0 0)
			(layer "F.Fab")
			(hide yes)
			(effects
				(font
					(size 1 1)
					(thickness 0.15)
				)
			)
		)
		(property "Public" "False"
			(at 0 0 0)
			(layer "F.Fab")
			(hide yes)
			(effects
				(font
					(size 1 1)
					(thickness 0.15)
				)
			)
		)
		(property "Tolerance" "1%"
			(at 0 0 0)
			(layer "F.Fab")
			(hide yes)
			(effects
				(font
					(size 1 1)
					(thickness 0.15)
				)
			)
		)
		(property "Val" "27R"
			(at 0 0 0)
			(layer "F.Fab")
			(hide yes)
			(effects
				(font
					(size 1 1)
					(thickness 0.15)
				)
			)
		)
		(sheetname "USB-C console")
		(sheetfile "usb-c_console.kicad_sch")
		(attr smd)
		(fp_rect
			(start -0.925 -0.47)
			(end 0.925 0.47)
			(stroke
				(width 0.05)
				(type default)
			)
			(fill no)
			(layer "F.CrtYd")
		)
		(fp_rect
			(start -0.5 -0.25)
			(end 0.5 0.25)
			(stroke
				(width 0.15)
				(type solid)
			)
			(fill no)
			(layer "F.Fab")
		)
		(pad "1" smd roundrect
			(at -0.48 0)
			(size 0.59 0.64)
			(layers "F.Cu" "F.Mask" "F.Paste")
			(roundrect_rratio 0.25)
			(net 55 "/USB-C console/USB_D+")
			(pintype "passive")
			(teardrops
				(best_length_ratio 0.2)
				(max_length 1)
				(best_width_ratio 0.9)
				(max_width 2)
				(curved_edges yes)
				(filter_ratio 0.9)
				(enabled yes)
				(allow_two_segments yes)
				(prefer_zone_connections yes)
			)
		)
		(pad "2" smd roundrect
			(at 0.48 0)
			(size 0.59 0.64)
			(layers "F.Cu" "F.Mask" "F.Paste")
			(roundrect_rratio 0.25)
			(net 568 "/USB-C console/FTDI_D+")
			(pintype "passive")
			(teardrops
				(best_length_ratio 0.2)
				(max_length 1)
				(best_width_ratio 0.9)
				(max_width 2)
				(curved_edges yes)
				(filter_ratio 0.9)
				(enabled yes)
				(allow_two_segments yes)
				(prefer_zone_connections yes)
			)
		)
	)
	(footprint "antmicro-footprints:Oscillator_SMD_Epson_SG3225EEN_3.2x2.5x1.2mm"
		(layer "F.Cu")
		(at 123.79 138.01 -90)
		(property "Reference" "Y3"
			(at 2.45 -0.46 0)
			(unlocked yes)
			(layer "F.SilkS")
			(effects
				(font
					(size 0.7 0.7)
					(thickness 0.15)
				)
				(justify left bottom)
			)
		)
		(property "Value" "Oscillator_156.25MHz_SG3225EEN"
			(at 0 3 270)
			(unlocked yes)
			(layer "F.Fab")
			(effects
				(font
					(size 0.7 0.7)
					(thickness 0.15)
				)
				(justify left bottom)
			)
		)
		(property "Datasheet" "https://support.epson.biz/td/api/doc_check.php?dl=brief_SG3225EEN&lang=en"
			(at 0 0 270)
			(layer "F.Fab")
			(hide yes)
			(effects
				(font
					(size 1.27 1.27)
					(thickness 0.15)
				)
			)
		)
		(property "Author" "Antmicro"
			(at -14.22 261.8 0)
			(layer "F.Fab")
			(hide yes)
			(effects
				(font
					(size 1 1)
					(thickness 0.15)
				)
			)
		)
		(property "License" "Apache-2.0"
			(at -14.22 261.8 0)
			(layer "F.Fab")
			(hide yes)
			(effects
				(font
					(size 1 1)
					(thickness 0.15)
				)
			)
		)
		(property "MPN" "SG3225EEN_156.250000M-CDGA3"
			(at -14.22 261.8 0)
			(layer "F.Fab")
			(hide yes)
			(effects
				(font
					(size 1 1)
					(thickness 0.15)
				)
			)
		)
		(property "Manufacturer" "Epson"
			(at -14.22 261.8 0)
			(layer "F.Fab")
			(hide yes)
			(effects
				(font
					(size 1 1)
					(thickness 0.15)
				)
			)
		)
		(property "Public" "False"
			(at -14.22 261.8 0)
			(layer "F.Fab")
			(hide yes)
			(effects
				(font
					(size 1 1)
					(thickness 0.15)
				)
			)
		)
		(property "Val" "156.25MHz"
			(at -14.22 261.8 0)
			(layer "F.Fab")
			(hide yes)
			(effects
				(font
					(size 1 1)
					(thickness 0.15)
				)
			)
		)
		(sheetname "KR to SFI #2")
		(sheetfile "kr_sfi.kicad_sch")
		(attr smd)
		(fp_line
			(start 1.25 1.925)
			(end -1.25 1.925)
			(stroke
				(width 0.15)
				(type solid)
			)
			(layer "F.SilkS")
		)
		(fp_line
			(start 1.25 -1.825)
			(end -1.25 -1.825)
			(stroke
				(width 0.15)
				(type solid)
			)
			(layer "F.SilkS")
		)
		(fp_circle
			(center -1.57 -1.87)
			(end -1.57 -1.82)
			(stroke
				(width 0.15)
				(type solid)
			)
			(fill yes)
			(layer "F.SilkS")
		)
		(fp_rect
			(start 1.58 -1.85)
			(end -1.6 1.96)
			(stroke
				(width 0.05)
				(type solid)
			)
			(fill no)
			(layer "F.CrtYd")
		)
		(pad "1" smd rect
			(at -0.925 -1.24 180)
			(size 0.92 1.05)
			(layers "F.Cu" "F.Mask" "F.Paste")
			(net 668 "Net-(Y3-EN)")
			(pinfunction "EN")
			(pintype "input")
			(solder_mask_margin 0.05)
			(teardrops
				(best_length_ratio 0.2)
				(max_length 1)
				(best_width_ratio 0.9)
				(max_width 2)
				(curved_edges yes)
				(filter_ratio 0.9)
				(enabled yes)
				(allow_two_segments yes)
				(prefer_zone_connections yes)
			)
		)
		(pad "2" smd rect
			(at -0.925 0.05 180)
			(size 0.8 1.05)
			(layers "F.Cu" "F.Mask" "F.Paste")
			(net 865 "unconnected-(Y3-NC-Pad2)")
			(pinfunction "NC")
			(pintype "no_connect")
			(solder_mask_margin 0.05)
			(teardrops
				(best_length_ratio 0.2)
				(max_length 1)
				(best_width_ratio 0.9)
				(max_width 2)
				(curved_edges yes)
				(filter_ratio 0.9)
				(enabled yes)
				(allow_two_segments yes)
				(prefer_zone_connections yes)
			)
		)
		(pad "3" smd rect
			(at -0.925 1.34 180)
			(size 0.92 1.05)
			(layers "F.Cu" "F.Mask" "F.Paste")
			(net 1 "GND")
			(pinfunction "GND")
			(pintype "power_in")
			(solder_mask_margin 0.05)
			(teardrops
				(best_length_ratio 0.2)
				(max_length 1)
				(best_width_ratio 0.9)
				(max_width 2)
				(curved_edges yes)
				(filter_ratio 0.9)
				(enabled yes)
				(allow_two_segments yes)
				(prefer_zone_connections yes)
			)
		)
		(pad "4" smd rect
			(at 0.925 1.34 180)
			(size 0.92 1.05)
			(layers "F.Cu" "F.Mask" "F.Paste")
			(net 115 "/2xSFP+/KR to SFI #2/CLK+")
			(pinfunction "OUT+")
			(pintype "output")
			(solder_mask_margin 0.05)
			(teardrops
				(best_length_ratio 0.2)
				(max_length 1)
				(best_width_ratio 0.9)
				(max_width 2)
				(curved_edges yes)
				(filter_ratio 0.9)
				(enabled yes)
				(allow_two_segments yes)
				(prefer_zone_connections yes)
			)
		)
		(pad "5" smd rect
			(at 0.925 0.05 180)
			(size 0.8 1.05)
			(layers "F.Cu" "F.Mask" "F.Paste")
			(net 117 "/2xSFP+/KR to SFI #2/CLK-")
			(pinfunction "OUT-")
			(pintype "output")
			(solder_mask_margin 0.05)
			(teardrops
				(best_length_ratio 0.2)
				(max_length 1)
				(best_width_ratio 0.9)
				(max_width 2)
				(curved_edges yes)
				(filter_ratio 0.9)
				(enabled yes)
				(allow_two_segments yes)
				(prefer_zone_connections yes)
			)
		)
		(pad "6" smd rect
			(at 0.925 -1.24 180)
			(size 0.92 1.05)
			(layers "F.Cu" "F.Mask" "F.Paste")
			(net 2 "+3V3")
			(pinfunction "VCC")
			(pintype "power_in")
			(solder_mask_margin 0.05)
			(teardrops
				(best_length_ratio 0.2)
				(max_length 1)
				(best_width_ratio 0.9)
				(max_width 2)
				(curved_edges yes)
				(filter_ratio 0.9)
				(enabled yes)
				(allow_two_segments yes)
				(prefer_zone_connections yes)
			)
		)
	)
	(footprint "antmicro-footprints:TP_SMD_0.75mm"
		(layer "F.Cu")
		(at 126.49 129.56)
		(property "Reference" "TP78"
			(at 0.46 -1.25 90)
			(layer "F.SilkS")
			(effects
				(font
					(size 0.7 0.7)
					(thickness 0.15)
				)
				(justify left bottom)
			)
		)
		(property "Value" "TP_0.75mm_SMD"
			(at 0 1.2 0)
			(layer "F.Fab")
			(effects
				(font
					(size 0.7 0.7)
					(thickness 0.15)
				)
				(justify left bottom)
			)
		)
		(property "Author" "Antmicro"
			(at 0 0 0)
			(layer "F.Fab")
			(hide yes)
			(effects
				(font
					(size 1 1)
					(thickness 0.15)
				)
			)
		)
		(property "License" "Apache-2.0"
			(at 0 0 0)
			(layer "F.Fab")
			(hide yes)
			(effects
				(font
					(size 1 1)
					(thickness 0.15)
				)
			)
		)
		(property "MPN" ""
			(at 0 0 0)
			(layer "F.Fab")
			(hide yes)
			(effects
				(font
					(size 1 1)
					(thickness 0.15)
				)
			)
		)
		(property "Manufacturer" ""
			(at 0 0 0)
			(layer "F.Fab")
			(hide yes)
			(effects
				(font
					(size 1 1)
					(thickness 0.15)
				)
			)
		)
		(property "Public" "False"
			(at 0 0 0)
			(layer "F.Fab")
			(hide yes)
			(effects
				(font
					(size 1 1)
					(thickness 0.15)
				)
			)
		)
		(sheetname "KR to SFI #2")
		(sheetfile "kr_sfi.kicad_sch")
		(attr exclude_from_pos_files exclude_from_bom)
		(fp_circle
			(center 0 0)
			(end 0.475 0)
			(stroke
				(width 0.05)
				(type default)
			)
			(fill no)
			(layer "F.CrtYd")
		)
		(pad "1" smd circle
			(at 0 0)
			(size 0.75 0.75)
			(layers "F.Cu" "F.Mask")
			(net 741 "Net-(U45C-REFCLK1-)")
			(pinfunction "1")
			(pintype "passive")
			(teardrops
				(best_length_ratio 0.4)
				(max_length 1)
				(best_width_ratio 0.9)
				(max_width 2)
				(curved_edges yes)
				(filter_ratio 0.9)
				(enabled yes)
				(allow_two_segments yes)
				(prefer_zone_connections yes)
			)
		)
	)
	(footprint "antmicro-footprints:LED_0603_1608Metric_G"
		(layer "F.Cu")
		(at 195.70861 74.802163 90)
		(descr "LED SMD 0603 Green")
		(tags "LED SMD 0603 Green")
		(property "Reference" "D34"
			(at -1.1 -0.55 90)
			(layer "F.SilkS")
			(effects
				(font
					(size 0.7 0.7)
					(thickness 0.15)
				)
				(justify left bottom)
			)
		)
		(property "Value" "LED_G_0603_LTST-C190GKT"
			(at -0.001 1.599 90)
			(layer "F.Fab")
			(effects
				(font
					(size 0.7 0.7)
					(thickness 0.15)
				)
				(justify left bottom)
			)
		)
		(property "Datasheet" "https://media.digikey.com/pdf/Data%20Sheets/Lite-On%20PDFs/LTST-C190GKT.pdf"
			(at 0 0 90)
			(layer "F.Fab")
			(hide yes)
			(effects
				(font
					(size 1.27 1.27)
					(thickness 0.15)
				)
			)
		)
		(property "Author" "Antmicro"
			(at 270.510773 -120.906447 0)
			(layer "F.Fab")
			(hide yes)
			(effects
				(font
					(size 1 1)
					(thickness 0.15)
				)
			)
		)
		(property "Color" "Green"
			(at 270.510773 -120.906447 0)
			(layer "F.Fab")
			(hide yes)
			(effects
				(font
					(size 1 1)
					(thickness 0.15)
				)
			)
		)
		(property "License" "Apache-2.0"
			(at 270.510773 -120.906447 0)
			(layer "F.Fab")
			(hide yes)
			(effects
				(font
					(size 1 1)
					(thickness 0.15)
				)
			)
		)
		(property "MPN" "LTST-C190GKT"
			(at 270.510773 -120.906447 0)
			(layer "F.Fab")
			(hide yes)
			(effects
				(font
					(size 1 1)
					(thickness 0.15)
				)
			)
		)
		(property "Manufacturer" "Lite-On"
			(at 270.510773 -120.906447 0)
			(layer "F.Fab")
			(hide yes)
			(effects
				(font
					(size 1 1)
					(thickness 0.15)
				)
			)
		)
		(property "Public" "False"
			(at 270.510773 -120.906447 0)
			(layer "F.Fab")
			(hide yes)
			(effects
				(font
					(size 1 1)
					(thickness 0.15)
				)
			)
		)
		(sheetname "Power")
		(sheetfile "power.kicad_sch")
		(attr smd)
		(fp_line
			(start 0.22 -0.35)
			(end -0.22 -0.35)
			(stroke
				(width 0.15)
				(type solid)
			)
			(layer "F.SilkS")
		)
		(fp_line
			(start -1.18 -0.319)
			(end -1.18 0.321)
			(stroke
				(width 0.15)
				(type solid)
			)
			(layer "F.SilkS")
		)
		(fp_line
			(start 0.105328 0.001008)
			(end 0.24 0.001)
			(stroke
				(width 0.1)
				(type solid)
			)
			(layer "F.SilkS")
		)
		(fp_line
			(start -0.094672 0.001008)
			(end 0.105328 -0.198992)
			(stroke
				(width 0.1)
				(type solid)
			)
			(layer "F.SilkS")
		)
		(fp_line
			(start -0.094672 0.001008)
			(end -0.24 0.001008)
			(stroke
				(width 0.1)
				(type solid)
			)
			(layer "F.SilkS")
		)
		(fp_line
			(start 0.105328 0.201008)
			(end 0.105328 -0.198992)
			(stroke
				(width 0.1)
				(type solid)
			)
			(layer "F.SilkS")
		)
		(fp_line
			(start 0.105328 0.201008)
			(end -0.094672 0.001008)
			(stroke
				(width 0.1)
				(type solid)
			)
			(layer "F.SilkS")
		)
		(fp_line
			(start -0.094672 0.201008)
			(end -0.094672 -0.198992)
			(stroke
				(width 0.1)
				(type solid)
			)
			(layer "F.SilkS")
		)
		(fp_line
			(start 0.22 0.35)
			(end -0.22 0.35)
			(stroke
				(width 0.15)
				(type solid)
			)
			(layer "F.SilkS")
		)
		(fp_rect
			(start 1.25 0.65)
			(end -1.25 -0.65)
			(stroke
				(width 0.05)
				(type solid)
			)
			(fill no)
			(layer "F.CrtYd")
		)
		(fp_line
			(start 0.201 -0.202)
			(end -0.101 0)
			(stroke
				(width 0.15)
				(type solid)
			)
			(layer "F.Fab")
		)
		(fp_line
			(start -0.199 -0.202)
			(end -0.199 0.1)
			(stroke
				(width 0.15)
				(type solid)
			)
			(layer "F.Fab")
		)
		(fp_line
			(start 0.599 0)
			(end 0.201 0)
			(stroke
				(width 0.15)
				(type solid)
			)
			(layer "F.Fab")
		)
		(fp_line
			(start 0.201 0)
			(end 0.201 -0.202)
			(stroke
				(width 0.15)
				(type solid)
			)
			(layer "F.Fab")
		)
		(fp_line
			(start -0.101 0)
			(end 0.201 0.2)
			(stroke
				(width 0.15)
				(type solid)
			)
			(layer "F.Fab")
		)
		(fp_line
			(start -0.199 0)
			(end -0.597 0)
			(stroke
				(width 0.15)
				(type solid)
			)
			(layer "F.Fab")
		)
		(fp_line
			(start 0.201 0.2)
			(end 0.201 0)
			(stroke
				(width 0.15)
				(type solid)
			)
			(layer "F.Fab")
		)
		(fp_line
			(start -0.199 0.2)
			(end -0.199 0.1)
			(stroke
				(width 0.15)
				(type solid)
			)
			(layer "F.Fab")
		)
		(fp_rect
			(start 0.848 0.4)
			(end -0.85 -0.402)
			(stroke
				(width 0.15)
				(type solid)
			)
			(fill no)
			(layer "F.Fab")
		)
		(pad "1" smd roundrect
			(at -0.7 0 270)
			(size 0.8 1)
			(layers "F.Cu" "F.Mask" "F.Paste")
			(roundrect_rratio 0.2)
			(net 986 "Net-(D34-C)")
			(pinfunction "C")
			(pintype "passive")
			(teardrops
				(best_length_ratio 0.2)
				(max_length 1)
				(best_width_ratio 0.9)
				(max_width 2)
				(curved_edges yes)
				(filter_ratio 0.9)
				(enabled yes)
				(allow_two_segments yes)
				(prefer_zone_connections yes)
			)
		)
		(pad "2" smd roundrect
			(at 0.7 0 270)
			(size 0.8 1)
			(layers "F.Cu" "F.Mask" "F.Paste")
			(roundrect_rratio 0.2)
			(net 52 "+5V")
			(pinfunction "A")
			(pintype "passive")
			(teardrops
				(best_length_ratio 0.2)
				(max_length 1)
				(best_width_ratio 0.9)
				(max_width 2)
				(curved_edges yes)
				(filter_ratio 0.9)
				(enabled yes)
				(allow_two_segments yes)
				(prefer_zone_connections yes)
			)
		)
	)
	(footprint "antmicro-footprints:C_0402_1005Metric"
		(layer "F.Cu")
		(at 124.84 141.86)
		(descr "Capacitor SMD 0402")
		(tags "capacitor SMD 0402")
		(property "Reference" "C179"
			(at -3.69 0.45 180)
			(layer "F.SilkS")
			(effects
				(font
					(size 0.7 0.7)
					(thickness 0.15)
				)
				(justify left bottom)
			)
		)
		(property "Value" "C_100n_0402"
			(at -1.022927 2.155213 0)
			(layer "F.Fab")
			(effects
				(font
					(size 0.7 0.7)
					(thickness 0.15)
				)
				(justify left bottom)
			)
		)
		(property "Datasheet" "https://www.murata.com/products/productdetail?partno=GRM155R61H104KE14%23"
			(at 0 0 0)
			(layer "F.Fab")
			(hide yes)
			(effects
				(font
					(size 1.27 1.27)
					(thickness 0.15)
				)
			)
		)
		(property "Author" "Antmicro"
			(at 0 0 0)
			(layer "F.Fab")
			(hide yes)
			(effects
				(font
					(size 1 1)
					(thickness 0.15)
				)
			)
		)
		(property "Dielectric" "X5R"
			(at 0 0 0)
			(layer "F.Fab")
			(hide yes)
			(effects
				(font
					(size 1 1)
					(thickness 0.15)
				)
			)
		)
		(property "License" "Apache-2.0"
			(at 0 0 0)
			(layer "F.Fab")
			(hide yes)
			(effects
				(font
					(size 1 1)
					(thickness 0.15)
				)
			)
		)
		(property "MPN" "GRM155R61H104KE14D"
			(at 0 0 0)
			(layer "F.Fab")
			(hide yes)
			(effects
				(font
					(size 1 1)
					(thickness 0.15)
				)
			)
		)
		(property "Manufacturer" "Murata"
			(at 0 0 0)
			(layer "F.Fab")
			(hide yes)
			(effects
				(font
					(size 1 1)
					(thickness 0.15)
				)
			)
		)
		(property "Public" "False"
			(at 0 0 0)
			(layer "F.Fab")
			(hide yes)
			(effects
				(font
					(size 1 1)
					(thickness 0.15)
				)
			)
		)
		(property "Val" "100n"
			(at 0 0 0)
			(layer "F.Fab")
			(hide yes)
			(effects
				(font
					(size 1 1)
					(thickness 0.15)
				)
			)
		)
		(property "Voltage" "50V"
			(at 0 0 0)
			(layer "F.Fab")
			(hide yes)
			(effects
				(font
					(size 1 1)
					(thickness 0.15)
				)
			)
		)
		(sheetname "KR to SFI #2")
		(sheetfile "kr_sfi.kicad_sch")
		(attr smd)
		(fp_rect
			(start -0.925 -0.47)
			(end 0.925 0.47)
			(stroke
				(width 0.05)
				(type default)
			)
			(fill no)
			(layer "F.CrtYd")
		)
		(fp_line
			(start -0.494 -0.25)
			(end 0.504 -0.25)
			(stroke
				(width 0.15)
				(type solid)
			)
			(layer "F.Fab")
		)
		(fp_line
			(start -0.494 0.248)
			(end -0.494 -0.25)
			(stroke
				(width 0.15)
				(type solid)
			)
			(layer "F.Fab")
		)
		(fp_line
			(start 0.504 -0.25)
			(end 0.504 0.248)
			(stroke
				(width 0.15)
				(type solid)
			)
			(layer "F.Fab")
		)
		(fp_line
			(start 0.504 0.248)
			(end -0.494 0.248)
			(stroke
				(width 0.15)
				(type solid)
			)
			(layer "F.Fab")
		)
		(pad "1" smd roundrect
			(at -0.48 0)
			(size 0.59 0.64)
			(layers "F.Cu" "F.Mask" "F.Paste")
			(roundrect_rratio 0.25)
			(net 115 "/2xSFP+/KR to SFI #2/CLK+")
			(pintype "passive")
			(teardrops
				(best_length_ratio 0.2)
				(max_length 1)
				(best_width_ratio 0.9)
				(max_width 2)
				(curved_edges yes)
				(filter_ratio 0.9)
				(enabled yes)
				(allow_two_segments yes)
				(prefer_zone_connections yes)
			)
		)
		(pad "2" smd roundrect
			(at 0.48 0)
			(size 0.59 0.64)
			(layers "F.Cu" "F.Mask" "F.Paste")
			(roundrect_rratio 0.25)
			(net 118 "/2xSFP+/KR to SFI #2/REFCLK-")
			(pintype "passive")
			(teardrops
				(best_length_ratio 0.2)
				(max_length 1)
				(best_width_ratio 0.9)
				(max_width 2)
				(curved_edges yes)
				(filter_ratio 0.9)
				(enabled yes)
				(allow_two_segments yes)
				(prefer_zone_connections yes)
			)
		)
	)
	(footprint "antmicro-footprints:C_0402_1005Metric"
		(layer "F.Cu")
		(at 194.340683 136.693926 -45)
		(descr "Capacitor SMD 0402")
		(tags "capacitor SMD 0402")
		(property "Reference" "C133"
			(at 3.864616 -0.431761 135)
			(layer "F.SilkS")
			(effects
				(font
					(size 0.7 0.7)
					(thickness 0.15)
				)
				(justify right top)
			)
		)
		(property "Value" "C_100n_0402"
			(at -1.022927 2.155213 135)
			(layer "F.Fab")
			(effects
				(font
					(size 0.7 0.7)
					(thickness 0.15)
				)
				(justify right top)
			)
		)
		(property "Datasheet" "https://www.murata.com/products/productdetail?partno=GRM155R61H104KE14%23"
			(at 0 0 135)
			(layer "B.Fab")
			(hide yes)
			(effects
				(font
					(size 1.27 1.27)
					(thickness 0.15)
				)
				(justify mirror)
			)
		)
		(property "Author" "Antmicro"
			(at 52.668 -325.634001 45)
			(layer "F.Fab")
			(hide yes)
			(effects
				(font
					(size 1 1)
					(thickness 0.15)
				)
			)
		)
		(property "Dielectric" "X5R"
			(at 52.668 -325.634001 45)
			(layer "F.Fab")
			(hide yes)
			(effects
				(font
					(size 1 1)
					(thickness 0.15)
				)
			)
		)
		(property "License" "Apache-2.0"
			(at 52.668 -325.634001 45)
			(layer "F.Fab")
			(hide yes)
			(effects
				(font
					(size 1 1)
					(thickness 0.15)
				)
			)
		)
		(property "MPN" "GRM155R61H104KE14D"
			(at 52.668 -325.634001 45)
			(layer "F.Fab")
			(hide yes)
			(effects
				(font
					(size 1 1)
					(thickness 0.15)
				)
			)
		)
		(property "Manufacturer" "Murata"
			(at 52.668 -325.634001 45)
			(layer "F.Fab")
			(hide yes)
			(effects
				(font
					(size 1 1)
					(thickness 0.15)
				)
			)
		)
		(property "Public" "False"
			(at 52.668 -325.634001 45)
			(layer "F.Fab")
			(hide yes)
			(effects
				(font
					(size 1 1)
					(thickness 0.15)
				)
			)
		)
		(property "Val" "100n"
			(at 52.668 -325.634001 45)
			(layer "F.Fab")
			(hide yes)
			(effects
				(font
					(size 1 1)
					(thickness 0.15)
				)
			)
		)
		(property "Voltage" "50V"
			(at 52.668 -325.634001 45)
			(layer "F.Fab")
			(hide yes)
			(effects
				(font
					(size 1 1)
					(thickness 0.15)
				)
			)
		)
		(sheetname "PCIe redriver")
		(sheetfile "pcie_redriver.kicad_sch")
		(attr smd)
		(fp_poly
			(pts
				(xy -0.925 -0.47) (xy 0.925 -0.47) (xy 0.925 0.47) (xy -0.925 0.47)
			)
			(stroke
				(width 0.05)
				(type default)
			)
			(fill no)
			(layer "F.CrtYd")
		)
		(fp_line
			(start -0.494 0.248)
			(end -0.494 -0.25)
			(stroke
				(width 0.15)
				(type solid)
			)
			(layer "F.Fab")
		)
		(fp_line
			(start -0.494 -0.25)
			(end 0.504 -0.25)
			(stroke
				(width 0.15)
				(type solid)
			)
			(layer "F.Fab")
		)
		(fp_line
			(start 0.504 0.248)
			(end -0.494 0.248)
			(stroke
				(width 0.15)
				(type solid)
			)
			(layer "F.Fab")
		)
		(fp_line
			(start 0.504 -0.25)
			(end 0.504 0.248)
			(stroke
				(width 0.15)
				(type solid)
			)
			(layer "F.Fab")
		)
		(pad "1" smd roundrect
			(at -0.48 0 315)
			(size 0.59 0.64)
			(layers "F.Cu" "F.Mask" "F.Paste")
			(roundrect_rratio 0.25)
			(net 1 "GND")
			(pintype "passive")
			(teardrops
				(best_length_ratio 0.2)
				(max_length 1)
				(best_width_ratio 0.9)
				(max_width 2)
				(curved_edges yes)
				(filter_ratio 0.9)
				(enabled yes)
				(allow_two_segments yes)
				(prefer_zone_connections yes)
			)
		)
		(pad "2" smd roundrect
			(at 0.48 0 315)
			(size 0.59 0.64)
			(layers "F.Cu" "F.Mask" "F.Paste")
			(roundrect_rratio 0.25)
			(net 2 "+3V3")
			(pintype "passive")
			(teardrops
				(best_length_ratio 0.2)
				(max_length 1)
				(best_width_ratio 0.9)
				(max_width 2)
				(curved_edges yes)
				(filter_ratio 0.9)
				(enabled yes)
				(allow_two_segments yes)
				(prefer_zone_connections yes)
			)
		)
	)
	(footprint "antmicro-footprints:R_0402_1005Metric"
		(layer "F.Cu")
		(at 122.05 87.06)
		(descr "Resistor SMD 0402")
		(tags "resistor SMD 0402")
		(property "Reference" "R18"
			(at 0.75 0.45 0)
			(layer "F.SilkS")
			(effects
				(font
					(size 0.7 0.7)
					(thickness 0.15)
				)
				(justify left bottom)
			)
		)
		(property "Value" "R_10k_0402"
			(at -1.011843 1.772047 0)
			(layer "F.Fab")
			(effects
				(font
					(size 0.7 0.7)
					(thickness 0.15)
				)
				(justify left bottom)
			)
		)
		(property "Datasheet" "https://www.bourns.com/docs/product-datasheets/cr.pdf"
			(at 0 0 0)
			(layer "F.Fab")
			(hide yes)
			(effects
				(font
					(size 1.27 1.27)
					(thickness 0.15)
				)
			)
		)
		(property "Author" "Antmicro"
			(at 0 0 0)
			(layer "F.Fab")
			(hide yes)
			(effects
				(font
					(size 1 1)
					(thickness 0.15)
				)
			)
		)
		(property "License" "Apache-2.0"
			(at 0 0 0)
			(layer "F.Fab")
			(hide yes)
			(effects
				(font
					(size 1 1)
					(thickness 0.15)
				)
			)
		)
		(property "MPN" "CR0402-FX-1002GLF"
			(at 0 0 0)
			(layer "F.Fab")
			(hide yes)
			(effects
				(font
					(size 1 1)
					(thickness 0.15)
				)
			)
		)
		(property "Manufacturer" "Bourns"
			(at 0 0 0)
			(layer "F.Fab")
			(hide yes)
			(effects
				(font
					(size 1 1)
					(thickness 0.15)
				)
			)
		)
		(property "Public" "False"
			(at 0 0 0)
			(layer "F.Fab")
			(hide yes)
			(effects
				(font
					(size 1 1)
					(thickness 0.15)
				)
			)
		)
		(property "Tolerance" "1%"
			(at 0 0 0)
			(layer "F.Fab")
			(hide yes)
			(effects
				(font
					(size 1 1)
					(thickness 0.15)
				)
			)
		)
		(property "Val" "10k"
			(at 0 0 0)
			(layer "F.Fab")
			(hide yes)
			(effects
				(font
					(size 1 1)
					(thickness 0.15)
				)
			)
		)
		(sheetname "2xUSB3.0+RJ45")
		(sheetfile "usb3+rj45.kicad_sch")
		(attr smd dnp)
		(fp_rect
			(start -0.925 -0.47)
			(end 0.925 0.47)
			(stroke
				(width 0.05)
				(type default)
			)
			(fill no)
			(layer "F.CrtYd")
		)
		(fp_rect
			(start -0.5 -0.25)
			(end 0.5 0.25)
			(stroke
				(width 0.15)
				(type solid)
			)
			(fill no)
			(layer "F.Fab")
		)
		(pad "1" smd roundrect
			(at -0.48 0)
			(size 0.59 0.64)
			(layers "F.Cu" "F.Mask" "F.Paste")
			(roundrect_rratio 0.25)
			(net 553 "/2xUSB3.0+RJ45/FLG_1B")
			(pintype "passive")
			(teardrops
				(best_length_ratio 0.2)
				(max_length 1)
				(best_width_ratio 0.9)
				(max_width 2)
				(curved_edges yes)
				(filter_ratio 0.9)
				(enabled yes)
				(allow_two_segments yes)
				(prefer_zone_connections yes)
			)
		)
		(pad "2" smd roundrect
			(at 0.48 0)
			(size 0.59 0.64)
			(layers "F.Cu" "F.Mask" "F.Paste")
			(roundrect_rratio 0.25)
			(net 2 "+3V3")
			(pintype "passive")
			(teardrops
				(best_length_ratio 0.2)
				(max_length 1)
				(best_width_ratio 0.9)
				(max_width 2)
				(curved_edges yes)
				(filter_ratio 0.9)
				(enabled yes)
				(allow_two_segments yes)
				(prefer_zone_connections yes)
			)
		)
	)
	(footprint "antmicro-footprints:LED_0603_1608Metric_G"
		(layer "F.Cu")
		(at 186.70861 74.802163 90)
		(descr "LED SMD 0603 Green")
		(tags "LED SMD 0603 Green")
		(property "Reference" "D31"
			(at -1.1 -0.55 90)
			(layer "F.SilkS")
			(effects
				(font
					(size 0.7 0.7)
					(thickness 0.15)
				)
				(justify left bottom)
			)
		)
		(property "Value" "LED_G_0603_LTST-C190GKT"
			(at -0.001 1.599 90)
			(layer "F.Fab")
			(effects
				(font
					(size 0.7 0.7)
					(thickness 0.15)
				)
				(justify left bottom)
			)
		)
		(property "Datasheet" "https://media.digikey.com/pdf/Data%20Sheets/Lite-On%20PDFs/LTST-C190GKT.pdf"
			(at 0 0 90)
			(layer "F.Fab")
			(hide yes)
			(effects
				(font
					(size 1.27 1.27)
					(thickness 0.15)
				)
			)
		)
		(property "Author" "Antmicro"
			(at 261.510773 -111.906447 0)
			(layer "F.Fab")
			(hide yes)
			(effects
				(font
					(size 1 1)
					(thickness 0.15)
				)
			)
		)
		(property "Color" "Green"
			(at 261.510773 -111.906447 0)
			(layer "F.Fab")
			(hide yes)
			(effects
				(font
					(size 1 1)
					(thickness 0.15)
				)
			)
		)
		(property "License" "Apache-2.0"
			(at 261.510773 -111.906447 0)
			(layer "F.Fab")
			(hide yes)
			(effects
				(font
					(size 1 1)
					(thickness 0.15)
				)
			)
		)
		(property "MPN" "LTST-C190GKT"
			(at 261.510773 -111.906447 0)
			(layer "F.Fab")
			(hide yes)
			(effects
				(font
					(size 1 1)
					(thickness 0.15)
				)
			)
		)
		(property "Manufacturer" "Lite-On"
			(at 261.510773 -111.906447 0)
			(layer "F.Fab")
			(hide yes)
			(effects
				(font
					(size 1 1)
					(thickness 0.15)
				)
			)
		)
		(property "Public" "False"
			(at 261.510773 -111.906447 0)
			(layer "F.Fab")
			(hide yes)
			(effects
				(font
					(size 1 1)
					(thickness 0.15)
				)
			)
		)
		(sheetname "Power")
		(sheetfile "power.kicad_sch")
		(attr smd)
		(fp_line
			(start 0.22 -0.35)
			(end -0.22 -0.35)
			(stroke
				(width 0.15)
				(type solid)
			)
			(layer "F.SilkS")
		)
		(fp_line
			(start -1.18 -0.319)
			(end -1.18 0.321)
			(stroke
				(width 0.15)
				(type solid)
			)
			(layer "F.SilkS")
		)
		(fp_line
			(start 0.105328 0.001008)
			(end 0.24 0.001)
			(stroke
				(width 0.1)
				(type solid)
			)
			(layer "F.SilkS")
		)
		(fp_line
			(start -0.094672 0.001008)
			(end 0.105328 -0.198992)
			(stroke
				(width 0.1)
				(type solid)
			)
			(layer "F.SilkS")
		)
		(fp_line
			(start -0.094672 0.001008)
			(end -0.24 0.001008)
			(stroke
				(width 0.1)
				(type solid)
			)
			(layer "F.SilkS")
		)
		(fp_line
			(start 0.105328 0.201008)
			(end 0.105328 -0.198992)
			(stroke
				(width 0.1)
				(type solid)
			)
			(layer "F.SilkS")
		)
		(fp_line
			(start 0.105328 0.201008)
			(end -0.094672 0.001008)
			(stroke
				(width 0.1)
				(type solid)
			)
			(layer "F.SilkS")
		)
		(fp_line
			(start -0.094672 0.201008)
			(end -0.094672 -0.198992)
			(stroke
				(width 0.1)
				(type solid)
			)
			(layer "F.SilkS")
		)
		(fp_line
			(start 0.22 0.35)
			(end -0.22 0.35)
			(stroke
				(width 0.15)
				(type solid)
			)
			(layer "F.SilkS")
		)
		(fp_rect
			(start 1.25 0.65)
			(end -1.25 -0.65)
			(stroke
				(width 0.05)
				(type solid)
			)
			(fill no)
			(layer "F.CrtYd")
		)
		(fp_line
			(start 0.201 -0.202)
			(end -0.101 0)
			(stroke
				(width 0.15)
				(type solid)
			)
			(layer "F.Fab")
		)
		(fp_line
			(start -0.199 -0.202)
			(end -0.199 0.1)
			(stroke
				(width 0.15)
				(type solid)
			)
			(layer "F.Fab")
		)
		(fp_line
			(start 0.599 0)
			(end 0.201 0)
			(stroke
				(width 0.15)
				(type solid)
			)
			(layer "F.Fab")
		)
		(fp_line
			(start 0.201 0)
			(end 0.201 -0.202)
			(stroke
				(width 0.15)
				(type solid)
			)
			(layer "F.Fab")
		)
		(fp_line
			(start -0.101 0)
			(end 0.201 0.2)
			(stroke
				(width 0.15)
				(type solid)
			)
			(layer "F.Fab")
		)
		(fp_line
			(start -0.199 0)
			(end -0.597 0)
			(stroke
				(width 0.15)
				(type solid)
			)
			(layer "F.Fab")
		)
		(fp_line
			(start 0.201 0.2)
			(end 0.201 0)
			(stroke
				(width 0.15)
				(type solid)
			)
			(layer "F.Fab")
		)
		(fp_line
			(start -0.199 0.2)
			(end -0.199 0.1)
			(stroke
				(width 0.15)
				(type solid)
			)
			(layer "F.Fab")
		)
		(fp_rect
			(start 0.848 0.4)
			(end -0.85 -0.402)
			(stroke
				(width 0.15)
				(type solid)
			)
			(fill no)
			(layer "F.Fab")
		)
		(pad "1" smd roundrect
			(at -0.7 0 270)
			(size 0.8 1)
			(layers "F.Cu" "F.Mask" "F.Paste")
			(roundrect_rratio 0.2)
			(net 983 "Net-(D31-C)")
			(pinfunction "C")
			(pintype "passive")
			(teardrops
				(best_length_ratio 0.2)
				(max_length 1)
				(best_width_ratio 0.9)
				(max_width 2)
				(curved_edges yes)
				(filter_ratio 0.9)
				(enabled yes)
				(allow_two_segments yes)
				(prefer_zone_connections yes)
			)
		)
		(pad "2" smd roundrect
			(at 0.7 0 270)
			(size 0.8 1)
			(layers "F.Cu" "F.Mask" "F.Paste")
			(roundrect_rratio 0.2)
			(net 62 "+12V_AON")
			(pinfunction "A")
			(pintype "passive")
			(teardrops
				(best_length_ratio 0.2)
				(max_length 1)
				(best_width_ratio 0.9)
				(max_width 2)
				(curved_edges yes)
				(filter_ratio 0.9)
				(enabled yes)
				(allow_two_segments yes)
				(prefer_zone_connections yes)
			)
		)
	)
	(footprint "antmicro-footprints:SOT-23-3"
		(layer "F.Cu")
		(at 238.41 127.49 90)
		(property "Reference" "D35"
			(at -1.8 -1.8 90)
			(layer "F.SilkS")
			(effects
				(font
					(size 0.7 0.7)
					(thickness 0.15)
				)
				(justify left bottom)
			)
		)
		(property "Value" "BAT54C"
			(at -1.9 2.7 90)
			(layer "F.Fab")
			(effects
				(font
					(size 0.7 0.7)
					(thickness 0.15)
				)
				(justify left bottom)
			)
		)
		(property "Datasheet" "https://diotec.com/request/datasheet/bat54.pdf"
			(at 0 0 90)
			(layer "F.Fab")
			(hide yes)
			(effects
				(font
					(size 1.27 1.27)
					(thickness 0.15)
				)
			)
		)
		(property "MPN" "BAT54C"
			(at 0 0 90)
			(unlocked yes)
			(layer "F.Fab")
			(hide yes)
			(effects
				(font
					(size 1 1)
					(thickness 0.15)
				)
			)
		)
		(property "Manufacturer" "Diotec Semiconductor"
			(at 0 0 90)
			(unlocked yes)
			(layer "F.Fab")
			(hide yes)
			(effects
				(font
					(size 1 1)
					(thickness 0.15)
				)
			)
		)
		(property "Author" "Antmicro"
			(at 0 0 90)
			(unlocked yes)
			(layer "F.Fab")
			(hide yes)
			(effects
				(font
					(size 1 1)
					(thickness 0.15)
				)
			)
		)
		(property "License" "Apache-2.0"
			(at 0 0 90)
			(unlocked yes)
			(layer "F.Fab")
			(hide yes)
			(effects
				(font
					(size 1 1)
					(thickness 0.15)
				)
			)
		)
		(sheetname "Com Express 7 MGMT")
		(sheetfile "com_express_7_mgmt.kicad_sch")
		(attr smd)
		(fp_line
			(start 0.7 -1.5)
			(end -0.7 -1.5)
			(stroke
				(width 0.15)
				(type solid)
			)
			(layer "F.SilkS")
		)
		(fp_line
			(start -0.85 -1.35)
			(end -0.7 -1.5)
			(stroke
				(width 0.15)
				(type solid)
			)
			(layer "F.SilkS")
		)
		(fp_line
			(start -1.45 -1.35)
			(end -0.85 -1.35)
			(stroke
				(width 0.15)
				(type solid)
			)
			(layer "F.SilkS")
		)
		(fp_line
			(start 0.7 -0.4)
			(end 0.7 -1.5)
			(stroke
				(width 0.15)
				(type solid)
			)
			(layer "F.SilkS")
		)
		(fp_line
			(start 0.7 0.4)
			(end 0.7 1.5)
			(stroke
				(width 0.15)
				(type solid)
			)
			(layer "F.SilkS")
		)
		(fp_line
			(start 0.7 1.5)
			(end -0.7 1.5)
			(stroke
				(width 0.15)
				(type solid)
			)
			(layer "F.SilkS")
		)
		(fp_line
			(start -0.7 1.5)
			(end -0.7 1.35)
			(stroke
				(width 0.15)
				(type solid)
			)
			(layer "F.SilkS")
		)
		(fp_line
			(start 0.825 -1.6)
			(end 0.825 -0.45)
			(stroke
				(width 0.05)
				(type solid)
			)
			(layer "F.CrtYd")
		)
		(fp_line
			(start -0.9 -1.6)
			(end 0.825 -1.6)
			(stroke
				(width 0.05)
				(type solid)
			)
			(layer "F.CrtYd")
		)
		(fp_line
			(start -0.9 -1.6)
			(end -0.9 -1.4)
			(stroke
				(width 0.05)
				(type solid)
			)
			(layer "F.CrtYd")
		)
		(fp_line
			(start -0.9 -1.4)
			(end -1.75 -1.4)
			(stroke
				(width 0.05)
				(type solid)
			)
			(layer "F.CrtYd")
		)
		(fp_line
			(start -0.85 -0.5)
			(end -1.75 -0.5)
			(stroke
				(width 0.05)
				(type solid)
			)
			(layer "F.CrtYd")
		)
		(fp_line
			(start -1.75 -0.5)
			(end -1.75 -1.4)
			(stroke
				(width 0.05)
				(type solid)
			)
			(layer "F.CrtYd")
		)
		(fp_line
			(start 1.75 -0.45)
			(end 1.75 0.45)
			(stroke
				(width 0.05)
				(type solid)
			)
			(layer "F.CrtYd")
		)
		(fp_line
			(start 0.825 -0.45)
			(end 1.75 -0.45)
			(stroke
				(width 0.05)
				(type solid)
			)
			(layer "F.CrtYd")
		)
		(fp_line
			(start 1.75 0.45)
			(end 0.85 0.45)
			(stroke
				(width 0.05)
				(type solid)
			)
			(layer "F.CrtYd")
		)
		(fp_line
			(start 0.85 0.45)
			(end 0.85 1.65)
			(stroke
				(width 0.05)
				(type solid)
			)
			(layer "F.CrtYd")
		)
		(fp_line
			(start -0.85 0.5)
			(end -0.85 -0.5)
			(stroke
				(width 0.05)
				(type solid)
			)
			(layer "F.CrtYd")
		)
		(fp_line
			(start -1.75 0.5)
			(end -0.85 0.5)
			(stroke
				(width 0.05)
				(type solid)
			)
			(layer "F.CrtYd")
		)
		(fp_line
			(start -0.85 1.4)
			(end -1.75 1.4)
			(stroke
				(width 0.05)
				(type solid)
			)
			(layer "F.CrtYd")
		)
		(fp_line
			(start -1.75 1.4)
			(end -1.75 0.5)
			(stroke
				(width 0.05)
				(type solid)
			)
			(layer "F.CrtYd")
		)
		(fp_line
			(start 0.85 1.65)
			(end -0.85 1.65)
			(stroke
				(width 0.05)
				(type solid)
			)
			(layer "F.CrtYd")
		)
		(fp_line
			(start -0.85 1.65)
			(end -0.85 1.4)
			(stroke
				(width 0.05)
				(type solid)
			)
			(layer "F.CrtYd")
		)
		(fp_line
			(start -0.437 -1.526)
			(end 0.688 -1.526)
			(stroke
				(width 0.15)
				(type solid)
			)
			(layer "F.Fab")
		)
		(fp_line
			(start -0.437 -1.526)
			(end -0.712 -1.325)
			(stroke
				(width 0.15)
				(type solid)
			)
			(layer "F.Fab")
		)
		(fp_line
			(start -0.712 -1.325)
			(end -0.712 1.523)
			(stroke
				(width 0.15)
				(type solid)
			)
			(layer "F.Fab")
		)
		(fp_line
			(start 0.688 1.519)
			(end 0.688 -1.52)
			(stroke
				(width 0.15)
				(type solid)
			)
			(layer "F.Fab")
		)
		(fp_line
			(start -0.712 1.519)
			(end 0.688 1.519)
			(stroke
				(width 0.15)
				(type solid)
			)
			(layer "F.Fab")
		)
		(pad "1" smd roundrect
			(at -1.1 -0.951 90)
			(size 1 0.6)
			(layers "F.Cu" "F.Mask" "F.Paste")
			(roundrect_rratio 0.15)
			(net 84 "/Com Express 7 MGMT/PWRBTN")
			(pinfunction "1")
			(pintype "passive")
			(teardrops
				(best_length_ratio 0.2)
				(max_length 1)
				(best_width_ratio 0.9)
				(max_width 2)
				(curved_edges yes)
				(filter_ratio 0.9)
				(enabled yes)
				(allow_two_segments yes)
				(prefer_zone_connections yes)
			)
		)
		(pad "2" smd roundrect
			(at -1.1 0.949 90)
			(size 1 0.6)
			(layers "F.Cu" "F.Mask" "F.Paste")
			(roundrect_rratio 0.15)
			(net 84 "/Com Express 7 MGMT/PWRBTN")
			(pinfunction "2")
			(pintype "passive")
			(teardrops
				(best_length_ratio 0.2)
				(max_length 1)
				(best_width_ratio 0.9)
				(max_width 2)
				(curved_edges yes)
				(filter_ratio 0.9)
				(enabled yes)
				(allow_two_segments yes)
				(prefer_zone_connections yes)
			)
		)
		(pad "3" smd roundrect
			(at 1.1 -0.0005 90)
			(size 1 0.6)
			(layers "F.Cu" "F.Mask" "F.Paste")
			(roundrect_rratio 0.15)
			(net 73 "+3V3_AON")
			(pinfunction "3")
			(pintype "passive")
			(teardrops
				(best_length_ratio 0.2)
				(max_length 1)
				(best_width_ratio 0.9)
				(max_width 2)
				(curved_edges yes)
				(filter_ratio 0.9)
				(enabled yes)
				(allow_two_segments yes)
				(prefer_zone_connections yes)
			)
		)
	)
	(footprint "antmicro-footprints:C_0402_1005Metric"
		(layer "F.Cu")
		(at 129.5 103.38 -90)
		(descr "Capacitor SMD 0402")
		(tags "capacitor SMD 0402")
		(property "Reference" "C13"
			(at -0.93 0.5 90)
			(layer "F.SilkS")
			(effects
				(font
					(size 0.7 0.7)
					(thickness 0.15)
				)
				(justify right bottom)
			)
		)
		(property "Value" "C_100n_0402"
			(at -1.022927 2.155213 90)
			(layer "F.Fab")
			(effects
				(font
					(size 0.7 0.7)
					(thickness 0.15)
				)
				(justify right bottom)
			)
		)
		(property "Datasheet" "https://www.murata.com/products/productdetail?partno=GRM155R61H104KE14%23"
			(at 0 0 270)
			(layer "F.Fab")
			(hide yes)
			(effects
				(font
					(size 1.27 1.27)
					(thickness 0.15)
				)
			)
		)
		(property "Author" "Antmicro"
			(at 26.12 232.88 0)
			(layer "F.Fab")
			(hide yes)
			(effects
				(font
					(size 1 1)
					(thickness 0.15)
				)
			)
		)
		(property "Dielectric" "X5R"
			(at 26.12 232.88 0)
			(layer "F.Fab")
			(hide yes)
			(effects
				(font
					(size 1 1)
					(thickness 0.15)
				)
			)
		)
		(property "License" "Apache-2.0"
			(at 26.12 232.88 0)
			(layer "F.Fab")
			(hide yes)
			(effects
				(font
					(size 1 1)
					(thickness 0.15)
				)
			)
		)
		(property "MPN" "GRM155R61H104KE14D"
			(at 26.12 232.88 0)
			(layer "F.Fab")
			(hide yes)
			(effects
				(font
					(size 1 1)
					(thickness 0.15)
				)
			)
		)
		(property "Manufacturer" "Murata"
			(at 26.12 232.88 0)
			(layer "F.Fab")
			(hide yes)
			(effects
				(font
					(size 1 1)
					(thickness 0.15)
				)
			)
		)
		(property "Public" "False"
			(at 26.12 232.88 0)
			(layer "F.Fab")
			(hide yes)
			(effects
				(font
					(size 1 1)
					(thickness 0.15)
				)
			)
		)
		(property "Val" "100n"
			(at 26.12 232.88 0)
			(layer "F.Fab")
			(hide yes)
			(effects
				(font
					(size 1 1)
					(thickness 0.15)
				)
			)
		)
		(property "Voltage" "50V"
			(at 26.12 232.88 0)
			(layer "F.Fab")
			(hide yes)
			(effects
				(font
					(size 1 1)
					(thickness 0.15)
				)
			)
		)
		(sheetname "2xUSB3.0+RJ45")
		(sheetfile "usb3+rj45.kicad_sch")
		(attr smd)
		(fp_rect
			(start -0.925 -0.47)
			(end 0.925 0.47)
			(stroke
				(width 0.05)
				(type default)
			)
			(fill no)
			(layer "F.CrtYd")
		)
		(fp_line
			(start -0.494 0.248)
			(end -0.494 -0.25)
			(stroke
				(width 0.15)
				(type solid)
			)
			(layer "F.Fab")
		)
		(fp_line
			(start 0.504 0.248)
			(end -0.494 0.248)
			(stroke
				(width 0.15)
				(type solid)
			)
			(layer "F.Fab")
		)
		(fp_line
			(start -0.494 -0.25)
			(end 0.504 -0.25)
			(stroke
				(width 0.15)
				(type solid)
			)
			(layer "F.Fab")
		)
		(fp_line
			(start 0.504 -0.25)
			(end 0.504 0.248)
			(stroke
				(width 0.15)
				(type solid)
			)
			(layer "F.Fab")
		)
		(pad "1" smd roundrect
			(at -0.48 0 270)
			(size 0.59 0.64)
			(layers "F.Cu" "F.Mask" "F.Paste")
			(roundrect_rratio 0.25)
			(net 51 "Net-(C13-Pad1)")
			(pintype "passive")
			(teardrops
				(best_length_ratio 0.2)
				(max_length 1)
				(best_width_ratio 0.9)
				(max_width 2)
				(curved_edges yes)
				(filter_ratio 0.9)
				(enabled yes)
				(allow_two_segments yes)
				(prefer_zone_connections yes)
			)
		)
		(pad "2" smd roundrect
			(at 0.48 0 270)
			(size 0.59 0.64)
			(layers "F.Cu" "F.Mask" "F.Paste")
			(roundrect_rratio 0.25)
			(net 1 "GND")
			(pintype "passive")
			(teardrops
				(best_length_ratio 0.2)
				(max_length 1)
				(best_width_ratio 0.9)
				(max_width 2)
				(curved_edges yes)
				(filter_ratio 0.9)
				(enabled yes)
				(allow_two_segments yes)
				(prefer_zone_connections yes)
			)
		)
	)
	(footprint "antmicro-footprints:R_0402_1005Metric"
		(layer "F.Cu")
		(at 308.05 139.96)
		(descr "Resistor SMD 0402")
		(tags "resistor SMD 0402")
		(property "Reference" "R94"
			(at -1.05 -0.45 0)
			(layer "F.SilkS")
			(effects
				(font
					(size 0.7 0.7)
					(thickness 0.15)
				)
				(justify left bottom)
			)
		)
		(property "Value" "R_100k_0402"
			(at -1.011843 1.772047 0)
			(layer "F.Fab")
			(effects
				(font
					(size 0.7 0.7)
					(thickness 0.15)
				)
				(justify left bottom)
			)
		)
		(property "Datasheet" "https://www.bourns.com/docs/product-datasheets/cr.pdf"
			(at 0 0 0)
			(layer "F.Fab")
			(hide yes)
			(effects
				(font
					(size 1.27 1.27)
					(thickness 0.15)
				)
			)
		)
		(property "Author" "Antmicro"
			(at 0 0 0)
			(layer "F.Fab")
			(hide yes)
			(effects
				(font
					(size 1 1)
					(thickness 0.15)
				)
			)
		)
		(property "License" "Apache-2.0"
			(at 0 0 0)
			(layer "F.Fab")
			(hide yes)
			(effects
				(font
					(size 1 1)
					(thickness 0.15)
				)
			)
		)
		(property "MPN" "CR0402-FX-1003GLF"
			(at 0 0 0)
			(layer "F.Fab")
			(hide yes)
			(effects
				(font
					(size 1 1)
					(thickness 0.15)
				)
			)
		)
		(property "Manufacturer" "Bourns"
			(at 0 0 0)
			(layer "F.Fab")
			(hide yes)
			(effects
				(font
					(size 1 1)
					(thickness 0.15)
				)
			)
		)
		(property "Public" "False"
			(at 0 0 0)
			(layer "F.Fab")
			(hide yes)
			(effects
				(font
					(size 1 1)
					(thickness 0.15)
				)
			)
		)
		(property "Tolerance" "1%"
			(at 0 0 0)
			(layer "F.Fab")
			(hide yes)
			(effects
				(font
					(size 1 1)
					(thickness 0.15)
				)
			)
		)
		(property "Val" "100k"
			(at 0 0 0)
			(layer "F.Fab")
			(hide yes)
			(effects
				(font
					(size 1 1)
					(thickness 0.15)
				)
			)
		)
		(sheetname "Power")
		(sheetfile "power.kicad_sch")
		(attr smd)
		(fp_rect
			(start -0.925 -0.47)
			(end 0.925 0.47)
			(stroke
				(width 0.05)
				(type default)
			)
			(fill no)
			(layer "F.CrtYd")
		)
		(fp_rect
			(start -0.5 -0.25)
			(end 0.5 0.25)
			(stroke
				(width 0.15)
				(type solid)
			)
			(fill no)
			(layer "F.Fab")
		)
		(pad "1" smd roundrect
			(at -0.48 0)
			(size 0.59 0.64)
			(layers "F.Cu" "F.Mask" "F.Paste")
			(roundrect_rratio 0.25)
			(net 534 "Net-(Q1-D)")
			(pintype "passive")
			(teardrops
				(best_length_ratio 0.2)
				(max_length 1)
				(best_width_ratio 0.9)
				(max_width 2)
				(curved_edges yes)
				(filter_ratio 0.9)
				(enabled yes)
				(allow_two_segments yes)
				(prefer_zone_connections yes)
			)
		)
		(pad "2" smd roundrect
			(at 0.48 0)
			(size 0.59 0.64)
			(layers "F.Cu" "F.Mask" "F.Paste")
			(roundrect_rratio 0.25)
			(net 62 "+12V_AON")
			(pintype "passive")
			(teardrops
				(best_length_ratio 0.2)
				(max_length 1)
				(best_width_ratio 0.9)
				(max_width 2)
				(curved_edges yes)
				(filter_ratio 0.9)
				(enabled yes)
				(allow_two_segments yes)
				(prefer_zone_connections yes)
			)
		)
	)
	(footprint "antmicro-footprints:R_0402_1005Metric"
		(layer "F.Cu")
		(at 213.98 135 -90)
		(descr "Resistor SMD 0402")
		(tags "resistor SMD 0402")
		(property "Reference" "R196"
			(at 0.81 -0.42 90)
			(layer "F.SilkS")
			(effects
				(font
					(size 0.7 0.7)
					(thickness 0.15)
				)
				(justify right bottom)
			)
		)
		(property "Value" "R_0R_0402"
			(at -1.011843 1.772047 90)
			(layer "F.Fab")
			(effects
				(font
					(size 0.7 0.7)
					(thickness 0.15)
				)
				(justify right bottom)
			)
		)
		(property "Datasheet" "https://industrial.panasonic.com/cdbs/www-data/pdf/RDA0000/AOA0000C301.pdf"
			(at 0 0 270)
			(layer "F.Fab")
			(hide yes)
			(effects
				(font
					(size 1.27 1.27)
					(thickness 0.15)
				)
			)
		)
		(property "Author" "Antmicro"
			(at 78.98 348.98 0)
			(layer "F.Fab")
			(hide yes)
			(effects
				(font
					(size 1 1)
					(thickness 0.15)
				)
			)
		)
		(property "Current" "1A"
			(at 78.98 348.98 0)
			(layer "F.Fab")
			(hide yes)
			(effects
				(font
					(size 1 1)
					(thickness 0.15)
				)
			)
		)
		(property "License" "Apache-2.0"
			(at 78.98 348.98 0)
			(layer "F.Fab")
			(hide yes)
			(effects
				(font
					(size 1 1)
					(thickness 0.15)
				)
			)
		)
		(property "MPN" "ERJ2GE0R00X"
			(at 78.98 348.98 0)
			(layer "F.Fab")
			(hide yes)
			(effects
				(font
					(size 1 1)
					(thickness 0.15)
				)
			)
		)
		(property "Manufacturer" "Panasonic"
			(at 78.98 348.98 0)
			(layer "F.Fab")
			(hide yes)
			(effects
				(font
					(size 1 1)
					(thickness 0.15)
				)
			)
		)
		(property "Public" "False"
			(at 78.98 348.98 0)
			(layer "F.Fab")
			(hide yes)
			(effects
				(font
					(size 1 1)
					(thickness 0.15)
				)
			)
		)
		(property "Tolerance" ""
			(at 78.98 348.98 0)
			(layer "F.Fab")
			(hide yes)
			(effects
				(font
					(size 1 1)
					(thickness 0.15)
				)
			)
		)
		(property "Val" "0R"
			(at 78.98 348.98 0)
			(layer "F.Fab")
			(hide yes)
			(effects
				(font
					(size 1 1)
					(thickness 0.15)
				)
			)
		)
		(sheetname "PCIe misc")
		(sheetfile "pcie_misc.kicad_sch")
		(attr smd)
		(fp_rect
			(start -0.925 -0.47)
			(end 0.925 0.47)
			(stroke
				(width 0.05)
				(type default)
			)
			(fill no)
			(layer "F.CrtYd")
		)
		(fp_rect
			(start -0.5 -0.25)
			(end 0.5 0.25)
			(stroke
				(width 0.15)
				(type solid)
			)
			(fill no)
			(layer "F.Fab")
		)
		(pad "1" smd roundrect
			(at -0.48 0 270)
			(size 0.59 0.64)
			(layers "F.Cu" "F.Mask" "F.Paste")
			(roundrect_rratio 0.25)
			(net 615 "/PCIe misc/DIF2+")
			(pintype "passive")
			(teardrops
				(best_length_ratio 0.2)
				(max_length 1)
				(best_width_ratio 0.9)
				(max_width 2)
				(curved_edges yes)
				(filter_ratio 0.9)
				(enabled yes)
				(allow_two_segments yes)
				(prefer_zone_connections yes)
			)
		)
		(pad "2" smd roundrect
			(at 0.48 0 270)
			(size 0.59 0.64)
			(layers "F.Cu" "F.Mask" "F.Paste")
			(roundrect_rratio 0.25)
			(net 21 "/M.2 key E/PCIE_{REF}.CK-")
			(pintype "passive")
			(teardrops
				(best_length_ratio 0.2)
				(max_length 1)
				(best_width_ratio 0.9)
				(max_width 2)
				(curved_edges yes)
				(filter_ratio 0.9)
				(enabled yes)
				(allow_two_segments yes)
				(prefer_zone_connections yes)
			)
		)
	)
	(footprint "antmicro-footprints:C_0402_1005Metric"
		(layer "F.Cu")
		(at 258.730708 78.085 -90)
		(descr "Capacitor SMD 0402")
		(tags "capacitor SMD 0402")
		(property "Reference" "C86"
			(at 0.8 -0.465 90)
			(layer "F.SilkS")
			(effects
				(font
					(size 0.7 0.7)
					(thickness 0.15)
				)
				(justify right bottom)
			)
		)
		(property "Value" "C_100n_0402"
			(at -1.022927 2.155213 90)
			(layer "F.Fab")
			(effects
				(font
					(size 0.7 0.7)
					(thickness 0.15)
				)
				(justify right bottom)
			)
		)
		(property "Datasheet" "https://www.murata.com/products/productdetail?partno=GRM155R61H104KE14%23"
			(at 0 0 270)
			(layer "F.Fab")
			(hide yes)
			(effects
				(font
					(size 1.27 1.27)
					(thickness 0.15)
				)
			)
		)
		(property "Author" "Antmicro"
			(at 180.645708 336.815708 0)
			(layer "F.Fab")
			(hide yes)
			(effects
				(font
					(size 1 1)
					(thickness 0.15)
				)
			)
		)
		(property "Dielectric" "X5R"
			(at 180.645708 336.815708 0)
			(layer "F.Fab")
			(hide yes)
			(effects
				(font
					(size 1 1)
					(thickness 0.15)
				)
			)
		)
		(property "License" "Apache-2.0"
			(at 180.645708 336.815708 0)
			(layer "F.Fab")
			(hide yes)
			(effects
				(font
					(size 1 1)
					(thickness 0.15)
				)
			)
		)
		(property "MPN" "GRM155R61H104KE14D"
			(at 180.645708 336.815708 0)
			(layer "F.Fab")
			(hide yes)
			(effects
				(font
					(size 1 1)
					(thickness 0.15)
				)
			)
		)
		(property "Manufacturer" "Murata"
			(at 180.645708 336.815708 0)
			(layer "F.Fab")
			(hide yes)
			(effects
				(font
					(size 1 1)
					(thickness 0.15)
				)
			)
		)
		(property "Public" "False"
			(at 180.645708 336.815708 0)
			(layer "F.Fab")
			(hide yes)
			(effects
				(font
					(size 1 1)
					(thickness 0.15)
				)
			)
		)
		(property "Val" "100n"
			(at 180.645708 336.815708 0)
			(layer "F.Fab")
			(hide yes)
			(effects
				(font
					(size 1 1)
					(thickness 0.15)
				)
			)
		)
		(property "Voltage" "50V"
			(at 180.645708 336.815708 0)
			(layer "F.Fab")
			(hide yes)
			(effects
				(font
					(size 1 1)
					(thickness 0.15)
				)
			)
		)
		(sheetname "Misc")
		(sheetfile "misc.kicad_sch")
		(attr smd)
		(fp_rect
			(start -0.925 -0.47)
			(end 0.925 0.47)
			(stroke
				(width 0.05)
				(type default)
			)
			(fill no)
			(layer "F.CrtYd")
		)
		(fp_line
			(start -0.494 0.248)
			(end -0.494 -0.25)
			(stroke
				(width 0.15)
				(type solid)
			)
			(layer "F.Fab")
		)
		(fp_line
			(start 0.504 0.248)
			(end -0.494 0.248)
			(stroke
				(width 0.15)
				(type solid)
			)
			(layer "F.Fab")
		)
		(fp_line
			(start -0.494 -0.25)
			(end 0.504 -0.25)
			(stroke
				(width 0.15)
				(type solid)
			)
			(layer "F.Fab")
		)
		(fp_line
			(start 0.504 -0.25)
			(end 0.504 0.248)
			(stroke
				(width 0.15)
				(type solid)
			)
			(layer "F.Fab")
		)
		(pad "1" smd roundrect
			(at -0.48 0 270)
			(size 0.59 0.64)
			(layers "F.Cu" "F.Mask" "F.Paste")
			(roundrect_rratio 0.25)
			(net 1 "GND")
			(pintype "passive")
			(teardrops
				(best_length_ratio 0.2)
				(max_length 1)
				(best_width_ratio 0.9)
				(max_width 2)
				(curved_edges yes)
				(filter_ratio 0.9)
				(enabled yes)
				(allow_two_segments yes)
				(prefer_zone_connections yes)
			)
		)
		(pad "2" smd roundrect
			(at 0.48 0 270)
			(size 0.59 0.64)
			(layers "F.Cu" "F.Mask" "F.Paste")
			(roundrect_rratio 0.25)
			(net 2 "+3V3")
			(pintype "passive")
			(teardrops
				(best_length_ratio 0.2)
				(max_length 1)
				(best_width_ratio 0.9)
				(max_width 2)
				(curved_edges yes)
				(filter_ratio 0.9)
				(enabled yes)
				(allow_two_segments yes)
				(prefer_zone_connections yes)
			)
		)
	)
	(footprint "antmicro-footprints:TP_SMD_0.75mm"
		(layer "F.Cu")
		(at 155.7 128.71)
		(property "Reference" "TP72"
			(at 0.4 -3.3 90)
			(layer "F.SilkS")
			(effects
				(font
					(size 0.7 0.7)
					(thickness 0.15)
				)
				(justify left bottom)
			)
		)
		(property "Value" "TP_0.75mm_SMD"
			(at 0 1.2 0)
			(layer "F.Fab")
			(effects
				(font
					(size 0.7 0.7)
					(thickness 0.15)
				)
				(justify left bottom)
			)
		)
		(property "Author" "Antmicro"
			(at 0 0 0)
			(layer "F.Fab")
			(hide yes)
			(effects
				(font
					(size 1 1)
					(thickness 0.15)
				)
			)
		)
		(property "License" "Apache-2.0"
			(at 0 0 0)
			(layer "F.Fab")
			(hide yes)
			(effects
				(font
					(size 1 1)
					(thickness 0.15)
				)
			)
		)
		(property "MPN" ""
			(at 0 0 0)
			(layer "F.Fab")
			(hide yes)
			(effects
				(font
					(size 1 1)
					(thickness 0.15)
				)
			)
		)
		(property "Manufacturer" ""
			(at 0 0 0)
			(layer "F.Fab")
			(hide yes)
			(effects
				(font
					(size 1 1)
					(thickness 0.15)
				)
			)
		)
		(property "Public" "False"
			(at 0 0 0)
			(layer "F.Fab")
			(hide yes)
			(effects
				(font
					(size 1 1)
					(thickness 0.15)
				)
			)
		)
		(sheetname "KR to SFI #1")
		(sheetfile "kr_sfi.kicad_sch")
		(attr exclude_from_pos_files exclude_from_bom)
		(fp_circle
			(center 0 0)
			(end 0.475 0)
			(stroke
				(width 0.05)
				(type default)
			)
			(fill no)
			(layer "F.CrtYd")
		)
		(pad "1" smd circle
			(at 0 0)
			(size 0.75 0.75)
			(layers "F.Cu" "F.Mask")
			(net 735 "Net-(U43A-LS_OK_{IN_A})")
			(pinfunction "1")
			(pintype "passive")
			(teardrops
				(best_length_ratio 0.4)
				(max_length 1)
				(best_width_ratio 0.9)
				(max_width 2)
				(curved_edges yes)
				(filter_ratio 0.9)
				(enabled yes)
				(allow_two_segments yes)
				(prefer_zone_connections yes)
			)
		)
	)
	(footprint "antmicro-footprints:R_0402_1005Metric"
		(layer "F.Cu")
		(at 142.37 144.05)
		(descr "Resistor SMD 0402")
		(tags "resistor SMD 0402")
		(property "Reference" "R247"
			(at -3.72 1.16 0)
			(layer "F.SilkS")
			(effects
				(font
					(size 0.7 0.7)
					(thickness 0.15)
				)
				(justify left bottom)
			)
		)
		(property "Value" "R_0R_0402"
			(at -1.011843 1.772047 0)
			(layer "F.Fab")
			(effects
				(font
					(size 0.7 0.7)
					(thickness 0.15)
				)
				(justify left bottom)
			)
		)
		(property "Datasheet" "https://industrial.panasonic.com/cdbs/www-data/pdf/RDA0000/AOA0000C301.pdf"
			(at 0 0 0)
			(layer "F.Fab")
			(hide yes)
			(effects
				(font
					(size 1.27 1.27)
					(thickness 0.15)
				)
			)
		)
		(property "Author" "Antmicro"
			(at 0 0 0)
			(layer "F.Fab")
			(hide yes)
			(effects
				(font
					(size 1 1)
					(thickness 0.15)
				)
			)
		)
		(property "Current" "1A"
			(at 0 0 0)
			(layer "F.Fab")
			(hide yes)
			(effects
				(font
					(size 1 1)
					(thickness 0.15)
				)
			)
		)
		(property "License" "Apache-2.0"
			(at 0 0 0)
			(layer "F.Fab")
			(hide yes)
			(effects
				(font
					(size 1 1)
					(thickness 0.15)
				)
			)
		)
		(property "MPN" "ERJ2GE0R00X"
			(at 0 0 0)
			(layer "F.Fab")
			(hide yes)
			(effects
				(font
					(size 1 1)
					(thickness 0.15)
				)
			)
		)
		(property "Manufacturer" "Panasonic"
			(at 0 0 0)
			(layer "F.Fab")
			(hide yes)
			(effects
				(font
					(size 1 1)
					(thickness 0.15)
				)
			)
		)
		(property "Public" "False"
			(at 0 0 0)
			(layer "F.Fab")
			(hide yes)
			(effects
				(font
					(size 1 1)
					(thickness 0.15)
				)
			)
		)
		(property "Tolerance" ""
			(at 0 0 0)
			(layer "F.Fab")
			(hide yes)
			(effects
				(font
					(size 1 1)
					(thickness 0.15)
				)
			)
		)
		(property "Val" "0R"
			(at 0 0 0)
			(layer "F.Fab")
			(hide yes)
			(effects
				(font
					(size 1 1)
					(thickness 0.15)
				)
			)
		)
		(sheetname "KR to SFI #1")
		(sheetfile "kr_sfi.kicad_sch")
		(attr smd)
		(fp_rect
			(start -0.925 -0.47)
			(end 0.925 0.47)
			(stroke
				(width 0.05)
				(type default)
			)
			(fill no)
			(layer "F.CrtYd")
		)
		(fp_rect
			(start -0.5 -0.25)
			(end 0.5 0.25)
			(stroke
				(width 0.15)
				(type solid)
			)
			(fill no)
			(layer "F.Fab")
		)
		(pad "1" smd roundrect
			(at -0.48 0)
			(size 0.59 0.64)
			(layers "F.Cu" "F.Mask" "F.Paste")
			(roundrect_rratio 0.25)
			(net 648 "/2xSFP+/KR to SFI #1/MDIO_R")
			(pintype "passive")
			(teardrops
				(best_length_ratio 0.2)
				(max_length 1)
				(best_width_ratio 0.9)
				(max_width 2)
				(curved_edges yes)
				(filter_ratio 0.9)
				(enabled yes)
				(allow_two_segments yes)
				(prefer_zone_connections yes)
			)
		)
		(pad "2" smd roundrect
			(at 0.48 0)
			(size 0.59 0.64)
			(layers "F.Cu" "F.Mask" "F.Paste")
			(roundrect_rratio 0.25)
			(net 649 "/2xSFP+/KR to SFI #1/MDIO")
			(pintype "passive")
			(teardrops
				(best_length_ratio 0.2)
				(max_length 1)
				(best_width_ratio 0.9)
				(max_width 2)
				(curved_edges yes)
				(filter_ratio 0.9)
				(enabled yes)
				(allow_two_segments yes)
				(prefer_zone_connections yes)
			)
		)
	)
	(footprint "antmicro-footprints:R_0402_1005Metric"
		(layer "F.Cu")
		(at 243.8 132.354 90)
		(descr "Resistor SMD 0402")
		(tags "resistor SMD 0402")
		(property "Reference" "R323"
			(at -3.706 0.45 90)
			(layer "F.SilkS")
			(effects
				(font
					(size 0.7 0.7)
					(thickness 0.15)
				)
				(justify left bottom)
			)
		)
		(property "Value" "R_1k_0402"
			(at -1.011843 1.772047 90)
			(layer "F.Fab")
			(effects
				(font
					(size 0.7 0.7)
					(thickness 0.15)
				)
				(justify left bottom)
			)
		)
		(property "Datasheet" "https://www.bourns.com/docs/product-datasheets/cr.pdf"
			(at 0 0 90)
			(layer "F.Fab")
			(hide yes)
			(effects
				(font
					(size 1.27 1.27)
					(thickness 0.15)
				)
			)
		)
		(property "Author" "Antmicro"
			(at 376.154 -111.446 0)
			(layer "F.Fab")
			(hide yes)
			(effects
				(font
					(size 1 1)
					(thickness 0.15)
				)
			)
		)
		(property "License" "Apache-2.0"
			(at 376.154 -111.446 0)
			(layer "F.Fab")
			(hide yes)
			(effects
				(font
					(size 1 1)
					(thickness 0.15)
				)
			)
		)
		(property "MPN" "CR0402-FX-1001GLF"
			(at 376.154 -111.446 0)
			(layer "F.Fab")
			(hide yes)
			(effects
				(font
					(size 1 1)
					(thickness 0.15)
				)
			)
		)
		(property "Manufacturer" "Bourns"
			(at 376.154 -111.446 0)
			(layer "F.Fab")
			(hide yes)
			(effects
				(font
					(size 1 1)
					(thickness 0.15)
				)
			)
		)
		(property "Public" "False"
			(at 376.154 -111.446 0)
			(layer "F.Fab")
			(hide yes)
			(effects
				(font
					(size 1 1)
					(thickness 0.15)
				)
			)
		)
		(property "Tolerance" "1%"
			(at 376.154 -111.446 0)
			(layer "F.Fab")
			(hide yes)
			(effects
				(font
					(size 1 1)
					(thickness 0.15)
				)
			)
		)
		(property "Val" "1k"
			(at 376.154 -111.446 0)
			(layer "F.Fab")
			(hide yes)
			(effects
				(font
					(size 1 1)
					(thickness 0.15)
				)
			)
		)
		(sheetname "Com Express 7 MGMT")
		(sheetfile "com_express_7_mgmt.kicad_sch")
		(attr smd)
		(fp_rect
			(start -0.925 -0.47)
			(end 0.925 0.47)
			(stroke
				(width 0.05)
				(type default)
			)
			(fill no)
			(layer "F.CrtYd")
		)
		(fp_rect
			(start -0.5 -0.25)
			(end 0.5 0.25)
			(stroke
				(width 0.15)
				(type solid)
			)
			(fill no)
			(layer "F.Fab")
		)
		(pad "1" smd roundrect
			(at -0.48 0 90)
			(size 0.59 0.64)
			(layers "F.Cu" "F.Mask" "F.Paste")
			(roundrect_rratio 0.25)
			(net 533 "/Com Express 7 MGMT/PSON")
			(pintype "passive")
			(teardrops
				(best_length_ratio 0.2)
				(max_length 1)
				(best_width_ratio 0.9)
				(max_width 2)
				(curved_edges yes)
				(filter_ratio 0.9)
				(enabled yes)
				(allow_two_segments yes)
				(prefer_zone_connections yes)
			)
		)
		(pad "2" smd roundrect
			(at 0.48 0 90)
			(size 0.59 0.64)
			(layers "F.Cu" "F.Mask" "F.Paste")
			(roundrect_rratio 0.25)
			(net 873 "Net-(U34-EN)")
			(pintype "passive")
			(teardrops
				(best_length_ratio 0.2)
				(max_length 1)
				(best_width_ratio 0.9)
				(max_width 2)
				(curved_edges yes)
				(filter_ratio 0.9)
				(enabled yes)
				(allow_two_segments yes)
				(prefer_zone_connections yes)
			)
		)
	)
	(footprint "antmicro-footprints:TP_SMD_0.75mm"
		(layer "F.Cu")
		(at 127.79 129.56)
		(property "Reference" "TP95"
			(at 0.46 -1.25 90)
			(layer "F.SilkS")
			(effects
				(font
					(size 0.7 0.7)
					(thickness 0.15)
				)
				(justify left bottom)
			)
		)
		(property "Value" "TP_0.75mm_SMD"
			(at 0 1.2 0)
			(layer "F.Fab")
			(effects
				(font
					(size 0.7 0.7)
					(thickness 0.15)
				)
				(justify left bottom)
			)
		)
		(property "Author" "Antmicro"
			(at 0 0 0)
			(layer "F.Fab")
			(hide yes)
			(effects
				(font
					(size 1 1)
					(thickness 0.15)
				)
			)
		)
		(property "License" "Apache-2.0"
			(at 0 0 0)
			(layer "F.Fab")
			(hide yes)
			(effects
				(font
					(size 1 1)
					(thickness 0.15)
				)
			)
		)
		(property "MPN" ""
			(at 0 0 0)
			(layer "F.Fab")
			(hide yes)
			(effects
				(font
					(size 1 1)
					(thickness 0.15)
				)
			)
		)
		(property "Manufacturer" ""
			(at 0 0 0)
			(layer "F.Fab")
			(hide yes)
			(effects
				(font
					(size 1 1)
					(thickness 0.15)
				)
			)
		)
		(property "Public" "False"
			(at 0 0 0)
			(layer "F.Fab")
			(hide yes)
			(effects
				(font
					(size 1 1)
					(thickness 0.15)
				)
			)
		)
		(sheetname "KR to SFI #2")
		(sheetfile "kr_sfi.kicad_sch")
		(attr exclude_from_pos_files exclude_from_bom)
		(fp_circle
			(center 0 0)
			(end 0.475 0)
			(stroke
				(width 0.05)
				(type default)
			)
			(fill no)
			(layer "F.CrtYd")
		)
		(pad "1" smd circle
			(at 0 0)
			(size 0.75 0.75)
			(layers "F.Cu" "F.Mask")
			(net 758 "Net-(U45B-LS_OK_{IN_B})")
			(pinfunction "1")
			(pintype "passive")
			(teardrops
				(best_length_ratio 0.4)
				(max_length 1)
				(best_width_ratio 0.9)
				(max_width 2)
				(curved_edges yes)
				(filter_ratio 0.9)
				(enabled yes)
				(allow_two_segments yes)
				(prefer_zone_connections yes)
			)
		)
	)
	(footprint "antmicro-footprints:R_0402_1005Metric"
		(layer "F.Cu")
		(at 289.85 101.86)
		(descr "Resistor SMD 0402")
		(tags "resistor SMD 0402")
		(property "Reference" "R117"
			(at -1.45 2.35 0)
			(layer "F.SilkS")
			(effects
				(font
					(size 0.7 0.7)
					(thickness 0.15)
				)
				(justify left bottom)
			)
		)
		(property "Value" "R_30k_0402"
			(at -1.011843 1.772047 0)
			(layer "F.Fab")
			(effects
				(font
					(size 0.7 0.7)
					(thickness 0.15)
				)
				(justify left bottom)
			)
		)
		(property "Datasheet" "https://www.bourns.com/docs/product-datasheets/cr.pdf"
			(at 0 0 0)
			(layer "F.Fab")
			(hide yes)
			(effects
				(font
					(size 1.27 1.27)
					(thickness 0.15)
				)
			)
		)
		(property "Author" "Antmicro"
			(at 0 0 0)
			(layer "F.Fab")
			(hide yes)
			(effects
				(font
					(size 1 1)
					(thickness 0.15)
				)
			)
		)
		(property "License" "Apache-2.0"
			(at 0 0 0)
			(layer "F.Fab")
			(hide yes)
			(effects
				(font
					(size 1 1)
					(thickness 0.15)
				)
			)
		)
		(property "MPN" "CR0402-FX-3002GLF"
			(at 0 0 0)
			(layer "F.Fab")
			(hide yes)
			(effects
				(font
					(size 1 1)
					(thickness 0.15)
				)
			)
		)
		(property "Manufacturer" "Bourns"
			(at 0 0 0)
			(layer "F.Fab")
			(hide yes)
			(effects
				(font
					(size 1 1)
					(thickness 0.15)
				)
			)
		)
		(property "Public" "False"
			(at 0 0 0)
			(layer "F.Fab")
			(hide yes)
			(effects
				(font
					(size 1 1)
					(thickness 0.15)
				)
			)
		)
		(property "Tolerance" "1%"
			(at 0 0 0)
			(layer "F.Fab")
			(hide yes)
			(effects
				(font
					(size 1 1)
					(thickness 0.15)
				)
			)
		)
		(property "Val" "30k"
			(at 0 0 0)
			(layer "F.Fab")
			(hide yes)
			(effects
				(font
					(size 1 1)
					(thickness 0.15)
				)
			)
		)
		(sheetname "Power")
		(sheetfile "power.kicad_sch")
		(attr smd)
		(fp_rect
			(start -0.925 -0.47)
			(end 0.925 0.47)
			(stroke
				(width 0.05)
				(type default)
			)
			(fill no)
			(layer "F.CrtYd")
		)
		(fp_rect
			(start -0.5 -0.25)
			(end 0.5 0.25)
			(stroke
				(width 0.15)
				(type solid)
			)
			(fill no)
			(layer "F.Fab")
		)
		(pad "1" smd roundrect
			(at -0.48 0)
			(size 0.59 0.64)
			(layers "F.Cu" "F.Mask" "F.Paste")
			(roundrect_rratio 0.25)
			(net 535 "Net-(Q3-G)")
			(pintype "passive")
			(teardrops
				(best_length_ratio 0.2)
				(max_length 1)
				(best_width_ratio 0.9)
				(max_width 2)
				(curved_edges yes)
				(filter_ratio 0.9)
				(enabled yes)
				(allow_two_segments yes)
				(prefer_zone_connections yes)
			)
		)
		(pad "2" smd roundrect
			(at 0.48 0)
			(size 0.59 0.64)
			(layers "F.Cu" "F.Mask" "F.Paste")
			(roundrect_rratio 0.25)
			(net 1 "GND")
			(pintype "passive")
			(teardrops
				(best_length_ratio 0.2)
				(max_length 1)
				(best_width_ratio 0.9)
				(max_width 2)
				(curved_edges yes)
				(filter_ratio 0.9)
				(enabled yes)
				(allow_two_segments yes)
				(prefer_zone_connections yes)
			)
		)
	)
	(footprint "antmicro-footprints:SOT-23-3"
		(layer "F.Cu")
		(at 250.9 127.16 180)
		(property "Reference" "Q11"
			(at 0.95 2.65 90)
			(layer "F.SilkS")
			(effects
				(font
					(size 0.7 0.7)
					(thickness 0.15)
				)
				(justify right bottom)
			)
		)
		(property "Value" "BSS138-7-F"
			(at -1.9 2.7 0)
			(layer "F.Fab")
			(effects
				(font
					(size 0.7 0.7)
					(thickness 0.15)
				)
				(justify right bottom)
			)
		)
		(property "Datasheet" "https://www.diodes.com/assets/Datasheets/ds30144.pdf"
			(at 0 0 180)
			(layer "F.Fab")
			(hide yes)
			(effects
				(font
					(size 1.27 1.27)
					(thickness 0.15)
				)
			)
		)
		(property "Author" "Antmicro"
			(at 501.8 254.32 0)
			(layer "F.Fab")
			(hide yes)
			(effects
				(font
					(size 1 1)
					(thickness 0.15)
				)
			)
		)
		(property "License" "Apache-2.0"
			(at 501.8 254.32 0)
			(layer "F.Fab")
			(hide yes)
			(effects
				(font
					(size 1 1)
					(thickness 0.15)
				)
			)
		)
		(property "MPN" "BSS138-7-F"
			(at 501.8 254.32 0)
			(layer "F.Fab")
			(hide yes)
			(effects
				(font
					(size 1 1)
					(thickness 0.15)
				)
			)
		)
		(property "Manufacturer" "Diodes Incorporated"
			(at 501.8 254.32 0)
			(layer "F.Fab")
			(hide yes)
			(effects
				(font
					(size 1 1)
					(thickness 0.15)
				)
			)
		)
		(sheetname "Com Express 7 MGMT")
		(sheetfile "com_express_7_mgmt.kicad_sch")
		(attr smd)
		(fp_line
			(start 0.7 1.5)
			(end -0.7 1.5)
			(stroke
				(width 0.15)
				(type solid)
			)
			(layer "F.SilkS")
		)
		(fp_line
			(start 0.7 0.4)
			(end 0.7 1.5)
			(stroke
				(width 0.15)
				(type solid)
			)
			(layer "F.SilkS")
		)
		(fp_line
			(start 0.7 -0.4)
			(end 0.7 -1.5)
			(stroke
				(width 0.15)
				(type solid)
			)
			(layer "F.SilkS")
		)
		(fp_line
			(start 0.7 -1.5)
			(end -0.7 -1.5)
			(stroke
				(width 0.15)
				(type solid)
			)
			(layer "F.SilkS")
		)
		(fp_line
			(start -0.7 1.5)
			(end -0.7 1.35)
			(stroke
				(width 0.15)
				(type solid)
			)
			(layer "F.SilkS")
		)
		(fp_line
			(start -0.85 -1.35)
			(end -0.7 -1.5)
			(stroke
				(width 0.15)
				(type solid)
			)
			(layer "F.SilkS")
		)
		(fp_line
			(start -1.45 -1.35)
			(end -0.85 -1.35)
			(stroke
				(width 0.15)
				(type solid)
			)
			(layer "F.SilkS")
		)
		(fp_line
			(start 1.75 0.45)
			(end 0.85 0.45)
			(stroke
				(width 0.05)
				(type solid)
			)
			(layer "F.CrtYd")
		)
		(fp_line
			(start 1.75 -0.45)
			(end 1.75 0.45)
			(stroke
				(width 0.05)
				(type solid)
			)
			(layer "F.CrtYd")
		)
		(fp_line
			(start 0.85 1.65)
			(end -0.85 1.65)
			(stroke
				(width 0.05)
				(type solid)
			)
			(layer "F.CrtYd")
		)
		(fp_line
			(start 0.85 0.45)
			(end 0.85 1.65)
			(stroke
				(width 0.05)
				(type solid)
			)
			(layer "F.CrtYd")
		)
		(fp_line
			(start 0.825 -0.45)
			(end 1.75 -0.45)
			(stroke
				(width 0.05)
				(type solid)
			)
			(layer "F.CrtYd")
		)
		(fp_line
			(start 0.825 -1.6)
			(end 0.825 -0.45)
			(stroke
				(width 0.05)
				(type solid)
			)
			(layer "F.CrtYd")
		)
		(fp_line
			(start -0.85 1.65)
			(end -0.85 1.4)
			(stroke
				(width 0.05)
				(type solid)
			)
			(layer "F.CrtYd")
		)
		(fp_line
			(start -0.85 1.4)
			(end -1.75 1.4)
			(stroke
				(width 0.05)
				(type solid)
			)
			(layer "F.CrtYd")
		)
		(fp_line
			(start -0.85 0.5)
			(end -0.85 -0.5)
			(stroke
				(width 0.05)
				(type solid)
			)
			(layer "F.CrtYd")
		)
		(fp_line
			(start -0.85 -0.5)
			(end -1.75 -0.5)
			(stroke
				(width 0.05)
				(type solid)
			)
			(layer "F.CrtYd")
		)
		(fp_line
			(start -0.9 -1.4)
			(end -1.75 -1.4)
			(stroke
				(width 0.05)
				(type solid)
			)
			(layer "F.CrtYd")
		)
		(fp_line
			(start -0.9 -1.6)
			(end 0.825 -1.6)
			(stroke
				(width 0.05)
				(type solid)
			)
			(layer "F.CrtYd")
		)
		(fp_line
			(start -0.9 -1.6)
			(end -0.9 -1.4)
			(stroke
				(width 0.05)
				(type solid)
			)
			(layer "F.CrtYd")
		)
		(fp_line
			(start -1.75 1.4)
			(end -1.75 0.5)
			(stroke
				(width 0.05)
				(type solid)
			)
			(layer "F.CrtYd")
		)
		(fp_line
			(start -1.75 0.5)
			(end -0.85 0.5)
			(stroke
				(width 0.05)
				(type solid)
			)
			(layer "F.CrtYd")
		)
		(fp_line
			(start -1.75 -0.5)
			(end -1.75 -1.4)
			(stroke
				(width 0.05)
				(type solid)
			)
			(layer "F.CrtYd")
		)
		(fp_line
			(start 0.688 1.519)
			(end 0.688 -1.52)
			(stroke
				(width 0.15)
				(type solid)
			)
			(layer "F.Fab")
		)
		(fp_line
			(start -0.437 -1.526)
			(end 0.688 -1.526)
			(stroke
				(width 0.15)
				(type solid)
			)
			(layer "F.Fab")
		)
		(fp_line
			(start -0.437 -1.526)
			(end -0.712 -1.325)
			(stroke
				(width 0.15)
				(type solid)
			)
			(layer "F.Fab")
		)
		(fp_line
			(start -0.712 1.519)
			(end 0.688 1.519)
			(stroke
				(width 0.15)
				(type solid)
			)
			(layer "F.Fab")
		)
		(fp_line
			(start -0.712 -1.325)
			(end -0.712 1.523)
			(stroke
				(width 0.15)
				(type solid)
			)
			(layer "F.Fab")
		)
		(pad "1" smd roundrect
			(at -1.1 -0.951 180)
			(size 1 0.6)
			(layers "F.Cu" "F.Mask" "F.Paste")
			(roundrect_rratio 0.15)
			(net 545 "Net-(Q11-G)")
			(pinfunction "G")
			(pintype "bidirectional")
			(teardrops
				(best_length_ratio 0.2)
				(max_length 1)
				(best_width_ratio 0.9)
				(max_width 2)
				(curved_edges yes)
				(filter_ratio 0.9)
				(enabled yes)
				(allow_two_segments yes)
				(prefer_zone_connections yes)
			)
		)
		(pad "2" smd roundrect
			(at -1.1 0.949 180)
			(size 1 0.6)
			(layers "F.Cu" "F.Mask" "F.Paste")
			(roundrect_rratio 0.15)
			(net 1 "GND")
			(pinfunction "S")
			(pintype "bidirectional")
			(teardrops
				(best_length_ratio 0.2)
				(max_length 1)
				(best_width_ratio 0.9)
				(max_width 2)
				(curved_edges yes)
				(filter_ratio 0.9)
				(enabled yes)
				(allow_two_segments yes)
				(prefer_zone_connections yes)
			)
		)
		(pad "3" smd roundrect
			(at 1.1 -0.0005 180)
			(size 1 0.6)
			(layers "F.Cu" "F.Mask" "F.Paste")
			(roundrect_rratio 0.15)
			(net 83 "Net-(Q11-D)")
			(pinfunction "D")
			(pintype "bidirectional")
			(teardrops
				(best_length_ratio 0.2)
				(max_length 1)
				(best_width_ratio 0.9)
				(max_width 2)
				(curved_edges yes)
				(filter_ratio 0.9)
				(enabled yes)
				(allow_two_segments yes)
				(prefer_zone_connections yes)
			)
		)
	)
	(footprint "antmicro-footprints:TP_SMD_0.75mm"
		(layer "F.Cu")
		(at 131.69 129.56)
		(property "Reference" "TP91"
			(at 0.46 -1.25 90)
			(layer "F.SilkS")
			(effects
				(font
					(size 0.7 0.7)
					(thickness 0.15)
				)
				(justify left bottom)
			)
		)
		(property "Value" "TP_0.75mm_SMD"
			(at 0 1.2 0)
			(layer "F.Fab")
			(effects
				(font
					(size 0.7 0.7)
					(thickness 0.15)
				)
				(justify left bottom)
			)
		)
		(property "Author" "Antmicro"
			(at 0 0 0)
			(layer "F.Fab")
			(hide yes)
			(effects
				(font
					(size 1 1)
					(thickness 0.15)
				)
			)
		)
		(property "License" "Apache-2.0"
			(at 0 0 0)
			(layer "F.Fab")
			(hide yes)
			(effects
				(font
					(size 1 1)
					(thickness 0.15)
				)
			)
		)
		(property "MPN" ""
			(at 0 0 0)
			(layer "F.Fab")
			(hide yes)
			(effects
				(font
					(size 1 1)
					(thickness 0.15)
				)
			)
		)
		(property "Manufacturer" ""
			(at 0 0 0)
			(layer "F.Fab")
			(hide yes)
			(effects
				(font
					(size 1 1)
					(thickness 0.15)
				)
			)
		)
		(property "Public" "False"
			(at 0 0 0)
			(layer "F.Fab")
			(hide yes)
			(effects
				(font
					(size 1 1)
					(thickness 0.15)
				)
			)
		)
		(sheetname "KR to SFI #2")
		(sheetfile "kr_sfi.kicad_sch")
		(attr exclude_from_pos_files exclude_from_bom)
		(fp_circle
			(center 0 0)
			(end 0.475 0)
			(stroke
				(width 0.05)
				(type default)
			)
			(fill no)
			(layer "F.CrtYd")
		)
		(pad "1" smd circle
			(at 0 0)
			(size 0.75 0.75)
			(layers "F.Cu" "F.Mask")
			(net 754 "Net-(U45A-LOSA)")
			(pinfunction "1")
			(pintype "passive")
			(teardrops
				(best_length_ratio 0.4)
				(max_length 1)
				(best_width_ratio 0.9)
				(max_width 2)
				(curved_edges yes)
				(filter_ratio 0.9)
				(enabled yes)
				(allow_two_segments yes)
				(prefer_zone_connections yes)
			)
		)
	)
	(footprint "antmicro-footprints:R_0402_1005Metric"
		(layer "F.Cu")
		(at 122.05 92.96 180)
		(descr "Resistor SMD 0402")
		(tags "resistor SMD 0402")
		(property "Reference" "R28"
			(at -2.95 -0.4 0)
			(layer "F.SilkS")
			(effects
				(font
					(size 0.7 0.7)
					(thickness 0.15)
				)
				(justify right bottom)
			)
		)
		(property "Value" "R_0R_0402"
			(at -1.011843 1.772047 0)
			(layer "F.Fab")
			(effects
				(font
					(size 0.7 0.7)
					(thickness 0.15)
				)
				(justify right bottom)
			)
		)
		(property "Datasheet" "https://industrial.panasonic.com/cdbs/www-data/pdf/RDA0000/AOA0000C301.pdf"
			(at 0 0 180)
			(layer "F.Fab")
			(hide yes)
			(effects
				(font
					(size 1.27 1.27)
					(thickness 0.15)
				)
			)
		)
		(property "Author" "Antmicro"
			(at 244.1 185.92 0)
			(layer "F.Fab")
			(hide yes)
			(effects
				(font
					(size 1 1)
					(thickness 0.15)
				)
			)
		)
		(property "Current" "1A"
			(at 244.1 185.92 0)
			(layer "F.Fab")
			(hide yes)
			(effects
				(font
					(size 1 1)
					(thickness 0.15)
				)
			)
		)
		(property "License" "Apache-2.0"
			(at 244.1 185.92 0)
			(layer "F.Fab")
			(hide yes)
			(effects
				(font
					(size 1 1)
					(thickness 0.15)
				)
			)
		)
		(property "MPN" "ERJ2GE0R00X"
			(at 244.1 185.92 0)
			(layer "F.Fab")
			(hide yes)
			(effects
				(font
					(size 1 1)
					(thickness 0.15)
				)
			)
		)
		(property "Manufacturer" "Panasonic"
			(at 244.1 185.92 0)
			(layer "F.Fab")
			(hide yes)
			(effects
				(font
					(size 1 1)
					(thickness 0.15)
				)
			)
		)
		(property "Public" "False"
			(at 244.1 185.92 0)
			(layer "F.Fab")
			(hide yes)
			(effects
				(font
					(size 1 1)
					(thickness 0.15)
				)
			)
		)
		(property "Tolerance" ""
			(at 244.1 185.92 0)
			(layer "F.Fab")
			(hide yes)
			(effects
				(font
					(size 1 1)
					(thickness 0.15)
				)
			)
		)
		(property "Val" "0R"
			(at 244.1 185.92 0)
			(layer "F.Fab")
			(hide yes)
			(effects
				(font
					(size 1 1)
					(thickness 0.15)
				)
			)
		)
		(sheetname "2xUSB3.0+RJ45")
		(sheetfile "usb3+rj45.kicad_sch")
		(attr smd)
		(fp_rect
			(start -0.925 -0.47)
			(end 0.925 0.47)
			(stroke
				(width 0.05)
				(type default)
			)
			(fill no)
			(layer "F.CrtYd")
		)
		(fp_rect
			(start -0.5 -0.25)
			(end 0.5 0.25)
			(stroke
				(width 0.15)
				(type solid)
			)
			(fill no)
			(layer "F.Fab")
		)
		(pad "1" smd roundrect
			(at -0.48 0 180)
			(size 0.59 0.64)
			(layers "F.Cu" "F.Mask" "F.Paste")
			(roundrect_rratio 0.25)
			(net 314 "/2xUSB3.0+RJ45/FLG_1")
			(pintype "passive")
			(teardrops
				(best_length_ratio 0.2)
				(max_length 1)
				(best_width_ratio 0.9)
				(max_width 2)
				(curved_edges yes)
				(filter_ratio 0.9)
				(enabled yes)
				(allow_two_segments yes)
				(prefer_zone_connections yes)
			)
		)
		(pad "2" smd roundrect
			(at 0.48 0 180)
			(size 0.59 0.64)
			(layers "F.Cu" "F.Mask" "F.Paste")
			(roundrect_rratio 0.25)
			(net 554 "/2xUSB3.0+RJ45/FLG_2B")
			(pintype "passive")
			(teardrops
				(best_length_ratio 0.2)
				(max_length 1)
				(best_width_ratio 0.9)
				(max_width 2)
				(curved_edges yes)
				(filter_ratio 0.9)
				(enabled yes)
				(allow_two_segments yes)
				(prefer_zone_connections yes)
			)
		)
	)
	(footprint "antmicro-footprints:R_0402_1005Metric"
		(layer "F.Cu")
		(at 155.299 165.36 180)
		(descr "Resistor SMD 0402")
		(tags "resistor SMD 0402")
		(property "Reference" "R63"
			(at -4.551 18.05 0)
			(layer "F.SilkS")
			(effects
				(font
					(size 0.7 0.7)
					(thickness 0.15)
				)
				(justify left bottom)
			)
		)
		(property "Value" "R_220R_0402"
			(at -1.011843 1.772047 0)
			(layer "F.Fab")
			(effects
				(font
					(size 0.7 0.7)
					(thickness 0.15)
				)
				(justify right bottom)
			)
		)
		(property "Datasheet" "https://www.bourns.com/docs/product-datasheets/cr.pdf"
			(at 0 0 180)
			(layer "F.Fab")
			(hide yes)
			(effects
				(font
					(size 1.27 1.27)
					(thickness 0.15)
				)
			)
		)
		(property "Author" "Antmicro"
			(at 310.598 330.72 0)
			(layer "F.Fab")
			(hide yes)
			(effects
				(font
					(size 1 1)
					(thickness 0.15)
				)
			)
		)
		(property "License" "Apache-2.0"
			(at 310.598 330.72 0)
			(layer "F.Fab")
			(hide yes)
			(effects
				(font
					(size 1 1)
					(thickness 0.15)
				)
			)
		)
		(property "MPN" "CR0402-FX-2200GLF"
			(at 310.598 330.72 0)
			(layer "F.Fab")
			(hide yes)
			(effects
				(font
					(size 1 1)
					(thickness 0.15)
				)
			)
		)
		(property "Manufacturer" "Bourns"
			(at 310.598 330.72 0)
			(layer "F.Fab")
			(hide yes)
			(effects
				(font
					(size 1 1)
					(thickness 0.15)
				)
			)
		)
		(property "Public" "False"
			(at 310.598 330.72 0)
			(layer "F.Fab")
			(hide yes)
			(effects
				(font
					(size 1 1)
					(thickness 0.15)
				)
			)
		)
		(property "Tolerance" "1%"
			(at 310.598 330.72 0)
			(layer "F.Fab")
			(hide yes)
			(effects
				(font
					(size 1 1)
					(thickness 0.15)
				)
			)
		)
		(property "Val" "220R"
			(at 310.598 330.72 0)
			(layer "F.Fab")
			(hide yes)
			(effects
				(font
					(size 1 1)
					(thickness 0.15)
				)
			)
		)
		(sheetname "2xSFP+")
		(sheetfile "2xSFP+.kicad_sch")
		(attr smd)
		(fp_rect
			(start -0.925 -0.47)
			(end 0.925 0.47)
			(stroke
				(width 0.05)
				(type default)
			)
			(fill no)
			(layer "F.CrtYd")
		)
		(fp_rect
			(start -0.5 -0.25)
			(end 0.5 0.25)
			(stroke
				(width 0.15)
				(type solid)
			)
			(fill no)
			(layer "F.Fab")
		)
		(pad "1" smd roundrect
			(at -0.48 0 180)
			(size 0.59 0.64)
			(layers "F.Cu" "F.Mask" "F.Paste")
			(roundrect_rratio 0.25)
			(net 939 "/2xSFP+/SFP0_LEDY")
			(pintype "passive")
			(teardrops
				(best_length_ratio 0.2)
				(max_length 1)
				(best_width_ratio 0.9)
				(max_width 2)
				(curved_edges yes)
				(filter_ratio 0.9)
				(enabled yes)
				(allow_two_segments yes)
				(prefer_zone_connections yes)
			)
		)
		(pad "2" smd roundrect
			(at 0.48 0 180)
			(size 0.59 0.64)
			(layers "F.Cu" "F.Mask" "F.Paste")
			(roundrect_rratio 0.25)
			(net 899 "Net-(D4-C)")
			(pintype "passive")
			(teardrops
				(best_length_ratio 0.2)
				(max_length 1)
				(best_width_ratio 0.9)
				(max_width 2)
				(curved_edges yes)
				(filter_ratio 0.9)
				(enabled yes)
				(allow_two_segments yes)
				(prefer_zone_connections yes)
			)
		)
	)
	(footprint "antmicro-footprints:SOT-23-5"
		(layer "F.Cu")
		(at 255.825 127.16)
		(property "Reference" "U32"
			(at 0.275 -1.8 90)
			(layer "F.SilkS")
			(effects
				(font
					(size 0.7 0.7)
					(thickness 0.15)
				)
				(justify left bottom)
			)
		)
		(property "Value" "TPS3840PL30DBVR"
			(at 0.002 2.799 0)
			(layer "F.Fab")
			(effects
				(font
					(size 0.7 0.7)
					(thickness 0.15)
				)
				(justify left bottom)
			)
		)
		(property "Datasheet" "https://www.ti.com/lit/ds/symlink/tps3840.pdf?HQS=dis-mous-null-mousermode-dsf-pf-null-wwe&DCM=yes&ref_url=https%3A%2F%2Fwww.mouser.com%2F&distId=26"
			(at 0 0 0)
			(layer "F.Fab")
			(hide yes)
			(effects
				(font
					(size 1.27 1.27)
					(thickness 0.15)
				)
			)
		)
		(property "Author" "Antmicro"
			(at 0 0 0)
			(layer "F.Fab")
			(hide yes)
			(effects
				(font
					(size 1 1)
					(thickness 0.15)
				)
			)
		)
		(property "License" "Apache-2.0"
			(at 0 0 0)
			(layer "F.Fab")
			(hide yes)
			(effects
				(font
					(size 1 1)
					(thickness 0.15)
				)
			)
		)
		(property "MPN" "TPS3840PL30DBVR"
			(at 0 0 0)
			(layer "F.Fab")
			(hide yes)
			(effects
				(font
					(size 1 1)
					(thickness 0.15)
				)
			)
		)
		(property "Manufacturer" "Texas Instruments"
			(at 0 0 0)
			(layer "F.Fab")
			(hide yes)
			(effects
				(font
					(size 1 1)
					(thickness 0.15)
				)
			)
		)
		(property ki_fp_filters "DBV0005A_N DBV0005A_M DBV0005A_L")
		(sheetname "Com Express 7 MGMT")
		(sheetfile "com_express_7_mgmt.kicad_sch")
		(attr smd)
		(fp_line
			(start -0.85 1.6)
			(end -0.85 1.301)
			(stroke
				(width 0.15)
				(type solid)
			)
			(layer "F.SilkS")
		)
		(fp_line
			(start -0.8 -1.6)
			(end -0.8 -1.3)
			(stroke
				(width 0.15)
				(type solid)
			)
			(layer "F.SilkS")
		)
		(fp_line
			(start -0.8 -1.6)
			(end -0.5 -1.6)
			(stroke
				(width 0.15)
				(type solid)
			)
			(layer "F.SilkS")
		)
		(fp_line
			(start -0.55 1.6)
			(end -0.85 1.6)
			(stroke
				(width 0.15)
				(type solid)
			)
			(layer "F.SilkS")
		)
		(fp_line
			(start 0.8 -1.6)
			(end 0.5 -1.6)
			(stroke
				(width 0.15)
				(type solid)
			)
			(layer "F.SilkS")
		)
		(fp_line
			(start 0.8 -1.3)
			(end 0.8 -1.6)
			(stroke
				(width 0.15)
				(type solid)
			)
			(layer "F.SilkS")
		)
		(fp_line
			(start 0.8 0.55)
			(end 0.8 -0.55)
			(stroke
				(width 0.15)
				(type solid)
			)
			(layer "F.SilkS")
		)
		(fp_line
			(start 0.8 1.3)
			(end 0.8 1.599)
			(stroke
				(width 0.15)
				(type solid)
			)
			(layer "F.SilkS")
		)
		(fp_line
			(start 0.8 1.599)
			(end 0.549 1.599)
			(stroke
				(width 0.15)
				(type solid)
			)
			(layer "F.SilkS")
		)
		(fp_circle
			(center -1.25 -1.5)
			(end -1.2 -1.5)
			(stroke
				(width 0.15)
				(type solid)
			)
			(fill yes)
			(layer "F.SilkS")
		)
		(fp_rect
			(start 1.9 -1.76)
			(end -1.9 1.75)
			(stroke
				(width 0.05)
				(type solid)
			)
			(fill no)
			(layer "F.CrtYd")
		)
		(fp_line
			(start -0.398 -1.526)
			(end -0.874 -1.05)
			(stroke
				(width 0.15)
				(type solid)
			)
			(layer "F.Fab")
		)
		(fp_rect
			(start 0.874 1.523)
			(end -0.873 -1.525)
			(stroke
				(width 0.15)
				(type solid)
			)
			(fill no)
			(layer "F.Fab")
		)
		(pad "1" smd rect
			(at -1.351 -0.951 270)
			(size 0.55 1)
			(layers "F.Cu" "F.Mask" "F.Paste")
			(net 545 "Net-(Q11-G)")
			(pinfunction "~{RESET}")
			(pintype "output")
			(teardrops
				(best_length_ratio 0.2)
				(max_length 1)
				(best_width_ratio 0.9)
				(max_width 2)
				(curved_edges yes)
				(filter_ratio 0.9)
				(enabled yes)
				(allow_two_segments yes)
				(prefer_zone_connections yes)
			)
		)
		(pad "2" smd rect
			(at -1.351 0 270)
			(size 0.55 1)
			(layers "F.Cu" "F.Mask" "F.Paste")
			(net 73 "+3V3_AON")
			(pinfunction "VDD")
			(pintype "power_in")
			(teardrops
				(best_length_ratio 0.2)
				(max_length 1)
				(best_width_ratio 0.9)
				(max_width 2)
				(curved_edges yes)
				(filter_ratio 0.9)
				(enabled yes)
				(allow_two_segments yes)
				(prefer_zone_connections yes)
			)
		)
		(pad "3" smd rect
			(at -1.351 0.949 270)
			(size 0.55 1)
			(layers "F.Cu" "F.Mask" "F.Paste")
			(net 1 "GND")
			(pinfunction "GND")
			(pintype "power_in")
			(teardrops
				(best_length_ratio 0.2)
				(max_length 1)
				(best_width_ratio 0.9)
				(max_width 2)
				(curved_edges yes)
				(filter_ratio 0.9)
				(enabled yes)
				(allow_two_segments yes)
				(prefer_zone_connections yes)
			)
		)
		(pad "4" smd rect
			(at 1.35 0.949 270)
			(size 0.55 1)
			(layers "F.Cu" "F.Mask" "F.Paste")
			(net 708 "Net-(U32-~{MR})")
			(pinfunction "~{MR}")
			(pintype "input")
			(teardrops
				(best_length_ratio 0.2)
				(max_length 1)
				(best_width_ratio 0.9)
				(max_width 2)
				(curved_edges yes)
				(filter_ratio 0.9)
				(enabled yes)
				(allow_two_segments yes)
				(prefer_zone_connections yes)
			)
		)
		(pad "5" smd rect
			(at 1.35 -0.951 270)
			(size 0.55 1)
			(layers "F.Cu" "F.Mask" "F.Paste")
			(net 82 "Net-(U32-CT)")
			(pinfunction "CT")
			(pintype "passive")
			(teardrops
				(best_length_ratio 0.2)
				(max_length 1)
				(best_width_ratio 0.9)
				(max_width 2)
				(curved_edges yes)
				(filter_ratio 0.9)
				(enabled yes)
				(allow_two_segments yes)
				(prefer_zone_connections yes)
			)
		)
	)
	(footprint "antmicro-footprints:SC70-3"
		(layer "F.Cu")
		(at 108.33 79)
		(property "Reference" "D9"
			(at 1.85 1.9 90)
			(layer "F.SilkS")
			(effects
				(font
					(size 0.7 0.7)
					(thickness 0.15)
				)
				(justify left bottom)
			)
		)
		(property "Value" "TPD2E2U06_SC70"
			(at 0 2.3 0)
			(layer "F.Fab")
			(effects
				(font
					(size 0.7 0.7)
					(thickness 0.15)
				)
				(justify left bottom)
			)
		)
		(property "Datasheet" "https://www.ti.com/lit/ds/symlink/tpd2e2u06.pdf?ts=1706006131823&ref_url=https%253A%252F%252Fwww.ti.com%252Finterface%252Fdiodes%252Fesd-protection-diodes%252Fproducts.html"
			(at 0 0 0)
			(layer "F.Fab")
			(hide yes)
			(effects
				(font
					(size 1.27 1.27)
					(thickness 0.15)
				)
			)
		)
		(property "Author" "Antmicro"
			(at 0 0 0)
			(layer "F.Fab")
			(hide yes)
			(effects
				(font
					(size 1 1)
					(thickness 0.15)
				)
			)
		)
		(property "License" "Apache-2.0"
			(at 0 0 0)
			(layer "F.Fab")
			(hide yes)
			(effects
				(font
					(size 1 1)
					(thickness 0.15)
				)
			)
		)
		(property "MPN" "TPD2E2U06DCKR"
			(at 0 0 0)
			(layer "F.Fab")
			(hide yes)
			(effects
				(font
					(size 1 1)
					(thickness 0.15)
				)
			)
		)
		(property "Manufacturer" "Texas Instruments"
			(at 0 0 0)
			(layer "F.Fab")
			(hide yes)
			(effects
				(font
					(size 1 1)
					(thickness 0.15)
				)
			)
		)
		(sheetname "USB-C console")
		(sheetfile "usb-c_console.kicad_sch")
		(attr smd)
		(fp_line
			(start -0.3 -1)
			(end 0.627 -0.999)
			(stroke
				(width 0.15)
				(type solid)
			)
			(layer "F.SilkS")
		)
		(fp_line
			(start -0.3 1)
			(end 0.627 1.001)
			(stroke
				(width 0.15)
				(type solid)
			)
			(layer "F.SilkS")
		)
		(fp_line
			(start 0.627 -0.6)
			(end 0.627 -0.999)
			(stroke
				(width 0.15)
				(type solid)
			)
			(layer "F.SilkS")
		)
		(fp_line
			(start 0.627 0.6)
			(end 0.627 1.001)
			(stroke
				(width 0.15)
				(type solid)
			)
			(layer "F.SilkS")
		)
		(fp_line
			(start -1.4 1)
			(end -1.4 -1)
			(stroke
				(width 0.05)
				(type solid)
			)
			(layer "F.CrtYd")
		)
		(fp_line
			(start -0.9 -1.3)
			(end -0.9 -1)
			(stroke
				(width 0.05)
				(type solid)
			)
			(layer "F.CrtYd")
		)
		(fp_line
			(start -0.9 -1.3)
			(end 0.9 -1.3)
			(stroke
				(width 0.05)
				(type solid)
			)
			(layer "F.CrtYd")
		)
		(fp_line
			(start -0.9 -1)
			(end -1.4 -1)
			(stroke
				(width 0.05)
				(type solid)
			)
			(layer "F.CrtYd")
		)
		(fp_line
			(start -0.9 1)
			(end -1.4 1)
			(stroke
				(width 0.05)
				(type solid)
			)
			(layer "F.CrtYd")
		)
		(fp_line
			(start -0.9 1.3)
			(end -0.9 1)
			(stroke
				(width 0.05)
				(type solid)
			)
			(layer "F.CrtYd")
		)
		(fp_line
			(start 0.9 -1.3)
			(end 0.9 -0.4)
			(stroke
				(width 0.05)
				(type solid)
			)
			(layer "F.CrtYd")
		)
		(fp_line
			(start 0.9 -0.4)
			(end 1.4 -0.4)
			(stroke
				(width 0.05)
				(type solid)
			)
			(layer "F.CrtYd")
		)
		(fp_line
			(start 0.9 0.4)
			(end 0.9 1.3)
			(stroke
				(width 0.05)
				(type solid)
			)
			(layer "F.CrtYd")
		)
		(fp_line
			(start 0.9 1.3)
			(end -0.9 1.3)
			(stroke
				(width 0.05)
				(type solid)
			)
			(layer "F.CrtYd")
		)
		(fp_line
			(start 1.4 -0.4)
			(end 1.4 0.4)
			(stroke
				(width 0.05)
				(type solid)
			)
			(layer "F.CrtYd")
		)
		(fp_line
			(start 1.4 0.4)
			(end 0.9 0.4)
			(stroke
				(width 0.05)
				(type solid)
			)
			(layer "F.CrtYd")
		)
		(fp_rect
			(start -0.623 -0.999)
			(end 0.627 1.001)
			(stroke
				(width 0.15)
				(type solid)
			)
			(fill no)
			(layer "F.Fab")
		)
		(pad "1" smd rect
			(at -1.051 -0.65 90)
			(size 0.6 0.6)
			(layers "F.Cu" "F.Mask" "F.Paste")
			(net 55 "/USB-C console/USB_D+")
			(pinfunction "1")
			(pintype "passive")
			(teardrops
				(best_length_ratio 0.2)
				(max_length 1)
				(best_width_ratio 0.9)
				(max_width 2)
				(curved_edges yes)
				(filter_ratio 0.9)
				(enabled yes)
				(allow_two_segments yes)
				(prefer_zone_connections yes)
			)
		)
		(pad "2" smd rect
			(at -1.051 0.65 90)
			(size 0.6 0.6)
			(layers "F.Cu" "F.Mask" "F.Paste")
			(net 56 "/USB-C console/USB_D-")
			(pinfunction "2")
			(pintype "passive")
			(teardrops
				(best_length_ratio 0.2)
				(max_length 1)
				(best_width_ratio 0.9)
				(max_width 2)
				(curved_edges yes)
				(filter_ratio 0.9)
				(enabled yes)
				(allow_two_segments yes)
				(prefer_zone_connections yes)
			)
		)
		(pad "3" smd rect
			(at 1.05 0 90)
			(size 0.6 0.6)
			(layers "F.Cu" "F.Mask" "F.Paste")
			(net 1 "GND")
			(pinfunction "3")
			(pintype "passive")
			(teardrops
				(best_length_ratio 0.2)
				(max_length 1)
				(best_width_ratio 0.9)
				(max_width 2)
				(curved_edges yes)
				(filter_ratio 0.9)
				(enabled yes)
				(allow_two_segments yes)
				(prefer_zone_connections yes)
			)
		)
	)
	(footprint "antmicro-footprints:R_0402_1005Metric"
		(layer "F.Cu")
		(at 122.05 90.96)
		(descr "Resistor SMD 0402")
		(tags "resistor SMD 0402")
		(property "Reference" "R25"
			(at 0.75 0.44 0)
			(layer "F.SilkS")
			(effects
				(font
					(size 0.7 0.7)
					(thickness 0.15)
				)
				(justify left bottom)
			)
		)
		(property "Value" "R_10k_0402"
			(at -1.011843 1.772047 0)
			(layer "F.Fab")
			(effects
				(font
					(size 0.7 0.7)
					(thickness 0.15)
				)
				(justify left bottom)
			)
		)
		(property "Datasheet" "https://www.bourns.com/docs/product-datasheets/cr.pdf"
			(at 0 0 0)
			(layer "F.Fab")
			(hide yes)
			(effects
				(font
					(size 1.27 1.27)
					(thickness 0.15)
				)
			)
		)
		(property "Author" "Antmicro"
			(at 0 0 0)
			(layer "F.Fab")
			(hide yes)
			(effects
				(font
					(size 1 1)
					(thickness 0.15)
				)
			)
		)
		(property "License" "Apache-2.0"
			(at 0 0 0)
			(layer "F.Fab")
			(hide yes)
			(effects
				(font
					(size 1 1)
					(thickness 0.15)
				)
			)
		)
		(property "MPN" "CR0402-FX-1002GLF"
			(at 0 0 0)
			(layer "F.Fab")
			(hide yes)
			(effects
				(font
					(size 1 1)
					(thickness 0.15)
				)
			)
		)
		(property "Manufacturer" "Bourns"
			(at 0 0 0)
			(layer "F.Fab")
			(hide yes)
			(effects
				(font
					(size 1 1)
					(thickness 0.15)
				)
			)
		)
		(property "Public" "False"
			(at 0 0 0)
			(layer "F.Fab")
			(hide yes)
			(effects
				(font
					(size 1 1)
					(thickness 0.15)
				)
			)
		)
		(property "Tolerance" "1%"
			(at 0 0 0)
			(layer "F.Fab")
			(hide yes)
			(effects
				(font
					(size 1 1)
					(thickness 0.15)
				)
			)
		)
		(property "Val" "10k"
			(at 0 0 0)
			(layer "F.Fab")
			(hide yes)
			(effects
				(font
					(size 1 1)
					(thickness 0.15)
				)
			)
		)
		(sheetname "2xUSB3.0+RJ45")
		(sheetfile "usb3+rj45.kicad_sch")
		(attr smd)
		(fp_rect
			(start -0.925 -0.47)
			(end 0.925 0.47)
			(stroke
				(width 0.05)
				(type default)
			)
			(fill no)
			(layer "F.CrtYd")
		)
		(fp_rect
			(start -0.5 -0.25)
			(end 0.5 0.25)
			(stroke
				(width 0.15)
				(type solid)
			)
			(fill no)
			(layer "F.Fab")
		)
		(pad "1" smd roundrect
			(at -0.48 0)
			(size 0.59 0.64)
			(layers "F.Cu" "F.Mask" "F.Paste")
			(roundrect_rratio 0.25)
			(net 556 "/2xUSB3.0+RJ45/EN_2B")
			(pintype "passive")
			(teardrops
				(best_length_ratio 0.2)
				(max_length 1)
				(best_width_ratio 0.9)
				(max_width 2)
				(curved_edges yes)
				(filter_ratio 0.9)
				(enabled yes)
				(allow_two_segments yes)
				(prefer_zone_connections yes)
			)
		)
		(pad "2" smd roundrect
			(at 0.48 0)
			(size 0.59 0.64)
			(layers "F.Cu" "F.Mask" "F.Paste")
			(roundrect_rratio 0.25)
			(net 2 "+3V3")
			(pintype "passive")
			(teardrops
				(best_length_ratio 0.2)
				(max_length 1)
				(best_width_ratio 0.9)
				(max_width 2)
				(curved_edges yes)
				(filter_ratio 0.9)
				(enabled yes)
				(allow_two_segments yes)
				(prefer_zone_connections yes)
			)
		)
	)
	(footprint "antmicro-footprints:R_0805_2012Metric"
		(layer "F.Cu")
		(at 304.25 96.74 180)
		(property "Reference" "R113"
			(at -1.45 0.93 0)
			(layer "F.SilkS")
			(effects
				(font
					(size 0.7 0.7)
					(thickness 0.15)
				)
				(justify right bottom)
			)
		)
		(property "Value" "R_0R001_0805"
			(at 1.82 -3.52 0)
			(layer "F.Fab")
			(effects
				(font
					(size 0.7 0.7)
					(thickness 0.15)
				)
				(justify left bottom mirror)
			)
		)
		(property "Datasheet" "https://www.eaton.com/content/dam/eaton/products/electronic-components/resources/data-sheet/eaton-msma-automotive-smd-current-sense-resistor-metal-strip-data-sheet-elx1179.pdf"
			(at 0 0 180)
			(layer "F.Fab")
			(hide yes)
			(effects
				(font
					(size 1.27 1.27)
					(thickness 0.15)
				)
			)
		)
		(property "Author" "Antmicro"
			(at 608.5 193.48 0)
			(layer "F.Fab")
			(hide yes)
			(effects
				(font
					(size 1 1)
					(thickness 0.15)
				)
			)
		)
		(property "License" "Apache-2.0"
			(at 608.5 193.48 0)
			(layer "F.Fab")
			(hide yes)
			(effects
				(font
					(size 1 1)
					(thickness 0.15)
				)
			)
		)
		(property "MPN" "MSMA0805R0010FSM"
			(at 608.5 193.48 0)
			(layer "F.Fab")
			(hide yes)
			(effects
				(font
					(size 1 1)
					(thickness 0.15)
				)
			)
		)
		(property "Manufacturer" "Eaton"
			(at 608.5 193.48 0)
			(layer "F.Fab")
			(hide yes)
			(effects
				(font
					(size 1 1)
					(thickness 0.15)
				)
			)
		)
		(property "Public" "False"
			(at 608.5 193.48 0)
			(layer "F.Fab")
			(hide yes)
			(effects
				(font
					(size 1 1)
					(thickness 0.15)
				)
			)
		)
		(property "Tolerance" "1%"
			(at 608.5 193.48 0)
			(layer "F.Fab")
			(hide yes)
			(effects
				(font
					(size 1 1)
					(thickness 0.15)
				)
			)
		)
		(property "Val" "0R001"
			(at 608.5 193.48 0)
			(layer "F.Fab")
			(hide yes)
			(effects
				(font
					(size 1 1)
					(thickness 0.15)
				)
			)
		)
		(sheetname "Power")
		(sheetfile "power.kicad_sch")
		(attr smd)
		(fp_line
			(start -0.3 -0.701)
			(end 0.298 -0.701)
			(stroke
				(width 0.15)
				(type solid)
			)
			(layer "F.SilkS")
		)
		(fp_line
			(start -0.32 0.699)
			(end 0.28 0.699)
			(stroke
				(width 0.15)
				(type solid)
			)
			(layer "F.SilkS")
		)
		(fp_rect
			(start 1.95 -0.9)
			(end -1.95 0.9)
			(stroke
				(width 0.05)
				(type default)
			)
			(fill no)
			(layer "F.CrtYd")
		)
		(fp_line
			(start 0.949 -0.677)
			(end 0.949 0.675)
			(stroke
				(width 0.15)
				(type solid)
			)
			(layer "F.Fab")
		)
		(fp_line
			(start -0.951 0.68)
			(end 0.949 0.68)
			(stroke
				(width 0.15)
				(type solid)
			)
			(layer "F.Fab")
		)
		(fp_line
			(start -0.951 -0.677)
			(end -0.951 0.675)
			(stroke
				(width 0.15)
				(type solid)
			)
			(layer "F.Fab")
		)
		(fp_line
			(start -0.951 -0.682)
			(end 0.949 -0.682)
			(stroke
				(width 0.15)
				(type solid)
			)
			(layer "F.Fab")
		)
		(pad "1" smd roundrect
			(at -1.1 0 180)
			(size 1.2 1.3)
			(layers "F.Cu" "F.Mask" "F.Paste")
			(roundrect_rratio 0.25)
			(net 75 "Net-(U50-IN+)")
			(pintype "passive")
			(teardrops
				(best_length_ratio 0.2)
				(max_length 1)
				(best_width_ratio 0.9)
				(max_width 2)
				(curved_edges yes)
				(filter_ratio 0.9)
				(enabled yes)
				(allow_two_segments yes)
				(prefer_zone_connections yes)
			)
		)
		(pad "2" smd roundrect
			(at 1.1 0 180)
			(size 1.2 1.3)
			(layers "F.Cu" "F.Mask" "F.Paste")
			(roundrect_rratio 0.25)
			(net 77 "+5V_AON")
			(pintype "passive")
			(teardrops
				(best_length_ratio 0.2)
				(max_length 1)
				(best_width_ratio 0.9)
				(max_width 2)
				(curved_edges yes)
				(filter_ratio 0.9)
				(enabled yes)
				(allow_two_segments yes)
				(prefer_zone_connections yes)
			)
		)
	)
	(footprint "antmicro-footprints:R_0402_1005Metric"
		(layer "F.Cu")
		(at 198.53 83.38 180)
		(descr "Resistor SMD 0402")
		(tags "resistor SMD 0402")
		(property "Reference" "R329"
			(at -1.625 -1.4 0)
			(layer "F.SilkS")
			(effects
				(font
					(size 0.7 0.7)
					(thickness 0.15)
				)
				(justify right bottom)
			)
		)
		(property "Value" "R_5k1_0402"
			(at -1.011843 1.772047 0)
			(layer "F.Fab")
			(effects
				(font
					(size 0.7 0.7)
					(thickness 0.15)
				)
				(justify right bottom)
			)
		)
		(property "Datasheet" "https://www.bourns.com/docs/product-datasheets/cr.pdf"
			(at 0 0 180)
			(layer "F.Fab")
			(hide yes)
			(effects
				(font
					(size 1.27 1.27)
					(thickness 0.15)
				)
			)
		)
		(property "Author" "Antmicro"
			(at 403.22722 166.544326 0)
			(layer "F.Fab")
			(hide yes)
			(effects
				(font
					(size 1 1)
					(thickness 0.15)
				)
			)
		)
		(property "License" "Apache-2.0"
			(at 403.22722 166.544326 0)
			(layer "F.Fab")
			(hide yes)
			(effects
				(font
					(size 1 1)
					(thickness 0.15)
				)
			)
		)
		(property "MPN" "CR0402-FX-5101GLF"
			(at 403.22722 166.544326 0)
			(layer "F.Fab")
			(hide yes)
			(effects
				(font
					(size 1 1)
					(thickness 0.15)
				)
			)
		)
		(property "Manufacturer" "Bourns"
			(at 403.22722 166.544326 0)
			(layer "F.Fab")
			(hide yes)
			(effects
				(font
					(size 1 1)
					(thickness 0.15)
				)
			)
		)
		(property "Tolerance" "1%"
			(at 403.22722 166.544326 0)
			(layer "F.Fab")
			(hide yes)
			(effects
				(font
					(size 1 1)
					(thickness 0.15)
				)
			)
		)
		(property "Val" "5k1"
			(at 403.22722 166.544326 0)
			(layer "F.Fab")
			(hide yes)
			(effects
				(font
					(size 1 1)
					(thickness 0.15)
				)
			)
		)
		(sheetname "Power")
		(sheetfile "power.kicad_sch")
		(attr smd)
		(fp_rect
			(start -0.925 -0.47)
			(end 0.925 0.47)
			(stroke
				(width 0.05)
				(type default)
			)
			(fill no)
			(layer "F.CrtYd")
		)
		(fp_rect
			(start -0.5 -0.25)
			(end 0.5 0.25)
			(stroke
				(width 0.15)
				(type solid)
			)
			(fill no)
			(layer "F.Fab")
		)
		(pad "1" smd roundrect
			(at -0.48 0 180)
			(size 0.59 0.64)
			(layers "F.Cu" "F.Mask" "F.Paste")
			(roundrect_rratio 0.25)
			(net 78 "+1V8")
			(pintype "passive")
			(teardrops
				(best_length_ratio 0.2)
				(max_length 1)
				(best_width_ratio 0.9)
				(max_width 2)
				(curved_edges yes)
				(filter_ratio 0.9)
				(enabled yes)
				(allow_two_segments yes)
				(prefer_zone_connections yes)
			)
		)
		(pad "2" smd roundrect
			(at 0.48 0 180)
			(size 0.59 0.64)
			(layers "F.Cu" "F.Mask" "F.Paste")
			(roundrect_rratio 0.25)
			(net 989 "Net-(Q14-B)")
			(pintype "passive")
			(teardrops
				(best_length_ratio 0.2)
				(max_length 1)
				(best_width_ratio 0.9)
				(max_width 2)
				(curved_edges yes)
				(filter_ratio 0.9)
				(enabled yes)
				(allow_two_segments yes)
				(prefer_zone_connections yes)
			)
		)
	)
	(footprint "antmicro-footprints:R_0402_1005Metric"
		(layer "F.Cu")
		(at 131.9 81.76 -90)
		(descr "Resistor SMD 0402")
		(tags "resistor SMD 0402")
		(property "Reference" "R233"
			(at -3.650001 -0.45 90)
			(layer "F.SilkS")
			(effects
				(font
					(size 0.7 0.7)
					(thickness 0.15)
				)
				(justify right bottom)
			)
		)
		(property "Value" "R_0R_0402"
			(at -1.011843 1.772047 90)
			(layer "F.Fab")
			(effects
				(font
					(size 0.7 0.7)
					(thickness 0.15)
				)
				(justify right bottom)
			)
		)
		(property "Datasheet" "https://industrial.panasonic.com/cdbs/www-data/pdf/RDA0000/AOA0000C301.pdf"
			(at 0 0 270)
			(layer "F.Fab")
			(hide yes)
			(effects
				(font
					(size 1.27 1.27)
					(thickness 0.15)
				)
			)
		)
		(property "Author" "Antmicro"
			(at 50.14 213.66 0)
			(layer "F.Fab")
			(hide yes)
			(effects
				(font
					(size 1 1)
					(thickness 0.15)
				)
			)
		)
		(property "Current" "1A"
			(at 50.14 213.66 0)
			(layer "F.Fab")
			(hide yes)
			(effects
				(font
					(size 1 1)
					(thickness 0.15)
				)
			)
		)
		(property "License" "Apache-2.0"
			(at 50.14 213.66 0)
			(layer "F.Fab")
			(hide yes)
			(effects
				(font
					(size 1 1)
					(thickness 0.15)
				)
			)
		)
		(property "MPN" "ERJ2GE0R00X"
			(at 50.14 213.66 0)
			(layer "F.Fab")
			(hide yes)
			(effects
				(font
					(size 1 1)
					(thickness 0.15)
				)
			)
		)
		(property "Manufacturer" "Panasonic"
			(at 50.14 213.66 0)
			(layer "F.Fab")
			(hide yes)
			(effects
				(font
					(size 1 1)
					(thickness 0.15)
				)
			)
		)
		(property "Public" "False"
			(at 50.14 213.66 0)
			(layer "F.Fab")
			(hide yes)
			(effects
				(font
					(size 1 1)
					(thickness 0.15)
				)
			)
		)
		(property "Tolerance" ""
			(at 50.14 213.66 0)
			(layer "F.Fab")
			(hide yes)
			(effects
				(font
					(size 1 1)
					(thickness 0.15)
				)
			)
		)
		(property "Val" "0R"
			(at 50.14 213.66 0)
			(layer "F.Fab")
			(hide yes)
			(effects
				(font
					(size 1 1)
					(thickness 0.15)
				)
			)
		)
		(sheetname "GPIO expander")
		(sheetfile "gpio_exp.kicad_sch")
		(attr smd)
		(fp_rect
			(start -0.925 -0.47)
			(end 0.925 0.47)
			(stroke
				(width 0.05)
				(type default)
			)
			(fill no)
			(layer "F.CrtYd")
		)
		(fp_rect
			(start -0.5 -0.25)
			(end 0.5 0.25)
			(stroke
				(width 0.15)
				(type solid)
			)
			(fill no)
			(layer "F.Fab")
		)
		(pad "1" smd roundrect
			(at -0.48 0 270)
			(size 0.59 0.64)
			(layers "F.Cu" "F.Mask" "F.Paste")
			(roundrect_rratio 0.25)
			(net 358 "/Com Express 7 MGMT/SMBus.SDA")
			(pintype "passive")
			(teardrops
				(best_length_ratio 0.2)
				(max_length 1)
				(best_width_ratio 0.9)
				(max_width 2)
				(curved_edges yes)
				(filter_ratio 0.9)
				(enabled yes)
				(allow_two_segments yes)
				(prefer_zone_connections yes)
			)
		)
		(pad "2" smd roundrect
			(at 0.48 0 270)
			(size 0.59 0.64)
			(layers "F.Cu" "F.Mask" "F.Paste")
			(roundrect_rratio 0.25)
			(net 634 "Net-(U41-SDA)")
			(pintype "passive")
			(teardrops
				(best_length_ratio 0.2)
				(max_length 1)
				(best_width_ratio 0.9)
				(max_width 2)
				(curved_edges yes)
				(filter_ratio 0.9)
				(enabled yes)
				(allow_two_segments yes)
				(prefer_zone_connections yes)
			)
		)
	)
	(footprint "antmicro-footprints:R_0402_1005Metric"
		(layer "F.Cu")
		(at 219.73 124.9)
		(descr "Resistor SMD 0402")
		(tags "resistor SMD 0402")
		(property "Reference" "R190"
			(at 0.77 0.46 0)
			(layer "F.SilkS")
			(effects
				(font
					(size 0.7 0.7)
					(thickness 0.15)
				)
				(justify left bottom)
			)
		)
		(property "Value" "R_1k_0402"
			(at -1.011843 1.772047 0)
			(layer "F.Fab")
			(effects
				(font
					(size 0.7 0.7)
					(thickness 0.15)
				)
				(justify left bottom)
			)
		)
		(property "Datasheet" "https://www.bourns.com/docs/product-datasheets/cr.pdf"
			(at 0 0 0)
			(layer "F.Fab")
			(hide yes)
			(effects
				(font
					(size 1.27 1.27)
					(thickness 0.15)
				)
			)
		)
		(property "Author" "Antmicro"
			(at 0 0 0)
			(layer "F.Fab")
			(hide yes)
			(effects
				(font
					(size 1 1)
					(thickness 0.15)
				)
			)
		)
		(property "License" "Apache-2.0"
			(at 0 0 0)
			(layer "F.Fab")
			(hide yes)
			(effects
				(font
					(size 1 1)
					(thickness 0.15)
				)
			)
		)
		(property "MPN" "CR0402-FX-1001GLF"
			(at 0 0 0)
			(layer "F.Fab")
			(hide yes)
			(effects
				(font
					(size 1 1)
					(thickness 0.15)
				)
			)
		)
		(property "Manufacturer" "Bourns"
			(at 0 0 0)
			(layer "F.Fab")
			(hide yes)
			(effects
				(font
					(size 1 1)
					(thickness 0.15)
				)
			)
		)
		(property "Public" "False"
			(at 0 0 0)
			(layer "F.Fab")
			(hide yes)
			(effects
				(font
					(size 1 1)
					(thickness 0.15)
				)
			)
		)
		(property "Tolerance" "1%"
			(at 0 0 0)
			(layer "F.Fab")
			(hide yes)
			(effects
				(font
					(size 1 1)
					(thickness 0.15)
				)
			)
		)
		(property "Val" "1k"
			(at 0 0 0)
			(layer "F.Fab")
			(hide yes)
			(effects
				(font
					(size 1 1)
					(thickness 0.15)
				)
			)
		)
		(sheetname "PCIe misc")
		(sheetfile "pcie_misc.kicad_sch")
		(attr smd)
		(fp_rect
			(start -0.925 -0.47)
			(end 0.925 0.47)
			(stroke
				(width 0.05)
				(type default)
			)
			(fill no)
			(layer "F.CrtYd")
		)
		(fp_rect
			(start -0.5 -0.25)
			(end 0.5 0.25)
			(stroke
				(width 0.15)
				(type solid)
			)
			(fill no)
			(layer "F.Fab")
		)
		(pad "1" smd roundrect
			(at -0.48 0)
			(size 0.59 0.64)
			(layers "F.Cu" "F.Mask" "F.Paste")
			(roundrect_rratio 0.25)
			(net 609 "Net-(U37-~{CKPWRGD_PD})")
			(pintype "passive")
			(teardrops
				(best_length_ratio 0.2)
				(max_length 1)
				(best_width_ratio 0.9)
				(max_width 2)
				(curved_edges yes)
				(filter_ratio 0.9)
				(enabled yes)
				(allow_two_segments yes)
				(prefer_zone_connections yes)
			)
		)
		(pad "2" smd roundrect
			(at 0.48 0)
			(size 0.59 0.64)
			(layers "F.Cu" "F.Mask" "F.Paste")
			(roundrect_rratio 0.25)
			(net 2 "+3V3")
			(pintype "passive")
			(teardrops
				(best_length_ratio 0.2)
				(max_length 1)
				(best_width_ratio 0.9)
				(max_width 2)
				(curved_edges yes)
				(filter_ratio 0.9)
				(enabled yes)
				(allow_two_segments yes)
				(prefer_zone_connections yes)
			)
		)
	)
	(footprint "antmicro-footprints:TP_SMD_0.75mm"
		(layer "F.Cu")
		(at 188.708611 72.802163 -90)
		(property "Reference" "TP103"
			(at 0 -0.6 90)
			(layer "F.SilkS")
			(hide yes)
			(effects
				(font
					(size 0.7 0.7)
					(thickness 0.15)
				)
				(justify right bottom)
			)
		)
		(property "Value" "TP_0.75mm_SMD"
			(at 0 1.2 90)
			(layer "F.Fab")
			(effects
				(font
					(size 0.7 0.7)
					(thickness 0.15)
				)
				(justify right bottom)
			)
		)
		(property "Author" "Antmicro"
			(at 115.906448 261.510774 0)
			(layer "F.Fab")
			(hide yes)
			(effects
				(font
					(size 1 1)
					(thickness 0.15)
				)
			)
		)
		(property "License" "Apache-2.0"
			(at 115.906448 261.510774 0)
			(layer "F.Fab")
			(hide yes)
			(effects
				(font
					(size 1 1)
					(thickness 0.15)
				)
			)
		)
		(property "MPN" ""
			(at 115.906448 261.510774 0)
			(layer "F.Fab")
			(hide yes)
			(effects
				(font
					(size 1 1)
					(thickness 0.15)
				)
			)
		)
		(property "Manufacturer" ""
			(at 115.906448 261.510774 0)
			(layer "F.Fab")
			(hide yes)
			(effects
				(font
					(size 1 1)
					(thickness 0.15)
				)
			)
		)
		(property "Public" "False"
			(at 115.906448 261.510774 0)
			(layer "F.Fab")
			(hide yes)
			(effects
				(font
					(size 1 1)
					(thickness 0.15)
				)
			)
		)
		(sheetname "Power")
		(sheetfile "power.kicad_sch")
		(attr exclude_from_pos_files exclude_from_bom)
		(fp_circle
			(center 0 0)
			(end 0.475 0)
			(stroke
				(width 0.05)
				(type default)
			)
			(fill no)
			(layer "F.CrtYd")
		)
		(pad "1" smd circle
			(at 0 0 270)
			(size 0.75 0.75)
			(layers "F.Cu" "F.Mask")
			(net 77 "+5V_AON")
			(pinfunction "1")
			(pintype "passive")
			(teardrops
				(best_length_ratio 0.4)
				(max_length 1)
				(best_width_ratio 0.9)
				(max_width 2)
				(curved_edges yes)
				(filter_ratio 0.9)
				(enabled yes)
				(allow_two_segments yes)
				(prefer_zone_connections yes)
			)
		)
	)
	(footprint "antmicro-footprints:TSSOP-8_3x3mm_P0.65mm"
		(layer "F.Cu")
		(at 121 73.61 90)
		(property "Reference" "U7"
			(at 1.3 2.8 90)
			(layer "F.SilkS")
			(effects
				(font
					(size 0.7 0.7)
					(thickness 0.15)
				)
				(justify left bottom)
			)
		)
		(property "Value" "NTS0102_TSSOP"
			(at 0 2.8 90)
			(layer "F.Fab")
			(effects
				(font
					(size 0.7 0.7)
					(thickness 0.15)
				)
				(justify left bottom)
			)
		)
		(property "Datasheet" "https://www.mouser.com/datasheet/2/302/NTS0102-1127324.pdf"
			(at 0 0 90)
			(layer "F.Fab")
			(hide yes)
			(effects
				(font
					(size 1.27 1.27)
					(thickness 0.15)
				)
			)
		)
		(property "Author" "Antmicro"
			(at 194.61 -47.39 0)
			(layer "F.Fab")
			(hide yes)
			(effects
				(font
					(size 1 1)
					(thickness 0.15)
				)
			)
		)
		(property "License" "Apache-2.0"
			(at 194.61 -47.39 0)
			(layer "F.Fab")
			(hide yes)
			(effects
				(font
					(size 1 1)
					(thickness 0.15)
				)
			)
		)
		(property "MPN" "NTS0102DP"
			(at 194.61 -47.39 0)
			(layer "F.Fab")
			(hide yes)
			(effects
				(font
					(size 1 1)
					(thickness 0.15)
				)
			)
		)
		(property "Manufacturer" "NXP"
			(at 194.61 -47.39 0)
			(layer "F.Fab")
			(hide yes)
			(effects
				(font
					(size 1 1)
					(thickness 0.15)
				)
			)
		)
		(sheetname "USB-C console")
		(sheetfile "usb-c_console.kicad_sch")
		(attr smd)
		(fp_line
			(start -1.525 -1.537)
			(end 1.552 -1.539)
			(stroke
				(width 0.15)
				(type solid)
			)
			(layer "F.SilkS")
		)
		(fp_line
			(start -1.55 1.561)
			(end 1.552 1.561)
			(stroke
				(width 0.15)
				(type solid)
			)
			(layer "F.SilkS")
		)
		(fp_circle
			(center -1.87 -1.4)
			(end -1.82 -1.4)
			(stroke
				(width 0.15)
				(type solid)
			)
			(fill yes)
			(layer "F.SilkS")
		)
		(fp_rect
			(start -3.15 -1.789)
			(end 3.15 1.811)
			(stroke
				(width 0.05)
				(type solid)
			)
			(fill no)
			(layer "F.CrtYd")
		)
		(fp_line
			(start 1.552 -1.539)
			(end 1.552 1.561)
			(stroke
				(width 0.15)
				(type solid)
			)
			(layer "F.Fab")
		)
		(fp_line
			(start -0.949 -1.539)
			(end 1.552 -1.539)
			(stroke
				(width 0.15)
				(type solid)
			)
			(layer "F.Fab")
		)
		(fp_line
			(start -1.55 -0.937)
			(end -0.949 -1.539)
			(stroke
				(width 0.15)
				(type solid)
			)
			(layer "F.Fab")
		)
		(fp_line
			(start -1.55 -0.937)
			(end -1.55 1.561)
			(stroke
				(width 0.15)
				(type solid)
			)
			(layer "F.Fab")
		)
		(fp_line
			(start -1.55 1.561)
			(end 1.552 1.561)
			(stroke
				(width 0.15)
				(type solid)
			)
			(layer "F.Fab")
		)
		(pad "1" smd roundrect
			(at -2.148 -0.962 90)
			(size 1.47 0.4)
			(layers "F.Cu" "F.Mask" "F.Paste")
			(roundrect_rratio 0.25)
			(net 700 "/USB-C console/FTDI_TX")
			(pinfunction "B_{2}")
			(pintype "bidirectional")
			(teardrops
				(best_length_ratio 0.2)
				(max_length 1)
				(best_width_ratio 0.9)
				(max_width 2)
				(curved_edges yes)
				(filter_ratio 0.9)
				(enabled yes)
				(allow_two_segments yes)
				(prefer_zone_connections yes)
			)
		)
		(pad "2" smd roundrect
			(at -2.148 -0.313 90)
			(size 1.47 0.4)
			(layers "F.Cu" "F.Mask" "F.Paste")
			(roundrect_rratio 0.25)
			(net 1 "GND")
			(pinfunction "GND")
			(pintype "power_in")
			(teardrops
				(best_length_ratio 0.2)
				(max_length 1)
				(best_width_ratio 0.9)
				(max_width 2)
				(curved_edges yes)
				(filter_ratio 0.9)
				(enabled yes)
				(allow_two_segments yes)
				(prefer_zone_connections yes)
			)
		)
		(pad "3" smd roundrect
			(at -2.148 0.338 90)
			(size 1.47 0.4)
			(layers "F.Cu" "F.Mask" "F.Paste")
			(roundrect_rratio 0.25)
			(net 2 "+3V3")
			(pinfunction "VCC_{A}")
			(pintype "power_in")
			(teardrops
				(best_length_ratio 0.2)
				(max_length 1)
				(best_width_ratio 0.9)
				(max_width 2)
				(curved_edges yes)
				(filter_ratio 0.9)
				(enabled yes)
				(allow_two_segments yes)
				(prefer_zone_connections yes)
			)
		)
		(pad "4" smd roundrect
			(at -2.148 0.987 90)
			(size 1.47 0.4)
			(layers "F.Cu" "F.Mask" "F.Paste")
			(roundrect_rratio 0.25)
			(net 572 "Net-(U7-A_{2})")
			(pinfunction "A_{2}")
			(pintype "bidirectional")
			(teardrops
				(best_length_ratio 0.2)
				(max_length 1)
				(best_width_ratio 0.9)
				(max_width 2)
				(curved_edges yes)
				(filter_ratio 0.9)
				(enabled yes)
				(allow_two_segments yes)
				(prefer_zone_connections yes)
			)
		)
		(pad "5" smd roundrect
			(at 2.151 0.987 90)
			(size 1.47 0.4)
			(layers "F.Cu" "F.Mask" "F.Paste")
			(roundrect_rratio 0.25)
			(net 571 "Net-(U7-A_{1})")
			(pinfunction "A_{1}")
			(pintype "bidirectional")
			(teardrops
				(best_length_ratio 0.2)
				(max_length 1)
				(best_width_ratio 0.9)
				(max_width 2)
				(curved_edges yes)
				(filter_ratio 0.9)
				(enabled yes)
				(allow_two_segments yes)
				(prefer_zone_connections yes)
			)
		)
		(pad "6" smd roundrect
			(at 2.151 0.338 90)
			(size 1.47 0.4)
			(layers "F.Cu" "F.Mask" "F.Paste")
			(roundrect_rratio 0.25)
			(net 2 "+3V3")
			(pinfunction "OE")
			(pintype "input")
			(teardrops
				(best_length_ratio 0.2)
				(max_length 1)
				(best_width_ratio 0.9)
				(max_width 2)
				(curved_edges yes)
				(filter_ratio 0.9)
				(enabled yes)
				(allow_two_segments yes)
				(prefer_zone_connections yes)
			)
		)
		(pad "7" smd roundrect
			(at 2.151 -0.313 90)
			(size 1.47 0.4)
			(layers "F.Cu" "F.Mask" "F.Paste")
			(roundrect_rratio 0.25)
			(net 58 "/USB-C console/VBUS_FTDI")
			(pinfunction "VCC_{B}")
			(pintype "power_in")
			(teardrops
				(best_length_ratio 0.2)
				(max_length 1)
				(best_width_ratio 0.9)
				(max_width 2)
				(curved_edges yes)
				(filter_ratio 0.9)
				(enabled yes)
				(allow_two_segments yes)
				(prefer_zone_connections yes)
			)
		)
		(pad "8" smd roundrect
			(at 2.151 -0.962 90)
			(size 1.47 0.4)
			(layers "F.Cu" "F.Mask" "F.Paste")
			(roundrect_rratio 0.25)
			(net 699 "/USB-C console/FTDI_RX")
			(pinfunction "B_{1}")
			(pintype "bidirectional")
			(teardrops
				(best_length_ratio 0.2)
				(max_length 1)
				(best_width_ratio 0.9)
				(max_width 2)
				(curved_edges yes)
				(filter_ratio 0.9)
				(enabled yes)
				(allow_two_segments yes)
				(prefer_zone_connections yes)
			)
		)
	)
	(footprint "antmicro-footprints:Conn_Molex_KK_1x4_0470531000"
		(layer "F.Cu")
		(at 252.510709 71.86 180)
		(property "Reference" "J10"
			(at 7.240001 -3.85 0)
			(layer "F.SilkS")
			(effects
				(font
					(size 0.7 0.7)
					(thickness 0.15)
				)
				(justify right bottom)
			)
		)
		(property "Value" "Molex_KK_1x4_0470531000"
			(at 0 4.7 0)
			(layer "F.Fab")
			(effects
				(font
					(size 0.7 0.7)
					(thickness 0.15)
				)
				(justify right bottom)
			)
		)
		(property "Datasheet" "https://tools.molex.com/pdm_docs/sd/470531000_sd.pdf"
			(at 0 0 180)
			(layer "F.Fab")
			(hide yes)
			(effects
				(font
					(size 1.27 1.27)
					(thickness 0.15)
				)
			)
		)
		(property "Author" "Antmicro"
			(at 505.021418 143.72 0)
			(layer "F.Fab")
			(hide yes)
			(effects
				(font
					(size 1 1)
					(thickness 0.15)
				)
			)
		)
		(property "License" "Apache-2.0"
			(at 505.021418 143.72 0)
			(layer "F.Fab")
			(hide yes)
			(effects
				(font
					(size 1 1)
					(thickness 0.15)
				)
			)
		)
		(property "MPN" "0470531000"
			(at 505.021418 143.72 0)
			(layer "F.Fab")
			(hide yes)
			(effects
				(font
					(size 1 1)
					(thickness 0.15)
				)
			)
		)
		(property "Manufacturer" "Molex"
			(at 505.021418 143.72 0)
			(layer "F.Fab")
			(hide yes)
			(effects
				(font
					(size 1 1)
					(thickness 0.15)
				)
			)
		)
		(sheetname "Misc")
		(sheetfile "misc.kicad_sch")
		(attr through_hole)
		(fp_line
			(start 8.95 3.4)
			(end -1.35 3.4)
			(stroke
				(width 0.15)
				(type solid)
			)
			(layer "F.SilkS")
		)
		(fp_line
			(start 8.95 -2.55)
			(end 8.95 3.4)
			(stroke
				(width 0.15)
				(type solid)
			)
			(layer "F.SilkS")
		)
		(fp_line
			(start 5.75 -2.55)
			(end 8.95 -2.55)
			(stroke
				(width 0.15)
				(type solid)
			)
			(layer "F.SilkS")
		)
		(fp_line
			(start 5.08 2.29)
			(end 5.08 3.3)
			(stroke
				(width 0.15)
				(type solid)
			)
			(layer "F.SilkS")
		)
		(fp_line
			(start 0 3.3)
			(end 0 2.29)
			(stroke
				(width 0.15)
				(type solid)
			)
			(layer "F.SilkS")
		)
		(fp_line
			(start 0 2.29)
			(end 5.08 2.29)
			(stroke
				(width 0.15)
				(type solid)
			)
			(layer "F.SilkS")
		)
		(fp_line
			(start -1.35 3.4)
			(end -1.35 -2.6)
			(stroke
				(width 0.15)
				(type solid)
			)
			(layer "F.SilkS")
		)
		(fp_line
			(start -1.35 -2.6)
			(end 4.4 -2.6)
			(stroke
				(width 0.15)
				(type solid)
			)
			(layer "F.SilkS")
		)
		(fp_circle
			(center 0 -3)
			(end 0.05 -3)
			(stroke
				(width 0.15)
				(type solid)
			)
			(fill yes)
			(layer "F.SilkS")
		)
		(fp_rect
			(start -1.54 -2.96)
			(end 9.16 3.55)
			(stroke
				(width 0.05)
				(type solid)
			)
			(fill no)
			(layer "F.CrtYd")
		)
		(fp_line
			(start 8.85 3.3)
			(end -1.2 3.3)
			(stroke
				(width 0.15)
				(type solid)
			)
			(layer "F.Fab")
		)
		(fp_line
			(start 8.85 -2.5)
			(end 8.85 3.3)
			(stroke
				(width 0.15)
				(type solid)
			)
			(layer "F.Fab")
		)
		(fp_line
			(start 5.75 -2.5)
			(end 8.85 -2.5)
			(stroke
				(width 0.15)
				(type solid)
			)
			(layer "F.Fab")
		)
		(fp_line
			(start 5.1 3.3)
			(end 5.1 2.3)
			(stroke
				(width 0.15)
				(type solid)
			)
			(layer "F.Fab")
		)
		(fp_line
			(start 5.1 2.3)
			(end 0 2.3)
			(stroke
				(width 0.15)
				(type solid)
			)
			(layer "F.Fab")
		)
		(fp_line
			(start 0 2.3)
			(end 0 3.3)
			(stroke
				(width 0.15)
				(type solid)
			)
			(layer "F.Fab")
		)
		(fp_line
			(start -1.2 3.3)
			(end -1.25 3.3)
			(stroke
				(width 0.15)
				(type solid)
			)
			(layer "F.Fab")
		)
		(fp_line
			(start -1.25 3.3)
			(end -1.25 -2.5)
			(stroke
				(width 0.15)
				(type solid)
			)
			(layer "F.Fab")
		)
		(fp_line
			(start -1.25 -2.5)
			(end 4.4 -2.5)
			(stroke
				(width 0.15)
				(type solid)
			)
			(layer "F.Fab")
		)
		(pad "" np_thru_hole circle
			(at 5.08 -2.16 270)
			(size 1.1 1.1)
			(drill 1.1)
			(layers "*.Cu" "*.Mask")
		)
		(pad "1" thru_hole rect
			(at 0 0 270)
			(size 2.03 1.73)
			(drill 1.02)
			(layers "*.Cu" "*.Mask")
			(remove_unused_layers no)
			(net 1 "GND")
			(pintype "passive")
			(teardrops
				(best_length_ratio 0.2)
				(max_length 1)
				(best_width_ratio 0.9)
				(max_width 2)
				(curved_edges yes)
				(filter_ratio 0.9)
				(enabled yes)
				(allow_two_segments yes)
				(prefer_zone_connections yes)
			)
		)
		(pad "2" thru_hole oval
			(at 2.54 0 270)
			(size 2.03 1.73)
			(drill 1.02)
			(layers "*.Cu" "*.Mask")
			(remove_unused_layers no)
			(net 81 "/Misc/FAN_12V")
			(pintype "passive")
			(teardrops
				(best_length_ratio 0.2)
				(max_length 1)
				(best_width_ratio 0.9)
				(max_width 2)
				(curved_edges yes)
				(filter_ratio 0.9)
				(enabled yes)
				(allow_two_segments yes)
				(prefer_zone_connections yes)
			)
		)
		(pad "3" thru_hole oval
			(at 5.08 0 270)
			(size 2.03 1.73)
			(drill 1.02)
			(layers "*.Cu" "*.Mask")
			(remove_unused_layers no)
			(net 281 "/Misc/TACH_{B5V}")
			(pintype "passive")
			(teardrops
				(best_length_ratio 0.2)
				(max_length 1)
				(best_width_ratio 0.9)
				(max_width 2)
				(curved_edges yes)
				(filter_ratio 0.9)
				(enabled yes)
				(allow_two_segments yes)
				(prefer_zone_connections yes)
			)
		)
		(pad "4" thru_hole oval
			(at 7.62 0 270)
			(size 2.03 1.73)
			(drill 1.02)
			(layers "*.Cu" "*.Mask")
			(remove_unused_layers no)
			(net 282 "/Misc/PWM_{B5V}")
			(pintype "passive")
			(teardrops
				(best_length_ratio 0.2)
				(max_length 1)
				(best_width_ratio 0.9)
				(max_width 2)
				(curved_edges yes)
				(filter_ratio 0.9)
				(enabled yes)
				(allow_two_segments yes)
				(prefer_zone_connections yes)
			)
		)
	)
	(footprint "antmicro-footprints:R_0402_1005Metric"
		(layer "F.Cu")
		(at 158.55 156.81 -90)
		(descr "Resistor SMD 0402")
		(tags "resistor SMD 0402")
		(property "Reference" "R36"
			(at -3.013 -0.449 90)
			(layer "F.SilkS")
			(effects
				(font
					(size 0.7 0.7)
					(thickness 0.15)
				)
				(justify right bottom)
			)
		)
		(property "Value" "R_0R_0402"
			(at -1.011843 1.772047 90)
			(layer "F.Fab")
			(effects
				(font
					(size 0.7 0.7)
					(thickness 0.15)
				)
				(justify right bottom)
			)
		)
		(property "Datasheet" "https://industrial.panasonic.com/cdbs/www-data/pdf/RDA0000/AOA0000C301.pdf"
			(at 0 0 270)
			(layer "F.Fab")
			(hide yes)
			(effects
				(font
					(size 1.27 1.27)
					(thickness 0.15)
				)
			)
		)
		(property "Author" "Antmicro"
			(at 1.74 315.36 0)
			(layer "F.Fab")
			(hide yes)
			(effects
				(font
					(size 1 1)
					(thickness 0.15)
				)
			)
		)
		(property "Current" "1A"
			(at 1.74 315.36 0)
			(layer "F.Fab")
			(hide yes)
			(effects
				(font
					(size 1 1)
					(thickness 0.15)
				)
			)
		)
		(property "License" "Apache-2.0"
			(at 1.74 315.36 0)
			(layer "F.Fab")
			(hide yes)
			(effects
				(font
					(size 1 1)
					(thickness 0.15)
				)
			)
		)
		(property "MPN" "ERJ2GE0R00X"
			(at 1.74 315.36 0)
			(layer "F.Fab")
			(hide yes)
			(effects
				(font
					(size 1 1)
					(thickness 0.15)
				)
			)
		)
		(property "Manufacturer" "Panasonic"
			(at 1.74 315.36 0)
			(layer "F.Fab")
			(hide yes)
			(effects
				(font
					(size 1 1)
					(thickness 0.15)
				)
			)
		)
		(property "Public" "False"
			(at 1.74 315.36 0)
			(layer "F.Fab")
			(hide yes)
			(effects
				(font
					(size 1 1)
					(thickness 0.15)
				)
			)
		)
		(property "Tolerance" ""
			(at 1.74 315.36 0)
			(layer "F.Fab")
			(hide yes)
			(effects
				(font
					(size 1 1)
					(thickness 0.15)
				)
			)
		)
		(property "Val" "0R"
			(at 1.74 315.36 0)
			(layer "F.Fab")
			(hide yes)
			(effects
				(font
					(size 1 1)
					(thickness 0.15)
				)
			)
		)
		(sheetname "2xSFP+")
		(sheetfile "2xSFP+.kicad_sch")
		(attr smd)
		(fp_rect
			(start -0.925 -0.47)
			(end 0.925 0.47)
			(stroke
				(width 0.05)
				(type default)
			)
			(fill no)
			(layer "F.CrtYd")
		)
		(fp_rect
			(start -0.5 -0.25)
			(end 0.5 0.25)
			(stroke
				(width 0.15)
				(type solid)
			)
			(fill no)
			(layer "F.Fab")
		)
		(pad "1" smd roundrect
			(at -0.48 0 270)
			(size 0.59 0.64)
			(layers "F.Cu" "F.Mask" "F.Paste")
			(roundrect_rratio 0.25)
			(net 1 "GND")
			(pintype "passive")
			(teardrops
				(best_length_ratio 0.2)
				(max_length 1)
				(best_width_ratio 0.9)
				(max_width 2)
				(curved_edges yes)
				(filter_ratio 0.9)
				(enabled yes)
				(allow_two_segments yes)
				(prefer_zone_connections yes)
			)
		)
		(pad "2" smd roundrect
			(at 0.48 0 270)
			(size 0.59 0.64)
			(layers "F.Cu" "F.Mask" "F.Paste")
			(roundrect_rratio 0.25)
			(net 561 "Net-(U5-A1)")
			(pintype "passive")
			(teardrops
				(best_length_ratio 0.2)
				(max_length 1)
				(best_width_ratio 0.9)
				(max_width 2)
				(curved_edges yes)
				(filter_ratio 0.9)
				(enabled yes)
				(allow_two_segments yes)
				(prefer_zone_connections yes)
			)
		)
	)
	(footprint "antmicro-footprints:R_0402_1005Metric"
		(layer "F.Cu")
		(at 215.925 136.95 -90)
		(descr "Resistor SMD 0402")
		(tags "resistor SMD 0402")
		(property "Reference" "R184"
			(at 0.86 -0.475 90)
			(layer "F.SilkS")
			(effects
				(font
					(size 0.7 0.7)
					(thickness 0.15)
				)
				(justify right bottom)
			)
		)
		(property "Value" "R_1k_0402"
			(at -1.011843 1.772047 90)
			(layer "F.Fab")
			(effects
				(font
					(size 0.7 0.7)
					(thickness 0.15)
				)
				(justify right bottom)
			)
		)
		(property "Datasheet" "https://www.bourns.com/docs/product-datasheets/cr.pdf"
			(at 0 0 270)
			(layer "F.Fab")
			(hide yes)
			(effects
				(font
					(size 1.27 1.27)
					(thickness 0.15)
				)
			)
		)
		(property "Author" "Antmicro"
			(at 78.975 352.875 0)
			(layer "F.Fab")
			(hide yes)
			(effects
				(font
					(size 1 1)
					(thickness 0.15)
				)
			)
		)
		(property "License" "Apache-2.0"
			(at 78.975 352.875 0)
			(layer "F.Fab")
			(hide yes)
			(effects
				(font
					(size 1 1)
					(thickness 0.15)
				)
			)
		)
		(property "MPN" "CR0402-FX-1001GLF"
			(at 78.975 352.875 0)
			(layer "F.Fab")
			(hide yes)
			(effects
				(font
					(size 1 1)
					(thickness 0.15)
				)
			)
		)
		(property "Manufacturer" "Bourns"
			(at 78.975 352.875 0)
			(layer "F.Fab")
			(hide yes)
			(effects
				(font
					(size 1 1)
					(thickness 0.15)
				)
			)
		)
		(property "Public" "False"
			(at 78.975 352.875 0)
			(layer "F.Fab")
			(hide yes)
			(effects
				(font
					(size 1 1)
					(thickness 0.15)
				)
			)
		)
		(property "Tolerance" "1%"
			(at 78.975 352.875 0)
			(layer "F.Fab")
			(hide yes)
			(effects
				(font
					(size 1 1)
					(thickness 0.15)
				)
			)
		)
		(property "Val" "1k"
			(at 78.975 352.875 0)
			(layer "F.Fab")
			(hide yes)
			(effects
				(font
					(size 1 1)
					(thickness 0.15)
				)
			)
		)
		(sheetname "PCIe misc")
		(sheetfile "pcie_misc.kicad_sch")
		(attr smd)
		(fp_rect
			(start -0.925 -0.47)
			(end 0.925 0.47)
			(stroke
				(width 0.05)
				(type default)
			)
			(fill no)
			(layer "F.CrtYd")
		)
		(fp_rect
			(start -0.5 -0.25)
			(end 0.5 0.25)
			(stroke
				(width 0.15)
				(type solid)
			)
			(fill no)
			(layer "F.Fab")
		)
		(pad "1" smd roundrect
			(at -0.48 0 270)
			(size 0.59 0.64)
			(layers "F.Cu" "F.Mask" "F.Paste")
			(roundrect_rratio 0.25)
			(net 604 "Net-(U37-~{OE2})")
			(pintype "passive")
			(teardrops
				(best_length_ratio 0.2)
				(max_length 1)
				(best_width_ratio 0.9)
				(max_width 2)
				(curved_edges yes)
				(filter_ratio 0.9)
				(enabled yes)
				(allow_two_segments yes)
				(prefer_zone_connections yes)
			)
		)
		(pad "2" smd roundrect
			(at 0.48 0 270)
			(size 0.59 0.64)
			(layers "F.Cu" "F.Mask" "F.Paste")
			(roundrect_rratio 0.25)
			(net 1 "GND")
			(pintype "passive")
			(teardrops
				(best_length_ratio 0.2)
				(max_length 1)
				(best_width_ratio 0.9)
				(max_width 2)
				(curved_edges yes)
				(filter_ratio 0.9)
				(enabled yes)
				(allow_two_segments yes)
				(prefer_zone_connections yes)
			)
		)
	)
	(footprint "antmicro-footprints:R_0201"
		(layer "F.Cu")
		(at 149.57 147.336 -90)
		(descr "Resistor SMD 0201")
		(tags "resistor SMD 0201")
		(property "Reference" "R273"
			(at 4.099 -0.33 270)
			(layer "F.SilkS")
			(effects
				(font
					(size 0.7 0.7)
					(thickness 0.15)
				)
				(justify left bottom)
			)
		)
		(property "Value" "R_0R_0201"
			(at 0 1.25 270)
			(layer "F.Fab")
			(effects
				(font
					(size 0.7 0.7)
					(thickness 0.15)
				)
				(justify left bottom)
			)
		)
		(property "Datasheet" "https://www.bourns.com/docs/product-datasheets/cr.pdf"
			(at 0 0 270)
			(layer "F.Fab")
			(hide yes)
			(effects
				(font
					(size 1.27 1.27)
					(thickness 0.15)
				)
			)
		)
		(property "Author" "Antmicro"
			(at 2.234 296.906 0)
			(layer "F.Fab")
			(hide yes)
			(effects
				(font
					(size 1 1)
					(thickness 0.15)
				)
			)
		)
		(property "License" "Apache-2.0"
			(at 2.234 296.906 0)
			(layer "F.Fab")
			(hide yes)
			(effects
				(font
					(size 1 1)
					(thickness 0.15)
				)
			)
		)
		(property "MPN" "CR0201-FX-0R00GLF"
			(at 2.234 296.906 0)
			(layer "F.Fab")
			(hide yes)
			(effects
				(font
					(size 1 1)
					(thickness 0.15)
				)
			)
		)
		(property "Manufacturer" "Bourns"
			(at 2.234 296.906 0)
			(layer "F.Fab")
			(hide yes)
			(effects
				(font
					(size 1 1)
					(thickness 0.15)
				)
			)
		)
		(property "Tolerance" "1%"
			(at 2.234 296.906 0)
			(layer "F.Fab")
			(hide yes)
			(effects
				(font
					(size 1 1)
					(thickness 0.15)
				)
			)
		)
		(property "Val" "0R"
			(at 2.234 296.906 0)
			(layer "F.Fab")
			(hide yes)
			(effects
				(font
					(size 1 1)
					(thickness 0.15)
				)
			)
		)
		(sheetname "KR to SFI #1")
		(sheetfile "kr_sfi.kicad_sch")
		(attr smd)
		(fp_rect
			(start -0.7 -0.35)
			(end 0.7 0.35)
			(stroke
				(width 0.05)
				(type default)
			)
			(fill no)
			(layer "F.CrtYd")
		)
		(fp_rect
			(start -0.3 -0.15)
			(end 0.298 0.148)
			(stroke
				(width 0.15)
				(type solid)
			)
			(fill no)
			(layer "F.Fab")
		)
		(pad "" smd roundrect
			(at -0.346 0 270)
			(size 0.318 0.36)
			(layers "F.Paste")
			(roundrect_rratio 0.25)
			(teardrops
				(best_length_ratio 0.2)
				(max_length 1)
				(best_width_ratio 0.9)
				(max_width 2)
				(curved_edges yes)
				(filter_ratio 0.9)
				(enabled yes)
				(allow_two_segments yes)
				(prefer_zone_connections yes)
			)
		)
		(pad "" smd roundrect
			(at 0.344 0 270)
			(size 0.318 0.36)
			(layers "F.Paste")
			(roundrect_rratio 0.25)
			(teardrops
				(best_length_ratio 0.2)
				(max_length 1)
				(best_width_ratio 0.9)
				(max_width 2)
				(curved_edges yes)
				(filter_ratio 0.9)
				(enabled yes)
				(allow_two_segments yes)
				(prefer_zone_connections yes)
			)
		)
		(pad "1" smd roundrect
			(at -0.32 0 270)
			(size 0.46 0.4)
			(layers "F.Cu" "F.Mask")
			(roundrect_rratio 0.25)
			(net 667 "/2xSFP+/KR to SFI #1/SFI_R.RX+")
			(pintype "passive")
			(teardrops
				(best_length_ratio 0.2)
				(max_length 1)
				(best_width_ratio 0.9)
				(max_width 2)
				(curved_edges yes)
				(filter_ratio 0.9)
				(enabled yes)
				(allow_two_segments yes)
				(prefer_zone_connections yes)
			)
		)
		(pad "2" smd roundrect
			(at 0.32 0 270)
			(size 0.46 0.4)
			(layers "F.Cu" "F.Mask")
			(roundrect_rratio 0.25)
			(net 171 "/2xSFP+/SFI0.RX+")
			(pintype "passive")
			(teardrops
				(best_length_ratio 0.2)
				(max_length 1)
				(best_width_ratio 0.9)
				(max_width 2)
				(curved_edges yes)
				(filter_ratio 0.9)
				(enabled yes)
				(allow_two_segments yes)
				(prefer_zone_connections yes)
			)
		)
	)
	(footprint "antmicro-footprints:L_WE-MAPI-4020"
		(layer "F.Cu")
		(at 311.240498 130.51 180)
		(property "Reference" "L4"
			(at -2.309502 1.45 0)
			(layer "F.SilkS")
			(effects
				(font
					(size 0.7 0.7)
					(thickness 0.15)
				)
				(justify left bottom)
			)
		)
		(property "Value" "L_1u8_6.8A_WE-MAPI-4020"
			(at -2.4 3.4 0)
			(layer "F.Fab")
			(effects
				(font
					(size 0.7 0.7)
					(thickness 0.15)
				)
				(justify left bottom)
			)
		)
		(property "Datasheet" "https://www.we-online.com/components/products/datasheet/74438356018.pdf"
			(at 0 0 180)
			(layer "F.Fab")
			(hide yes)
			(effects
				(font
					(size 1.27 1.27)
					(thickness 0.15)
				)
			)
		)
		(property "Author" "Antmicro"
			(at 622.480996 261.02 0)
			(layer "F.Fab")
			(hide yes)
			(effects
				(font
					(size 1 1)
					(thickness 0.15)
				)
			)
		)
		(property "IMax" "6.8 A"
			(at 622.480996 261.02 0)
			(layer "F.Fab")
			(hide yes)
			(effects
				(font
					(size 1 1)
					(thickness 0.15)
				)
			)
		)
		(property "ISat" "6.5 A"
			(at 622.480996 261.02 0)
			(layer "F.Fab")
			(hide yes)
			(effects
				(font
					(size 1 1)
					(thickness 0.15)
				)
			)
		)
		(property "License" "Apache-2.0"
			(at 622.480996 261.02 0)
			(layer "F.Fab")
			(hide yes)
			(effects
				(font
					(size 1 1)
					(thickness 0.15)
				)
			)
		)
		(property "MPN" "74438356018"
			(at 622.480996 261.02 0)
			(layer "F.Fab")
			(hide yes)
			(effects
				(font
					(size 1 1)
					(thickness 0.15)
				)
			)
		)
		(property "Manufacturer" "Würth Elektronik"
			(at 622.480996 261.02 0)
			(layer "F.Fab")
			(hide yes)
			(effects
				(font
					(size 1 1)
					(thickness 0.15)
				)
			)
		)
		(property "Public" "False"
			(at 622.480996 261.02 0)
			(layer "F.Fab")
			(hide yes)
			(effects
				(font
					(size 1 1)
					(thickness 0.15)
				)
			)
		)
		(property "Size" "4.1x4.1mm"
			(at 622.480996 261.02 0)
			(layer "F.Fab")
			(hide yes)
			(effects
				(font
					(size 1 1)
					(thickness 0.15)
				)
			)
		)
		(property "Val" "1u8/6.8A"
			(at 622.480996 261.02 0)
			(layer "F.Fab")
			(hide yes)
			(effects
				(font
					(size 1 1)
					(thickness 0.15)
				)
			)
		)
		(sheetname "Power")
		(sheetfile "power.kicad_sch")
		(attr smd)
		(fp_rect
			(start -2.2 -2.2)
			(end 2.2 2.2)
			(stroke
				(width 0.15)
				(type solid)
			)
			(fill no)
			(layer "F.SilkS")
		)
		(fp_rect
			(start -2.3 -2.3)
			(end 2.3 2.3)
			(stroke
				(width 0.05)
				(type solid)
			)
			(fill no)
			(layer "F.CrtYd")
		)
		(fp_rect
			(start -2.05 -2.05)
			(end 2.05 2.05)
			(stroke
				(width 0.15)
				(type solid)
			)
			(fill no)
			(layer "F.Fab")
		)
		(pad "1" smd roundrect
			(at -1.185 0 270)
			(size 3.7 1)
			(layers "F.Cu" "F.Mask" "F.Paste")
			(roundrect_rratio 0.1)
			(net 871 "Net-(U22-SW)")
			(pintype "passive")
			(teardrops
				(best_length_ratio 0.2)
				(max_length 1)
				(best_width_ratio 0.9)
				(max_width 2)
				(curved_edges yes)
				(filter_ratio 0.9)
				(enabled yes)
				(allow_two_segments yes)
				(prefer_zone_connections yes)
			)
		)
		(pad "2" smd roundrect
			(at 1.185 0 270)
			(size 3.7 1)
			(layers "F.Cu" "F.Mask" "F.Paste")
			(roundrect_rratio 0.1)
			(net 76 "Net-(C63-Pad2)")
			(pintype "passive")
			(teardrops
				(best_length_ratio 0.2)
				(max_length 1)
				(best_width_ratio 0.9)
				(max_width 2)
				(curved_edges yes)
				(filter_ratio 0.9)
				(enabled yes)
				(allow_two_segments yes)
				(prefer_zone_connections yes)
			)
		)
	)
	(footprint "antmicro-footprints:R_0402_1005Metric"
		(layer "F.Cu")
		(at 112.4 144.36 90)
		(descr "Resistor SMD 0402")
		(tags "resistor SMD 0402")
		(property "Reference" "R207"
			(at 0.8 0.4 90)
			(layer "F.SilkS")
			(effects
				(font
					(size 0.7 0.7)
					(thickness 0.15)
				)
				(justify left bottom)
			)
		)
		(property "Value" "R_1k_0402"
			(at -1.011843 1.772047 90)
			(layer "F.Fab")
			(effects
				(font
					(size 0.7 0.7)
					(thickness 0.15)
				)
				(justify left bottom)
			)
		)
		(property "Datasheet" "https://www.bourns.com/docs/product-datasheets/cr.pdf"
			(at 0 0 90)
			(layer "F.Fab")
			(hide yes)
			(effects
				(font
					(size 1.27 1.27)
					(thickness 0.15)
				)
			)
		)
		(property "Author" "Antmicro"
			(at 256.76 31.96 0)
			(layer "F.Fab")
			(hide yes)
			(effects
				(font
					(size 1 1)
					(thickness 0.15)
				)
			)
		)
		(property "License" "Apache-2.0"
			(at 256.76 31.96 0)
			(layer "F.Fab")
			(hide yes)
			(effects
				(font
					(size 1 1)
					(thickness 0.15)
				)
			)
		)
		(property "MPN" "CR0402-FX-1001GLF"
			(at 256.76 31.96 0)
			(layer "F.Fab")
			(hide yes)
			(effects
				(font
					(size 1 1)
					(thickness 0.15)
				)
			)
		)
		(property "Manufacturer" "Bourns"
			(at 256.76 31.96 0)
			(layer "F.Fab")
			(hide yes)
			(effects
				(font
					(size 1 1)
					(thickness 0.15)
				)
			)
		)
		(property "Public" "False"
			(at 256.76 31.96 0)
			(layer "F.Fab")
			(hide yes)
			(effects
				(font
					(size 1 1)
					(thickness 0.15)
				)
			)
		)
		(property "Tolerance" "1%"
			(at 256.76 31.96 0)
			(layer "F.Fab")
			(hide yes)
			(effects
				(font
					(size 1 1)
					(thickness 0.15)
				)
			)
		)
		(property "Val" "1k"
			(at 256.76 31.96 0)
			(layer "F.Fab")
			(hide yes)
			(effects
				(font
					(size 1 1)
					(thickness 0.15)
				)
			)
		)
		(sheetname "PCIe redriver")
		(sheetfile "pcie_redriver.kicad_sch")
		(attr smd dnp)
		(fp_rect
			(start -0.925 -0.47)
			(end 0.925 0.47)
			(stroke
				(width 0.05)
				(type default)
			)
			(fill no)
			(layer "F.CrtYd")
		)
		(fp_rect
			(start -0.5 -0.25)
			(end 0.5 0.25)
			(stroke
				(width 0.15)
				(type solid)
			)
			(fill no)
			(layer "F.Fab")
		)
		(pad "1" smd roundrect
			(at -0.48 0 90)
			(size 0.59 0.64)
			(layers "F.Cu" "F.Mask" "F.Paste")
			(roundrect_rratio 0.25)
			(net 1 "GND")
			(pintype "passive")
			(teardrops
				(best_length_ratio 0.2)
				(max_length 1)
				(best_width_ratio 0.9)
				(max_width 2)
				(curved_edges yes)
				(filter_ratio 0.9)
				(enabled yes)
				(allow_two_segments yes)
				(prefer_zone_connections yes)
			)
		)
		(pad "2" smd roundrect
			(at 0.48 0 90)
			(size 0.59 0.64)
			(layers "F.Cu" "F.Mask" "F.Paste")
			(roundrect_rratio 0.25)
			(net 625 "/PCIe redriver/TX_EQ2")
			(pintype "passive")
			(teardrops
				(best_length_ratio 0.2)
				(max_length 1)
				(best_width_ratio 0.9)
				(max_width 2)
				(curved_edges yes)
				(filter_ratio 0.9)
				(enabled yes)
				(allow_two_segments yes)
				(prefer_zone_connections yes)
			)
		)
	)
	(footprint "antmicro-footprints:C_0402_1005Metric"
		(layer "F.Cu")
		(at 118.9 148.421 -90)
		(descr "Capacitor SMD 0402")
		(tags "capacitor SMD 0402")
		(property "Reference" "C119"
			(at -12.611 -1.1 90)
			(layer "F.SilkS")
			(effects
				(font
					(size 0.7 0.7)
					(thickness 0.15)
				)
				(justify right bottom)
			)
		)
		(property "Value" "C_100n_0402"
			(at -1.022927 2.155213 90)
			(layer "F.Fab")
			(effects
				(font
					(size 0.7 0.7)
					(thickness 0.15)
				)
				(justify right bottom)
			)
		)
		(property "Datasheet" "https://www.murata.com/products/productdetail?partno=GRM155R61H104KE14%23"
			(at 0 0 270)
			(layer "F.Fab")
			(hide yes)
			(effects
				(font
					(size 1.27 1.27)
					(thickness 0.15)
				)
			)
		)
		(property "Author" "Antmicro"
			(at -29.521 267.321 0)
			(layer "F.Fab")
			(hide yes)
			(effects
				(font
					(size 1 1)
					(thickness 0.15)
				)
			)
		)
		(property "Dielectric" "X5R"
			(at -29.521 267.321 0)
			(layer "F.Fab")
			(hide yes)
			(effects
				(font
					(size 1 1)
					(thickness 0.15)
				)
			)
		)
		(property "License" "Apache-2.0"
			(at -29.521 267.321 0)
			(layer "F.Fab")
			(hide yes)
			(effects
				(font
					(size 1 1)
					(thickness 0.15)
				)
			)
		)
		(property "MPN" "GRM155R61H104KE14D"
			(at -29.521 267.321 0)
			(layer "F.Fab")
			(hide yes)
			(effects
				(font
					(size 1 1)
					(thickness 0.15)
				)
			)
		)
		(property "Manufacturer" "Murata"
			(at -29.521 267.321 0)
			(layer "F.Fab")
			(hide yes)
			(effects
				(font
					(size 1 1)
					(thickness 0.15)
				)
			)
		)
		(property "Public" "False"
			(at -29.521 267.321 0)
			(layer "F.Fab")
			(hide yes)
			(effects
				(font
					(size 1 1)
					(thickness 0.15)
				)
			)
		)
		(property "Val" "100n"
			(at -29.521 267.321 0)
			(layer "F.Fab")
			(hide yes)
			(effects
				(font
					(size 1 1)
					(thickness 0.15)
				)
			)
		)
		(property "Voltage" "50V"
			(at -29.521 267.321 0)
			(layer "F.Fab")
			(hide yes)
			(effects
				(font
					(size 1 1)
					(thickness 0.15)
				)
			)
		)
		(sheetname "PCIe redriver")
		(sheetfile "pcie_redriver.kicad_sch")
		(attr smd)
		(fp_rect
			(start -0.925 -0.47)
			(end 0.925 0.47)
			(stroke
				(width 0.05)
				(type default)
			)
			(fill no)
			(layer "F.CrtYd")
		)
		(fp_line
			(start -0.494 0.248)
			(end -0.494 -0.25)
			(stroke
				(width 0.15)
				(type solid)
			)
			(layer "F.Fab")
		)
		(fp_line
			(start 0.504 0.248)
			(end -0.494 0.248)
			(stroke
				(width 0.15)
				(type solid)
			)
			(layer "F.Fab")
		)
		(fp_line
			(start -0.494 -0.25)
			(end 0.504 -0.25)
			(stroke
				(width 0.15)
				(type solid)
			)
			(layer "F.Fab")
		)
		(fp_line
			(start 0.504 -0.25)
			(end 0.504 0.248)
			(stroke
				(width 0.15)
				(type solid)
			)
			(layer "F.Fab")
		)
		(pad "1" smd roundrect
			(at -0.48 0 270)
			(size 0.59 0.64)
			(layers "F.Cu" "F.Mask" "F.Paste")
			(roundrect_rratio 0.25)
			(net 1 "GND")
			(pintype "passive")
			(teardrops
				(best_length_ratio 0.2)
				(max_length 1)
				(best_width_ratio 0.9)
				(max_width 2)
				(curved_edges yes)
				(filter_ratio 0.9)
				(enabled yes)
				(allow_two_segments yes)
				(prefer_zone_connections yes)
			)
		)
		(pad "2" smd roundrect
			(at 0.48 0 270)
			(size 0.59 0.64)
			(layers "F.Cu" "F.Mask" "F.Paste")
			(roundrect_rratio 0.25)
			(net 2 "+3V3")
			(pintype "passive")
			(teardrops
				(best_length_ratio 0.2)
				(max_length 1)
				(best_width_ratio 0.9)
				(max_width 2)
				(curved_edges yes)
				(filter_ratio 0.9)
				(enabled yes)
				(allow_two_segments yes)
				(prefer_zone_connections yes)
			)
		)
	)
	(footprint "antmicro-footprints:C_0402_1005Metric"
		(layer "F.Cu")
		(at 302.575 140.185 -90)
		(descr "Capacitor SMD 0402")
		(tags "capacitor SMD 0402")
		(property "Reference" "C46"
			(at -0.875 0.525 90)
			(layer "F.SilkS")
			(effects
				(font
					(size 0.7 0.7)
					(thickness 0.15)
				)
				(justify right bottom)
			)
		)
		(property "Value" "C_1u_0402"
			(at -1.022927 2.155213 90)
			(layer "F.Fab")
			(effects
				(font
					(size 0.7 0.7)
					(thickness 0.15)
				)
				(justify right bottom)
			)
		)
		(property "Datasheet" "https://product.tdk.com/en/search/capacitor/ceramic/mlcc/info?part_no=C1005X6S1A105K050BC"
			(at 0 0 270)
			(layer "F.Fab")
			(hide yes)
			(effects
				(font
					(size 1.27 1.27)
					(thickness 0.15)
				)
			)
		)
		(property "Author" "Antmicro"
			(at 162.39 442.76 0)
			(layer "F.Fab")
			(hide yes)
			(effects
				(font
					(size 1 1)
					(thickness 0.15)
				)
			)
		)
		(property "Dielectric" ""
			(at 162.39 442.76 0)
			(layer "F.Fab")
			(hide yes)
			(effects
				(font
					(size 1 1)
					(thickness 0.15)
				)
			)
		)
		(property "License" "Apache-2.0"
			(at 162.39 442.76 0)
			(layer "F.Fab")
			(hide yes)
			(effects
				(font
					(size 1 1)
					(thickness 0.15)
				)
			)
		)
		(property "MPN" "C1005X6S1A105K050BC"
			(at 162.39 442.76 0)
			(layer "F.Fab")
			(hide yes)
			(effects
				(font
					(size 1 1)
					(thickness 0.15)
				)
			)
		)
		(property "Manufacturer" "TDK"
			(at 162.39 442.76 0)
			(layer "F.Fab")
			(hide yes)
			(effects
				(font
					(size 1 1)
					(thickness 0.15)
				)
			)
		)
		(property "Public" "False"
			(at 162.39 442.76 0)
			(layer "F.Fab")
			(hide yes)
			(effects
				(font
					(size 1 1)
					(thickness 0.15)
				)
			)
		)
		(property "Val" "1u"
			(at 162.39 442.76 0)
			(layer "F.Fab")
			(hide yes)
			(effects
				(font
					(size 1 1)
					(thickness 0.15)
				)
			)
		)
		(property "Voltage" ""
			(at 162.39 442.76 0)
			(layer "F.Fab")
			(hide yes)
			(effects
				(font
					(size 1 1)
					(thickness 0.15)
				)
			)
		)
		(sheetname "Power")
		(sheetfile "power.kicad_sch")
		(attr smd)
		(fp_rect
			(start -0.925 -0.47)
			(end 0.925 0.47)
			(stroke
				(width 0.05)
				(type default)
			)
			(fill no)
			(layer "F.CrtYd")
		)
		(fp_line
			(start -0.494 0.248)
			(end -0.494 -0.25)
			(stroke
				(width 0.15)
				(type solid)
			)
			(layer "F.Fab")
		)
		(fp_line
			(start 0.504 0.248)
			(end -0.494 0.248)
			(stroke
				(width 0.15)
				(type solid)
			)
			(layer "F.Fab")
		)
		(fp_line
			(start -0.494 -0.25)
			(end 0.504 -0.25)
			(stroke
				(width 0.15)
				(type solid)
			)
			(layer "F.Fab")
		)
		(fp_line
			(start 0.504 -0.25)
			(end 0.504 0.248)
			(stroke
				(width 0.15)
				(type solid)
			)
			(layer "F.Fab")
		)
		(pad "1" smd roundrect
			(at -0.48 0 270)
			(size 0.59 0.64)
			(layers "F.Cu" "F.Mask" "F.Paste")
			(roundrect_rratio 0.25)
			(net 1 "GND")
			(pintype "passive")
			(teardrops
				(best_length_ratio 0.2)
				(max_length 1)
				(best_width_ratio 0.9)
				(max_width 2)
				(curved_edges yes)
				(filter_ratio 0.9)
				(enabled yes)
				(allow_two_segments yes)
				(prefer_zone_connections yes)
			)
		)
		(pad "2" smd roundrect
			(at 0.48 0 270)
			(size 0.59 0.64)
			(layers "F.Cu" "F.Mask" "F.Paste")
			(roundrect_rratio 0.25)
			(net 65 "+12V")
			(pintype "passive")
			(teardrops
				(best_length_ratio 0.2)
				(max_length 1)
				(best_width_ratio 0.9)
				(max_width 2)
				(curved_edges yes)
				(filter_ratio 0.9)
				(enabled yes)
				(allow_two_segments yes)
				(prefer_zone_connections yes)
			)
		)
	)
	(footprint "antmicro-footprints:R_0402_1005Metric"
		(layer "F.Cu")
		(at 156.475 71.31 180)
		(descr "Resistor SMD 0402")
		(tags "resistor SMD 0402")
		(property "Reference" "R133"
			(at -3.65 -0.45 0)
			(layer "F.SilkS")
			(effects
				(font
					(size 0.7 0.7)
					(thickness 0.15)
				)
				(justify right bottom)
			)
		)
		(property "Value" "R_0R_0402"
			(at -1.011843 1.772047 0)
			(layer "F.Fab")
			(effects
				(font
					(size 0.7 0.7)
					(thickness 0.15)
				)
				(justify right bottom)
			)
		)
		(property "Datasheet" "https://industrial.panasonic.com/cdbs/www-data/pdf/RDA0000/AOA0000C301.pdf"
			(at 0 0 180)
			(layer "F.Fab")
			(hide yes)
			(effects
				(font
					(size 1.27 1.27)
					(thickness 0.15)
				)
			)
		)
		(property "Author" "Antmicro"
			(at 312.95 142.62 0)
			(layer "F.Fab")
			(hide yes)
			(effects
				(font
					(size 1 1)
					(thickness 0.15)
				)
			)
		)
		(property "Current" "1A"
			(at 312.95 142.62 0)
			(layer "F.Fab")
			(hide yes)
			(effects
				(font
					(size 1 1)
					(thickness 0.15)
				)
			)
		)
		(property "License" "Apache-2.0"
			(at 312.95 142.62 0)
			(layer "F.Fab")
			(hide yes)
			(effects
				(font
					(size 1 1)
					(thickness 0.15)
				)
			)
		)
		(property "MPN" "ERJ2GE0R00X"
			(at 312.95 142.62 0)
			(layer "F.Fab")
			(hide yes)
			(effects
				(font
					(size 1 1)
					(thickness 0.15)
				)
			)
		)
		(property "Manufacturer" "Panasonic"
			(at 312.95 142.62 0)
			(layer "F.Fab")
			(hide yes)
			(effects
				(font
					(size 1 1)
					(thickness 0.15)
				)
			)
		)
		(property "Public" "False"
			(at 312.95 142.62 0)
			(layer "F.Fab")
			(hide yes)
			(effects
				(font
					(size 1 1)
					(thickness 0.15)
				)
			)
		)
		(property "Tolerance" ""
			(at 312.95 142.62 0)
			(layer "F.Fab")
			(hide yes)
			(effects
				(font
					(size 1 1)
					(thickness 0.15)
				)
			)
		)
		(property "Val" "0R"
			(at 312.95 142.62 0)
			(layer "F.Fab")
			(hide yes)
			(effects
				(font
					(size 1 1)
					(thickness 0.15)
				)
			)
		)
		(sheetname "M.2 key E")
		(sheetfile "m2keye.kicad_sch")
		(attr smd)
		(fp_rect
			(start -0.925 -0.47)
			(end 0.925 0.47)
			(stroke
				(width 0.05)
				(type default)
			)
			(fill no)
			(layer "F.CrtYd")
		)
		(fp_rect
			(start -0.5 -0.25)
			(end 0.5 0.25)
			(stroke
				(width 0.15)
				(type solid)
			)
			(fill no)
			(layer "F.Fab")
		)
		(pad "1" smd roundrect
			(at -0.48 0 180)
			(size 0.59 0.64)
			(layers "F.Cu" "F.Mask" "F.Paste")
			(roundrect_rratio 0.25)
			(net 378 "/Com Express 7 Interfaces/USB1.D+")
			(pintype "passive")
			(teardrops
				(best_length_ratio 0.2)
				(max_length 1)
				(best_width_ratio 0.9)
				(max_width 2)
				(curved_edges yes)
				(filter_ratio 0.9)
				(enabled yes)
				(allow_two_segments yes)
				(prefer_zone_connections yes)
			)
		)
		(pad "2" smd roundrect
			(at 0.48 0 180)
			(size 0.59 0.64)
			(layers "F.Cu" "F.Mask" "F.Paste")
			(roundrect_rratio 0.25)
			(net 3 "/M.2 key E/WIFI_BT_USB_D_P")
			(pintype "passive")
			(teardrops
				(best_length_ratio 0.2)
				(max_length 1)
				(best_width_ratio 0.9)
				(max_width 2)
				(curved_edges yes)
				(filter_ratio 0.9)
				(enabled yes)
				(allow_two_segments yes)
				(prefer_zone_connections yes)
			)
		)
	)
	(footprint "antmicro-footprints:C_Pol_EIA-B"
		(layer "F.Cu")
		(at 308.825 135.8135)
		(property "Reference" "C65"
			(at -1.975 2.6465 0)
			(layer "F.SilkS")
			(effects
				(font
					(size 0.7 0.7)
					(thickness 0.15)
				)
				(justify left bottom)
			)
		)
		(property "Value" "C_Pol_100u_10V_KEMET-T520-B"
			(at -3.965 2.1265 0)
			(layer "F.Fab")
			(effects
				(font
					(size 0.7 0.7)
					(thickness 0.15)
				)
				(justify right bottom mirror)
			)
		)
		(property "Datasheet" "https://www.kemet.com/en/us/capacitors/product/T520B107M010ATE070.html"
			(at 0 0 0)
			(layer "F.Fab")
			(hide yes)
			(effects
				(font
					(size 1.27 1.27)
					(thickness 0.15)
				)
			)
		)
		(property "Author" "Antmicro"
			(at 0 0 0)
			(layer "F.Fab")
			(hide yes)
			(effects
				(font
					(size 1 1)
					(thickness 0.15)
				)
			)
		)
		(property "Dielectric" "template_dielectric"
			(at 0 0 0)
			(layer "F.Fab")
			(hide yes)
			(effects
				(font
					(size 1 1)
					(thickness 0.15)
				)
			)
		)
		(property "License" "Apache-2.0"
			(at 0 0 0)
			(layer "F.Fab")
			(hide yes)
			(effects
				(font
					(size 1 1)
					(thickness 0.15)
				)
			)
		)
		(property "MPN" "T520B107M010ATE070"
			(at 0 0 0)
			(layer "F.Fab")
			(hide yes)
			(effects
				(font
					(size 1 1)
					(thickness 0.15)
				)
			)
		)
		(property "Manufacturer" "KEMET"
			(at 0 0 0)
			(layer "F.Fab")
			(hide yes)
			(effects
				(font
					(size 1 1)
					(thickness 0.15)
				)
			)
		)
		(property "Public" "False"
			(at 0 0 0)
			(layer "F.Fab")
			(hide yes)
			(effects
				(font
					(size 1 1)
					(thickness 0.15)
				)
			)
		)
		(property "Val" "100u"
			(at 0 0 0)
			(layer "F.Fab")
			(hide yes)
			(effects
				(font
					(size 1 1)
					(thickness 0.15)
				)
			)
		)
		(property "Voltage" "10V"
			(at 0 0 0)
			(layer "F.Fab")
			(hide yes)
			(effects
				(font
					(size 1 1)
					(thickness 0.15)
				)
			)
		)
		(sheetname "Power")
		(sheetfile "power.kicad_sch")
		(attr smd)
		(fp_line
			(start -2.521 -1.676)
			(end -2.123 -1.676)
			(stroke
				(width 0.15)
				(type solid)
			)
			(layer "F.SilkS")
		)
		(fp_line
			(start -2.325 -1.475)
			(end -2.325 -1.878)
			(stroke
				(width 0.15)
				(type solid)
			)
			(layer "F.SilkS")
		)
		(fp_line
			(start -1.8 -1.6)
			(end 1.8 -1.6)
			(stroke
				(width 0.15)
				(type solid)
			)
			(layer "F.SilkS")
		)
		(fp_line
			(start -1.8 -1.3)
			(end -1.8 -1.6)
			(stroke
				(width 0.15)
				(type solid)
			)
			(layer "F.SilkS")
		)
		(fp_line
			(start -1.8 1.3)
			(end -1.8 1.6)
			(stroke
				(width 0.15)
				(type solid)
			)
			(layer "F.SilkS")
		)
		(fp_line
			(start 1.8 -1.3)
			(end 1.8 -1.6)
			(stroke
				(width 0.15)
				(type solid)
			)
			(layer "F.SilkS")
		)
		(fp_line
			(start 1.8 1.3)
			(end 1.8 1.6)
			(stroke
				(width 0.15)
				(type solid)
			)
			(layer "F.SilkS")
		)
		(fp_line
			(start 1.8 1.6)
			(end -1.8 1.6)
			(stroke
				(width 0.15)
				(type solid)
			)
			(layer "F.SilkS")
		)
		(fp_line
			(start -2.411 -1.35)
			(end -2.41 1.35)
			(stroke
				(width 0.05)
				(type solid)
			)
			(layer "F.CrtYd")
		)
		(fp_line
			(start -1.97 -1.75)
			(end -1.97 -1.35)
			(stroke
				(width 0.05)
				(type solid)
			)
			(layer "F.CrtYd")
		)
		(fp_line
			(start -1.97 -1.35)
			(end -2.41 -1.35)
			(stroke
				(width 0.05)
				(type solid)
			)
			(layer "F.CrtYd")
		)
		(fp_line
			(start -1.97 1.35)
			(end -2.41 1.35)
			(stroke
				(width 0.05)
				(type solid)
			)
			(layer "F.CrtYd")
		)
		(fp_line
			(start -1.97 1.35)
			(end -1.97 1.75)
			(stroke
				(width 0.05)
				(type solid)
			)
			(layer "F.CrtYd")
		)
		(fp_line
			(start 1.959 -1.75)
			(end -1.97 -1.75)
			(stroke
				(width 0.05)
				(type solid)
			)
			(layer "F.CrtYd")
		)
		(fp_line
			(start 1.959 -1.75)
			(end 1.959 -1.35)
			(stroke
				(width 0.05)
				(type solid)
			)
			(layer "F.CrtYd")
		)
		(fp_line
			(start 1.96 1.35)
			(end 1.96 1.75)
			(stroke
				(width 0.05)
				(type solid)
			)
			(layer "F.CrtYd")
		)
		(fp_line
			(start 1.96 1.75)
			(end -1.97 1.75)
			(stroke
				(width 0.05)
				(type solid)
			)
			(layer "F.CrtYd")
		)
		(fp_line
			(start 2.399 -1.35)
			(end 1.959 -1.35)
			(stroke
				(width 0.05)
				(type solid)
			)
			(layer "F.CrtYd")
		)
		(fp_line
			(start 2.399 -1.35)
			(end 2.4 1.35)
			(stroke
				(width 0.05)
				(type solid)
			)
			(layer "F.CrtYd")
		)
		(fp_line
			(start 2.4 1.35)
			(end 1.96 1.35)
			(stroke
				(width 0.05)
				(type solid)
			)
			(layer "F.CrtYd")
		)
		(fp_line
			(start -1.7 1.324)
			(end -1.551 1.475)
			(stroke
				(width 0.15)
				(type solid)
			)
			(layer "F.Fab")
		)
		(fp_rect
			(start -1.72 -1.5)
			(end 1.719 1.499)
			(stroke
				(width 0.15)
				(type solid)
			)
			(fill no)
			(layer "F.Fab")
		)
		(pad "1" smd roundrect
			(at -1.551 0)
			(size 1.2 2.2)
			(layers "F.Cu" "F.Mask" "F.Paste")
			(roundrect_rratio 0.1)
			(net 76 "Net-(C63-Pad2)")
			(pintype "passive")
			(teardrops
				(best_length_ratio 0.2)
				(max_length 1)
				(best_width_ratio 0.9)
				(max_width 2)
				(curved_edges yes)
				(filter_ratio 0.9)
				(enabled yes)
				(allow_two_segments yes)
				(prefer_zone_connections yes)
			)
		)
		(pad "2" smd roundrect
			(at 1.55 0)
			(size 1.2 2.2)
			(layers "F.Cu" "F.Mask" "F.Paste")
			(roundrect_rratio 0.1)
			(net 1 "GND")
			(pintype "passive")
			(teardrops
				(best_length_ratio 0.2)
				(max_length 1)
				(best_width_ratio 0.9)
				(max_width 2)
				(curved_edges yes)
				(filter_ratio 0.9)
				(enabled yes)
				(allow_two_segments yes)
				(prefer_zone_connections yes)
			)
		)
	)
	(footprint "antmicro-footprints:SOT-23-8"
		(layer "F.Cu")
		(at 244.05 129.26 -90)
		(descr "http://www.ti.com/lit/ds/symlink/ina219.pdf")
		(property "Reference" "U34"
			(at 1.4 1.7 180)
			(layer "F.SilkS")
			(effects
				(font
					(size 0.7 0.7)
					(thickness 0.15)
				)
				(justify right bottom)
			)
		)
		(property "Value" "LTC2950CTS8-1"
			(at 0 2.8 90)
			(layer "F.Fab")
			(effects
				(font
					(size 0.7 0.7)
					(thickness 0.15)
				)
				(justify right bottom)
			)
		)
		(property "Datasheet" "https://www.analog.com/media/en/technical-documentation/data-sheets/295012fd.pdf"
			(at 0 0 270)
			(layer "F.Fab")
			(hide yes)
			(effects
				(font
					(size 1.27 1.27)
					(thickness 0.15)
				)
			)
		)
		(property "Author" "Antmicro"
			(at 114.79 373.31 0)
			(layer "F.Fab")
			(hide yes)
			(effects
				(font
					(size 1 1)
					(thickness 0.15)
				)
			)
		)
		(property "License" "Apache-2.0"
			(at 114.79 373.31 0)
			(layer "F.Fab")
			(hide yes)
			(effects
				(font
					(size 1 1)
					(thickness 0.15)
				)
			)
		)
		(property "MPN" "LTC2950CTS8-1"
			(at 114.79 373.31 0)
			(layer "F.Fab")
			(hide yes)
			(effects
				(font
					(size 1 1)
					(thickness 0.15)
				)
			)
		)
		(property "Manufacturer" "Analog Devices"
			(at 114.79 373.31 0)
			(layer "F.Fab")
			(hide yes)
			(effects
				(font
					(size 1 1)
					(thickness 0.15)
				)
			)
		)
		(sheetname "Com Express 7 MGMT")
		(sheetfile "com_express_7_mgmt.kicad_sch")
		(attr smd)
		(fp_line
			(start -0.987 1.6)
			(end -0.987 1.324)
			(stroke
				(width 0.15)
				(type solid)
			)
			(layer "F.SilkS")
		)
		(fp_line
			(start -0.613 1.6)
			(end -0.987 1.6)
			(stroke
				(width 0.15)
				(type solid)
			)
			(layer "F.SilkS")
		)
		(fp_line
			(start 1 1.6)
			(end 0.6 1.6)
			(stroke
				(width 0.15)
				(type solid)
			)
			(layer "F.SilkS")
		)
		(fp_line
			(start 1 1.3)
			(end 1 1.6)
			(stroke
				(width 0.15)
				(type solid)
			)
			(layer "F.SilkS")
		)
		(fp_line
			(start -1 -1.3)
			(end -1 -1.6)
			(stroke
				(width 0.15)
				(type solid)
			)
			(layer "F.SilkS")
		)
		(fp_line
			(start 1 -1.3)
			(end 1 -1.6)
			(stroke
				(width 0.15)
				(type solid)
			)
			(layer "F.SilkS")
		)
		(fp_line
			(start -1 -1.6)
			(end -0.6 -1.6)
			(stroke
				(width 0.15)
				(type solid)
			)
			(layer "F.SilkS")
		)
		(fp_line
			(start 1 -1.6)
			(end 0.625 -1.6)
			(stroke
				(width 0.15)
				(type solid)
			)
			(layer "F.SilkS")
		)
		(fp_circle
			(center -1.3 -1.4)
			(end -1.25 -1.4)
			(stroke
				(width 0.15)
				(type solid)
			)
			(fill yes)
			(layer "F.SilkS")
		)
		(fp_rect
			(start -1.9 -1.75)
			(end 1.898 1.75)
			(stroke
				(width 0.05)
				(type solid)
			)
			(fill no)
			(layer "F.CrtYd")
		)
		(fp_line
			(start -1.4 -1.25)
			(end -1.2 -1.45)
			(stroke
				(width 0.15)
				(type solid)
			)
			(layer "F.Fab")
		)
		(fp_rect
			(start -1.401 -1.45)
			(end 1.398 1.449)
			(stroke
				(width 0.15)
				(type solid)
			)
			(fill no)
			(layer "F.Fab")
		)
		(pad "1" smd roundrect
			(at -1.3 -0.975 180)
			(size 0.45 1.1)
			(layers "F.Cu" "F.Mask" "F.Paste")
			(roundrect_rratio 0.25)
			(net 73 "+3V3_AON")
			(pinfunction "V_{IN}")
			(pintype "power_in")
			(teardrops
				(best_length_ratio 0.2)
				(max_length 1)
				(best_width_ratio 0.9)
				(max_width 2)
				(curved_edges yes)
				(filter_ratio 0.9)
				(enabled yes)
				(allow_two_segments yes)
				(prefer_zone_connections yes)
			)
		)
		(pad "2" smd roundrect
			(at -1.3 -0.325 180)
			(size 0.45 1.1)
			(layers "F.Cu" "F.Mask" "F.Paste")
			(roundrect_rratio 0.25)
			(net 84 "/Com Express 7 MGMT/PWRBTN")
			(pinfunction "~{PB}")
			(pintype "input")
			(teardrops
				(best_length_ratio 0.2)
				(max_length 1)
				(best_width_ratio 0.9)
				(max_width 2)
				(curved_edges yes)
				(filter_ratio 0.9)
				(enabled yes)
				(allow_two_segments yes)
				(prefer_zone_connections yes)
			)
		)
		(pad "3" smd roundrect
			(at -1.3 0.325 180)
			(size 0.45 1.1)
			(layers "F.Cu" "F.Mask" "F.Paste")
			(roundrect_rratio 0.25)
			(net 48 "Net-(U34-ONT)")
			(pinfunction "ONT")
			(pintype "passive")
			(teardrops
				(best_length_ratio 0.2)
				(max_length 1)
				(best_width_ratio 0.9)
				(max_width 2)
				(curved_edges yes)
				(filter_ratio 0.9)
				(enabled yes)
				(allow_two_segments yes)
				(prefer_zone_connections yes)
			)
		)
		(pad "4" smd roundrect
			(at -1.3 0.975 180)
			(size 0.45 1.1)
			(layers "F.Cu" "F.Mask" "F.Paste")
			(roundrect_rratio 0.25)
			(net 1 "GND")
			(pinfunction "GND")
			(pintype "power_in")
			(teardrops
				(best_length_ratio 0.2)
				(max_length 1)
				(best_width_ratio 0.9)
				(max_width 2)
				(curved_edges yes)
				(filter_ratio 0.9)
				(enabled yes)
				(allow_two_segments yes)
				(prefer_zone_connections yes)
			)
		)
		(pad "5" smd roundrect
			(at 1.3 0.975 180)
			(size 0.45 1.1)
			(layers "F.Cu" "F.Mask" "F.Paste")
			(roundrect_rratio 0.25)
			(net 599 "Net-(U34-~{INT})")
			(pinfunction "~{INT}")
			(pintype "output")
			(teardrops
				(best_length_ratio 0.2)
				(max_length 1)
				(best_width_ratio 0.9)
				(max_width 2)
				(curved_edges yes)
				(filter_ratio 0.9)
				(enabled yes)
				(allow_two_segments yes)
				(prefer_zone_connections yes)
			)
		)
		(pad "6" smd roundrect
			(at 1.3 0.325 180)
			(size 0.45 1.1)
			(layers "F.Cu" "F.Mask" "F.Paste")
			(roundrect_rratio 0.25)
			(net 873 "Net-(U34-EN)")
			(pinfunction "EN")
			(pintype "output")
			(teardrops
				(best_length_ratio 0.2)
				(max_length 1)
				(best_width_ratio 0.9)
				(max_width 2)
				(curved_edges yes)
				(filter_ratio 0.9)
				(enabled yes)
				(allow_two_segments yes)
				(prefer_zone_connections yes)
			)
		)
		(pad "7" smd roundrect
			(at 1.3 -0.325 180)
			(size 0.45 1.1)
			(layers "F.Cu" "F.Mask" "F.Paste")
			(roundrect_rratio 0.25)
			(net 46 "Net-(U34-OFFT)")
			(pinfunction "OFFT")
			(pintype "passive")
			(teardrops
				(best_length_ratio 0.2)
				(max_length 1)
				(best_width_ratio 0.9)
				(max_width 2)
				(curved_edges yes)
				(filter_ratio 0.9)
				(enabled yes)
				(allow_two_segments yes)
				(prefer_zone_connections yes)
			)
		)
		(pad "8" smd roundrect
			(at 1.3 -0.975 180)
			(size 0.45 1.1)
			(layers "F.Cu" "F.Mask" "F.Paste")
			(roundrect_rratio 0.25)
			(net 872 "Net-(U34-~{KILL})")
			(pinfunction "~{KILL}")
			(pintype "input")
			(teardrops
				(best_length_ratio 0.2)
				(max_length 1)
				(best_width_ratio 0.9)
				(max_width 2)
				(curved_edges yes)
				(filter_ratio 0.9)
				(enabled yes)
				(allow_two_segments yes)
				(prefer_zone_connections yes)
			)
		)
	)
	(footprint "antmicro-footprints:QSOP-24_8.65x6mm_P0.635mm"
		(layer "F.Cu")
		(at 257.34 86.05 180)
		(property "Reference" "U24"
			(at -1.16 -5.52 0)
			(layer "F.SilkS")
			(effects
				(font
					(size 0.7 0.7)
					(thickness 0.15)
				)
				(justify right bottom)
			)
		)
		(property "Value" "ADT7476AARQZ"
			(at 0 2 90)
			(layer "F.Fab")
			(effects
				(font
					(size 0.7 0.7)
					(thickness 0.15)
				)
				(justify left bottom)
			)
		)
		(property "Datasheet" "https://www.onsemi.com/pdf/datasheet/adt7476a-d.pdf"
			(at 0 0 180)
			(layer "F.Fab")
			(hide yes)
			(effects
				(font
					(size 1.27 1.27)
					(thickness 0.15)
				)
			)
		)
		(property "Author" "Antmicro"
			(at 514.68 172.1 0)
			(layer "F.Fab")
			(hide yes)
			(effects
				(font
					(size 1 1)
					(thickness 0.15)
				)
			)
		)
		(property "License" "Apache-2.0"
			(at 514.68 172.1 0)
			(layer "F.Fab")
			(hide yes)
			(effects
				(font
					(size 1 1)
					(thickness 0.15)
				)
			)
		)
		(property "MPN" "ADT7476AARQZ"
			(at 514.68 172.1 0)
			(layer "F.Fab")
			(hide yes)
			(effects
				(font
					(size 1 1)
					(thickness 0.15)
				)
			)
		)
		(property "Manufacturer" "Onsemi"
			(at 514.68 172.1 0)
			(layer "F.Fab")
			(hide yes)
			(effects
				(font
					(size 1 1)
					(thickness 0.15)
				)
			)
		)
		(sheetname "Misc")
		(sheetfile "misc.kicad_sch")
		(attr smd)
		(fp_line
			(start 1.4 4.3)
			(end -1.4 4.3)
			(stroke
				(width 0.15)
				(type solid)
			)
			(layer "F.SilkS")
		)
		(fp_line
			(start -1.6 -4.3)
			(end 1.6 -4.3)
			(stroke
				(width 0.15)
				(type solid)
			)
			(layer "F.SilkS")
		)
		(fp_circle
			(center -3.55 -3.49)
			(end -3.5 -3.49)
			(stroke
				(width 0.15)
				(type solid)
			)
			(fill yes)
			(layer "F.SilkS")
		)
		(fp_rect
			(start -3.3 -4.6)
			(end 3.3 4.6)
			(stroke
				(width 0.05)
				(type solid)
			)
			(fill no)
			(layer "F.CrtYd")
		)
		(fp_line
			(start 2 4.25)
			(end -2 4.25)
			(stroke
				(width 0.15)
				(type solid)
			)
			(layer "F.Fab")
		)
		(fp_line
			(start 2 -4.25)
			(end 2 4.25)
			(stroke
				(width 0.15)
				(type solid)
			)
			(layer "F.Fab")
		)
		(fp_line
			(start -1.25 -4.25)
			(end 2 -4.25)
			(stroke
				(width 0.15)
				(type solid)
			)
			(layer "F.Fab")
		)
		(fp_line
			(start -2 4.25)
			(end -2 -1.5)
			(stroke
				(width 0.15)
				(type solid)
			)
			(layer "F.Fab")
		)
		(fp_line
			(start -2 -1.5)
			(end -2 -3.5)
			(stroke
				(width 0.15)
				(type solid)
			)
			(layer "F.Fab")
		)
		(fp_line
			(start -2 -3.5)
			(end -1.25 -4.25)
			(stroke
				(width 0.15)
				(type solid)
			)
			(layer "F.Fab")
		)
		(pad "1" smd rect
			(at -2.64 -3.49 90)
			(size 0.42 1.12)
			(layers "F.Cu" "F.Mask" "F.Paste")
			(net 372 "/Com Express 7 MGMT/I2C.SDA")
			(pinfunction "SDA")
			(pintype "open_collector")
			(teardrops
				(best_length_ratio 0.2)
				(max_length 1)
				(best_width_ratio 0.9)
				(max_width 2)
				(curved_edges yes)
				(filter_ratio 0.9)
				(enabled yes)
				(allow_two_segments yes)
				(prefer_zone_connections yes)
			)
		)
		(pad "2" smd rect
			(at -2.64 -2.86 90)
			(size 0.42 1.12)
			(layers "F.Cu" "F.Mask" "F.Paste")
			(net 371 "/Com Express 7 MGMT/I2C.SCL")
			(pinfunction "SCL")
			(pintype "open_collector")
			(teardrops
				(best_length_ratio 0.2)
				(max_length 1)
				(best_width_ratio 0.9)
				(max_width 2)
				(curved_edges yes)
				(filter_ratio 0.9)
				(enabled yes)
				(allow_two_segments yes)
				(prefer_zone_connections yes)
			)
		)
		(pad "3" smd rect
			(at -2.64 -2.22 90)
			(size 0.42 1.12)
			(layers "F.Cu" "F.Mask" "F.Paste")
			(net 1 "GND")
			(pinfunction "GND")
			(pintype "power_in")
			(teardrops
				(best_length_ratio 0.2)
				(max_length 1)
				(best_width_ratio 0.9)
				(max_width 2)
				(curved_edges yes)
				(filter_ratio 0.9)
				(enabled yes)
				(allow_two_segments yes)
				(prefer_zone_connections yes)
			)
		)
		(pad "4" smd rect
			(at -2.64 -1.59 90)
			(size 0.42 1.12)
			(layers "F.Cu" "F.Mask" "F.Paste")
			(net 80 "Net-(Q6-D)")
			(pinfunction "VCC")
			(pintype "power_in")
			(teardrops
				(best_length_ratio 0.2)
				(max_length 1)
				(best_width_ratio 0.9)
				(max_width 2)
				(curved_edges yes)
				(filter_ratio 0.9)
				(enabled yes)
				(allow_two_segments yes)
				(prefer_zone_connections yes)
			)
		)
		(pad "5" smd rect
			(at -2.64 -0.95 90)
			(size 0.42 1.12)
			(layers "F.Cu" "F.Mask" "F.Paste")
			(net 706 "Net-(U24-GPIO0)")
			(pinfunction "GPIO0")
			(pintype "open_collector")
			(teardrops
				(best_length_ratio 0.2)
				(max_length 1)
				(best_width_ratio 0.9)
				(max_width 2)
				(curved_edges yes)
				(filter_ratio 0.9)
				(enabled yes)
				(allow_two_segments yes)
				(prefer_zone_connections yes)
			)
		)
		(pad "6" smd rect
			(at -2.64 -0.32 90)
			(size 0.42 1.12)
			(layers "F.Cu" "F.Mask" "F.Paste")
			(net 705 "Net-(U24-GPIO1)")
			(pinfunction "GPIO1")
			(pintype "open_collector")
			(teardrops
				(best_length_ratio 0.2)
				(max_length 1)
				(best_width_ratio 0.9)
				(max_width 2)
				(curved_edges yes)
				(filter_ratio 0.9)
				(enabled yes)
				(allow_two_segments yes)
				(prefer_zone_connections yes)
			)
		)
		(pad "7" smd rect
			(at -2.64 0.32 90)
			(size 0.42 1.12)
			(layers "F.Cu" "F.Mask" "F.Paste")
			(net 704 "Net-(U24-GPIO2)")
			(pinfunction "GPIO2")
			(pintype "open_collector")
			(teardrops
				(best_length_ratio 0.2)
				(max_length 1)
				(best_width_ratio 0.9)
				(max_width 2)
				(curved_edges yes)
				(filter_ratio 0.9)
				(enabled yes)
				(allow_two_segments yes)
				(prefer_zone_connections yes)
			)
		)
		(pad "8" smd rect
			(at -2.64 0.95 90)
			(size 0.42 1.12)
			(layers "F.Cu" "F.Mask" "F.Paste")
			(net 703 "Net-(U24-GPIO3)")
			(pinfunction "GPIO3")
			(pintype "open_collector")
			(teardrops
				(best_length_ratio 0.2)
				(max_length 1)
				(best_width_ratio 0.9)
				(max_width 2)
				(curved_edges yes)
				(filter_ratio 0.9)
				(enabled yes)
				(allow_two_segments yes)
				(prefer_zone_connections yes)
			)
		)
		(pad "9" smd rect
			(at -2.64 1.59 90)
			(size 0.42 1.12)
			(layers "F.Cu" "F.Mask" "F.Paste")
			(net 707 "Net-(U24-TACH3)")
			(pinfunction "TACH3")
			(pintype "input")
			(teardrops
				(best_length_ratio 0.2)
				(max_length 1)
				(best_width_ratio 0.9)
				(max_width 2)
				(curved_edges yes)
				(filter_ratio 0.9)
				(enabled yes)
				(allow_two_segments yes)
				(prefer_zone_connections yes)
			)
		)
		(pad "10" smd rect
			(at -2.64 2.22 90)
			(size 0.42 1.12)
			(layers "F.Cu" "F.Mask" "F.Paste")
			(net 596 "/Misc/PWM2")
			(pinfunction "PWM2")
			(pintype "open_collector")
			(teardrops
				(best_length_ratio 0.2)
				(max_length 1)
				(best_width_ratio 0.9)
				(max_width 2)
				(curved_edges yes)
				(filter_ratio 0.9)
				(enabled yes)
				(allow_two_segments yes)
				(prefer_zone_connections yes)
			)
		)
		(pad "11" smd rect
			(at -2.64 2.86 90)
			(size 0.42 1.12)
			(layers "F.Cu" "F.Mask" "F.Paste")
			(net 780 "/Misc/TACH_{A3V3}")
			(pinfunction "TACH1")
			(pintype "input")
			(teardrops
				(best_length_ratio 0.2)
				(max_length 1)
				(best_width_ratio 0.9)
				(max_width 2)
				(curved_edges yes)
				(filter_ratio 0.9)
				(enabled yes)
				(allow_two_segments yes)
				(prefer_zone_connections yes)
			)
		)
		(pad "12" smd rect
			(at -2.64 3.49 90)
			(size 0.42 1.12)
			(layers "F.Cu" "F.Mask" "F.Paste")
			(net 781 "/Misc/TACH_{B3V3}")
			(pinfunction "TACH2")
			(pintype "input")
			(teardrops
				(best_length_ratio 0.2)
				(max_length 1)
				(best_width_ratio 0.9)
				(max_width 2)
				(curved_edges yes)
				(filter_ratio 0.9)
				(enabled yes)
				(allow_two_segments yes)
				(prefer_zone_connections yes)
			)
		)
		(pad "13" smd rect
			(at 2.64 3.49 90)
			(size 0.42 1.12)
			(layers "F.Cu" "F.Mask" "F.Paste")
			(net 588 "/Misc/~{ADDREN}")
			(pinfunction "PWM3")
			(pintype "input")
			(teardrops
				(best_length_ratio 0.2)
				(max_length 1)
				(best_width_ratio 0.9)
				(max_width 2)
				(curved_edges yes)
				(filter_ratio 0.9)
				(enabled yes)
				(allow_two_segments yes)
				(prefer_zone_connections yes)
			)
		)
		(pad "14" smd rect
			(at 2.64 2.86 90)
			(size 0.42 1.12)
			(layers "F.Cu" "F.Mask" "F.Paste")
			(net 589 "/Misc/~{ADDRSEL}")
			(pinfunction "TACH4")
			(pintype "input")
			(teardrops
				(best_length_ratio 0.2)
				(max_length 1)
				(best_width_ratio 0.9)
				(max_width 2)
				(curved_edges yes)
				(filter_ratio 0.9)
				(enabled yes)
				(allow_two_segments yes)
				(prefer_zone_connections yes)
			)
		)
		(pad "15" smd rect
			(at 2.64 2.22 90)
			(size 0.42 1.12)
			(layers "F.Cu" "F.Mask" "F.Paste")
			(net 542 "Net-(Q9-E)")
			(pinfunction "D2-")
			(pintype "passive")
			(teardrops
				(best_length_ratio 0.2)
				(max_length 1)
				(best_width_ratio 0.9)
				(max_width 2)
				(curved_edges yes)
				(filter_ratio 0.9)
				(enabled yes)
				(allow_two_segments yes)
				(prefer_zone_connections yes)
			)
		)
		(pad "16" smd rect
			(at 2.64 1.59 90)
			(size 0.42 1.12)
			(layers "F.Cu" "F.Mask" "F.Paste")
			(net 541 "Net-(Q9-B)")
			(pinfunction "D2+")
			(pintype "passive")
			(teardrops
				(best_length_ratio 0.2)
				(max_length 1)
				(best_width_ratio 0.9)
				(max_width 2)
				(curved_edges yes)
				(filter_ratio 0.9)
				(enabled yes)
				(allow_two_segments yes)
				(prefer_zone_connections yes)
			)
		)
		(pad "17" smd rect
			(at 2.64 0.95 90)
			(size 0.42 1.12)
			(layers "F.Cu" "F.Mask" "F.Paste")
			(net 544 "Net-(Q10-E)")
			(pinfunction "D1-")
			(pintype "passive")
			(teardrops
				(best_length_ratio 0.2)
				(max_length 1)
				(best_width_ratio 0.9)
				(max_width 2)
				(curved_edges yes)
				(filter_ratio 0.9)
				(enabled yes)
				(allow_two_segments yes)
				(prefer_zone_connections yes)
			)
		)
		(pad "18" smd rect
			(at 2.64 0.32 90)
			(size 0.42 1.12)
			(layers "F.Cu" "F.Mask" "F.Paste")
			(net 543 "Net-(Q10-B)")
			(pinfunction "D1+")
			(pintype "passive")
			(teardrops
				(best_length_ratio 0.2)
				(max_length 1)
				(best_width_ratio 0.9)
				(max_width 2)
				(curved_edges yes)
				(filter_ratio 0.9)
				(enabled yes)
				(allow_two_segments yes)
				(prefer_zone_connections yes)
			)
		)
		(pad "19" smd rect
			(at 2.64 -0.32 90)
			(size 0.42 1.12)
			(layers "F.Cu" "F.Mask" "F.Paste")
			(net 594 "Net-(U24-GPIO4)")
			(pinfunction "GPIO4")
			(pintype "open_collector")
			(teardrops
				(best_length_ratio 0.2)
				(max_length 1)
				(best_width_ratio 0.9)
				(max_width 2)
				(curved_edges yes)
				(filter_ratio 0.9)
				(enabled yes)
				(allow_two_segments yes)
				(prefer_zone_connections yes)
			)
		)
		(pad "20" smd rect
			(at 2.64 -0.95 90)
			(size 0.42 1.12)
			(layers "F.Cu" "F.Mask" "F.Paste")
			(net 592 "Net-(U24-+5V_{IN})")
			(pinfunction "+5V_{IN}")
			(pintype "passive")
			(teardrops
				(best_length_ratio 0.2)
				(max_length 1)
				(best_width_ratio 0.9)
				(max_width 2)
				(curved_edges yes)
				(filter_ratio 0.9)
				(enabled yes)
				(allow_two_segments yes)
				(prefer_zone_connections yes)
			)
		)
		(pad "21" smd rect
			(at 2.64 -1.59 90)
			(size 0.42 1.12)
			(layers "F.Cu" "F.Mask" "F.Paste")
			(net 591 "Net-(U24-+12V_{IN})")
			(pinfunction "+12V_{IN}")
			(pintype "passive")
			(teardrops
				(best_length_ratio 0.2)
				(max_length 1)
				(best_width_ratio 0.9)
				(max_width 2)
				(curved_edges yes)
				(filter_ratio 0.9)
				(enabled yes)
				(allow_two_segments yes)
				(prefer_zone_connections yes)
			)
		)
		(pad "22" smd rect
			(at 2.64 -2.22 90)
			(size 0.42 1.12)
			(layers "F.Cu" "F.Mask" "F.Paste")
			(net 590 "Net-(U24-+2.5V_{IN})")
			(pinfunction "+2.5V_{IN}")
			(pintype "passive")
			(teardrops
				(best_length_ratio 0.2)
				(max_length 1)
				(best_width_ratio 0.9)
				(max_width 2)
				(curved_edges yes)
				(filter_ratio 0.9)
				(enabled yes)
				(allow_two_segments yes)
				(prefer_zone_connections yes)
			)
		)
		(pad "23" smd rect
			(at 2.64 -2.86 90)
			(size 0.42 1.12)
			(layers "F.Cu" "F.Mask" "F.Paste")
			(net 593 "Net-(U24-V_{CCP})")
			(pinfunction "V_{CCP}")
			(pintype "passive")
			(teardrops
				(best_length_ratio 0.2)
				(max_length 1)
				(best_width_ratio 0.9)
				(max_width 2)
				(curved_edges yes)
				(filter_ratio 0.9)
				(enabled yes)
				(allow_two_segments yes)
				(prefer_zone_connections yes)
			)
		)
		(pad "24" smd rect
			(at 2.64 -3.49 90)
			(size 0.42 1.12)
			(layers "F.Cu" "F.Mask" "F.Paste")
			(net 597 "/Misc/PWM1")
			(pinfunction "PWM1")
			(pintype "open_collector")
			(teardrops
				(best_length_ratio 0.2)
				(max_length 1)
				(best_width_ratio 0.9)
				(max_width 2)
				(curved_edges yes)
				(filter_ratio 0.9)
				(enabled yes)
				(allow_two_segments yes)
				(prefer_zone_connections yes)
			)
		)
	)
	(footprint "antmicro-footprints:C_0402_1005Metric"
		(layer "F.Cu")
		(at 115.9 146.301 90)
		(descr "Capacitor SMD 0402")
		(tags "capacitor SMD 0402")
		(property "Reference" "C114"
			(at 10.541 2.1 90)
			(layer "F.SilkS")
			(effects
				(font
					(size 0.7 0.7)
					(thickness 0.15)
				)
				(justify left bottom)
			)
		)
		(property "Value" "C_100n_0402"
			(at -1.022927 2.155213 90)
			(layer "F.Fab")
			(effects
				(font
					(size 0.7 0.7)
					(thickness 0.15)
				)
				(justify left bottom)
			)
		)
		(property "Datasheet" "https://www.murata.com/products/productdetail?partno=GRM155R61H104KE14%23"
			(at 0 0 90)
			(layer "F.Fab")
			(hide yes)
			(effects
				(font
					(size 1.27 1.27)
					(thickness 0.15)
				)
			)
		)
		(property "Author" "Antmicro"
			(at 262.201 30.401 0)
			(layer "F.Fab")
			(hide yes)
			(effects
				(font
					(size 1 1)
					(thickness 0.15)
				)
			)
		)
		(property "Dielectric" "X5R"
			(at 262.201 30.401 0)
			(layer "F.Fab")
			(hide yes)
			(effects
				(font
					(size 1 1)
					(thickness 0.15)
				)
			)
		)
		(property "License" "Apache-2.0"
			(at 262.201 30.401 0)
			(layer "F.Fab")
			(hide yes)
			(effects
				(font
					(size 1 1)
					(thickness 0.15)
				)
			)
		)
		(property "MPN" "GRM155R61H104KE14D"
			(at 262.201 30.401 0)
			(layer "F.Fab")
			(hide yes)
			(effects
				(font
					(size 1 1)
					(thickness 0.15)
				)
			)
		)
		(property "Manufacturer" "Murata"
			(at 262.201 30.401 0)
			(layer "F.Fab")
			(hide yes)
			(effects
				(font
					(size 1 1)
					(thickness 0.15)
				)
			)
		)
		(property "Public" "False"
			(at 262.201 30.401 0)
			(layer "F.Fab")
			(hide yes)
			(effects
				(font
					(size 1 1)
					(thickness 0.15)
				)
			)
		)
		(property "Val" "100n"
			(at 262.201 30.401 0)
			(layer "F.Fab")
			(hide yes)
			(effects
				(font
					(size 1 1)
					(thickness 0.15)
				)
			)
		)
		(property "Voltage" "50V"
			(at 262.201 30.401 0)
			(layer "F.Fab")
			(hide yes)
			(effects
				(font
					(size 1 1)
					(thickness 0.15)
				)
			)
		)
		(sheetname "PCIe redriver")
		(sheetfile "pcie_redriver.kicad_sch")
		(attr smd)
		(fp_rect
			(start -0.925 -0.47)
			(end 0.925 0.47)
			(stroke
				(width 0.05)
				(type default)
			)
			(fill no)
			(layer "F.CrtYd")
		)
		(fp_line
			(start 0.504 -0.25)
			(end 0.504 0.248)
			(stroke
				(width 0.15)
				(type solid)
			)
			(layer "F.Fab")
		)
		(fp_line
			(start -0.494 -0.25)
			(end 0.504 -0.25)
			(stroke
				(width 0.15)
				(type solid)
			)
			(layer "F.Fab")
		)
		(fp_line
			(start 0.504 0.248)
			(end -0.494 0.248)
			(stroke
				(width 0.15)
				(type solid)
			)
			(layer "F.Fab")
		)
		(fp_line
			(start -0.494 0.248)
			(end -0.494 -0.25)
			(stroke
				(width 0.15)
				(type solid)
			)
			(layer "F.Fab")
		)
		(pad "1" smd roundrect
			(at -0.48 0 90)
			(size 0.59 0.64)
			(layers "F.Cu" "F.Mask" "F.Paste")
			(roundrect_rratio 0.25)
			(net 1 "GND")
			(pintype "passive")
			(teardrops
				(best_length_ratio 0.2)
				(max_length 1)
				(best_width_ratio 0.9)
				(max_width 2)
				(curved_edges yes)
				(filter_ratio 0.9)
				(enabled yes)
				(allow_two_segments yes)
				(prefer_zone_connections yes)
			)
		)
		(pad "2" smd roundrect
			(at 0.48 0 90)
			(size 0.59 0.64)
			(layers "F.Cu" "F.Mask" "F.Paste")
			(roundrect_rratio 0.25)
			(net 2 "+3V3")
			(pintype "passive")
			(teardrops
				(best_length_ratio 0.2)
				(max_length 1)
				(best_width_ratio 0.9)
				(max_width 2)
				(curved_edges yes)
				(filter_ratio 0.9)
				(enabled yes)
				(allow_two_segments yes)
				(prefer_zone_connections yes)
			)
		)
	)
	(footprint "antmicro-footprints:TP_SMD_0.75mm"
		(layer "F.Cu")
		(at 183.70861 72.802163 -90)
		(property "Reference" "TP105"
			(at 0 -0.6 90)
			(layer "F.SilkS")
			(hide yes)
			(effects
				(font
					(size 0.7 0.7)
					(thickness 0.15)
				)
				(justify right bottom)
			)
		)
		(property "Value" "TP_0.75mm_SMD"
			(at 0 1.2 90)
			(layer "F.Fab")
			(effects
				(font
					(size 0.7 0.7)
					(thickness 0.15)
				)
				(justify right bottom)
			)
		)
		(property "Author" "Antmicro"
			(at 110.906447 256.510773 0)
			(layer "F.Fab")
			(hide yes)
			(effects
				(font
					(size 1 1)
					(thickness 0.15)
				)
			)
		)
		(property "License" "Apache-2.0"
			(at 110.906447 256.510773 0)
			(layer "F.Fab")
			(hide yes)
			(effects
				(font
					(size 1 1)
					(thickness 0.15)
				)
			)
		)
		(property "MPN" ""
			(at 110.906447 256.510773 0)
			(layer "F.Fab")
			(hide yes)
			(effects
				(font
					(size 1 1)
					(thickness 0.15)
				)
			)
		)
		(property "Manufacturer" ""
			(at 110.906447 256.510773 0)
			(layer "F.Fab")
			(hide yes)
			(effects
				(font
					(size 1 1)
					(thickness 0.15)
				)
			)
		)
		(property "Public" "False"
			(at 110.906447 256.510773 0)
			(layer "F.Fab")
			(hide yes)
			(effects
				(font
					(size 1 1)
					(thickness 0.15)
				)
			)
		)
		(sheetname "Power")
		(sheetfile "power.kicad_sch")
		(attr exclude_from_pos_files exclude_from_bom)
		(fp_circle
			(center 0 0)
			(end 0.475 0)
			(stroke
				(width 0.05)
				(type default)
			)
			(fill no)
			(layer "F.CrtYd")
		)
		(pad "1" smd circle
			(at 0 0 270)
			(size 0.75 0.75)
			(layers "F.Cu" "F.Mask")
			(net 1 "GND")
			(pinfunction "1")
			(pintype "passive")
			(teardrops
				(best_length_ratio 0.4)
				(max_length 1)
				(best_width_ratio 0.9)
				(max_width 2)
				(curved_edges yes)
				(filter_ratio 0.9)
				(enabled yes)
				(allow_two_segments yes)
				(prefer_zone_connections yes)
			)
		)
	)
	(footprint "antmicro-footprints:R_0201"
		(layer "F.Cu")
		(at 132.17 147.961 -90)
		(descr "Resistor SMD 0201")
		(tags "resistor SMD 0201")
		(property "Reference" "R310"
			(at 3.6 -0.58 90)
			(layer "F.SilkS")
			(effects
				(font
					(size 0.7 0.7)
					(thickness 0.15)
				)
				(justify right bottom)
			)
		)
		(property "Value" "R_0R_0201"
			(at 0 1.25 90)
			(layer "F.Fab")
			(effects
				(font
					(size 0.7 0.7)
					(thickness 0.15)
				)
				(justify right bottom)
			)
		)
		(property "Datasheet" "https://www.bourns.com/docs/product-datasheets/cr.pdf"
			(at 0 0 270)
			(layer "F.Fab")
			(hide yes)
			(effects
				(font
					(size 1.27 1.27)
					(thickness 0.15)
				)
			)
		)
		(property "Author" "Antmicro"
			(at -15.791 280.131 0)
			(layer "F.Fab")
			(hide yes)
			(effects
				(font
					(size 1 1)
					(thickness 0.15)
				)
			)
		)
		(property "License" "Apache-2.0"
			(at -15.791 280.131 0)
			(layer "F.Fab")
			(hide yes)
			(effects
				(font
					(size 1 1)
					(thickness 0.15)
				)
			)
		)
		(property "MPN" "CR0201-FX-0R00GLF"
			(at -15.791 280.131 0)
			(layer "F.Fab")
			(hide yes)
			(effects
				(font
					(size 1 1)
					(thickness 0.15)
				)
			)
		)
		(property "Manufacturer" "Bourns"
			(at -15.791 280.131 0)
			(layer "F.Fab")
			(hide yes)
			(effects
				(font
					(size 1 1)
					(thickness 0.15)
				)
			)
		)
		(property "Tolerance" "1%"
			(at -15.791 280.131 0)
			(layer "F.Fab")
			(hide yes)
			(effects
				(font
					(size 1 1)
					(thickness 0.15)
				)
			)
		)
		(property "Val" "0R"
			(at -15.791 280.131 0)
			(layer "F.Fab")
			(hide yes)
			(effects
				(font
					(size 1 1)
					(thickness 0.15)
				)
			)
		)
		(sheetname "KR to SFI #2")
		(sheetfile "kr_sfi.kicad_sch")
		(attr smd dnp)
		(fp_rect
			(start -0.7 -0.35)
			(end 0.7 0.35)
			(stroke
				(width 0.05)
				(type default)
			)
			(fill no)
			(layer "F.CrtYd")
		)
		(fp_rect
			(start -0.3 -0.15)
			(end 0.298 0.148)
			(stroke
				(width 0.15)
				(type solid)
			)
			(fill no)
			(layer "F.Fab")
		)
		(pad "" smd roundrect
			(at -0.346 0 270)
			(size 0.318 0.36)
			(layers "F.Paste")
			(roundrect_rratio 0.25)
			(teardrops
				(best_length_ratio 0.2)
				(max_length 1)
				(best_width_ratio 0.9)
				(max_width 2)
				(curved_edges yes)
				(filter_ratio 0.9)
				(enabled yes)
				(allow_two_segments yes)
				(prefer_zone_connections yes)
			)
		)
		(pad "" smd roundrect
			(at 0.344 0 270)
			(size 0.318 0.36)
			(layers "F.Paste")
			(roundrect_rratio 0.25)
			(teardrops
				(best_length_ratio 0.2)
				(max_length 1)
				(best_width_ratio 0.9)
				(max_width 2)
				(curved_edges yes)
				(filter_ratio 0.9)
				(enabled yes)
				(allow_two_segments yes)
				(prefer_zone_connections yes)
			)
		)
		(pad "1" smd roundrect
			(at -0.32 0 270)
			(size 0.46 0.4)
			(layers "F.Cu" "F.Mask")
			(roundrect_rratio 0.25)
			(net 877 "/2xSFP+/SFI1.RX-")
			(pintype "passive")
			(teardrops
				(best_length_ratio 0.2)
				(max_length 1)
				(best_width_ratio 0.9)
				(max_width 2)
				(curved_edges yes)
				(filter_ratio 0.9)
				(enabled yes)
				(allow_two_segments yes)
				(prefer_zone_connections yes)
			)
		)
		(pad "2" smd roundrect
			(at 0.32 0 270)
			(size 0.46 0.4)
			(layers "F.Cu" "F.Mask")
			(roundrect_rratio 0.25)
			(net 968 "/2xSFP+/KR to SFI #2/BYP_RX-")
			(pintype "passive")
			(teardrops
				(best_length_ratio 0.2)
				(max_length 1)
				(best_width_ratio 0.9)
				(max_width 2)
				(curved_edges yes)
				(filter_ratio 0.9)
				(enabled yes)
				(allow_two_segments yes)
				(prefer_zone_connections yes)
			)
		)
	)
	(footprint "antmicro-footprints:SOT-23-3"
		(layer "F.Cu")
		(at 304.975 138.76)
		(property "Reference" "Q1"
			(at 1.875 1.75 90)
			(layer "F.SilkS")
			(effects
				(font
					(size 0.7 0.7)
					(thickness 0.15)
				)
				(justify left bottom)
			)
		)
		(property "Value" "BSS138-7-F"
			(at -1.9 2.7 0)
			(layer "F.Fab")
			(effects
				(font
					(size 0.7 0.7)
					(thickness 0.15)
				)
				(justify left bottom)
			)
		)
		(property "Datasheet" "https://www.diodes.com/assets/Datasheets/ds30144.pdf"
			(at 0 0 0)
			(layer "F.Fab")
			(hide yes)
			(effects
				(font
					(size 1.27 1.27)
					(thickness 0.15)
				)
			)
		)
		(property "Author" "Antmicro"
			(at 0 0 0)
			(layer "F.Fab")
			(hide yes)
			(effects
				(font
					(size 1 1)
					(thickness 0.15)
				)
			)
		)
		(property "License" "Apache-2.0"
			(at 0 0 0)
			(layer "F.Fab")
			(hide yes)
			(effects
				(font
					(size 1 1)
					(thickness 0.15)
				)
			)
		)
		(property "MPN" "BSS138-7-F"
			(at 0 0 0)
			(layer "F.Fab")
			(hide yes)
			(effects
				(font
					(size 1 1)
					(thickness 0.15)
				)
			)
		)
		(property "Manufacturer" "Diodes Incorporated"
			(at 0 0 0)
			(layer "F.Fab")
			(hide yes)
			(effects
				(font
					(size 1 1)
					(thickness 0.15)
				)
			)
		)
		(sheetname "Power")
		(sheetfile "power.kicad_sch")
		(attr smd)
		(fp_line
			(start -1.45 -1.35)
			(end -0.85 -1.35)
			(stroke
				(width 0.15)
				(type solid)
			)
			(layer "F.SilkS")
		)
		(fp_line
			(start -0.85 -1.35)
			(end -0.7 -1.5)
			(stroke
				(width 0.15)
				(type solid)
			)
			(layer "F.SilkS")
		)
		(fp_line
			(start -0.7 1.5)
			(end -0.7 1.35)
			(stroke
				(width 0.15)
				(type solid)
			)
			(layer "F.SilkS")
		)
		(fp_line
			(start 0.7 -1.5)
			(end -0.7 -1.5)
			(stroke
				(width 0.15)
				(type solid)
			)
			(layer "F.SilkS")
		)
		(fp_line
			(start 0.7 -0.4)
			(end 0.7 -1.5)
			(stroke
				(width 0.15)
				(type solid)
			)
			(layer "F.SilkS")
		)
		(fp_line
			(start 0.7 0.4)
			(end 0.7 1.5)
			(stroke
				(width 0.15)
				(type solid)
			)
			(layer "F.SilkS")
		)
		(fp_line
			(start 0.7 1.5)
			(end -0.7 1.5)
			(stroke
				(width 0.15)
				(type solid)
			)
			(layer "F.SilkS")
		)
		(fp_line
			(start -1.75 -0.5)
			(end -1.75 -1.4)
			(stroke
				(width 0.05)
				(type solid)
			)
			(layer "F.CrtYd")
		)
		(fp_line
			(start -1.75 0.5)
			(end -0.85 0.5)
			(stroke
				(width 0.05)
				(type solid)
			)
			(layer "F.CrtYd")
		)
		(fp_line
			(start -1.75 1.4)
			(end -1.75 0.5)
			(stroke
				(width 0.05)
				(type solid)
			)
			(layer "F.CrtYd")
		)
		(fp_line
			(start -0.9 -1.6)
			(end -0.9 -1.4)
			(stroke
				(width 0.05)
				(type solid)
			)
			(layer "F.CrtYd")
		)
		(fp_line
			(start -0.9 -1.6)
			(end 0.825 -1.6)
			(stroke
				(width 0.05)
				(type solid)
			)
			(layer "F.CrtYd")
		)
		(fp_line
			(start -0.9 -1.4)
			(end -1.75 -1.4)
			(stroke
				(width 0.05)
				(type solid)
			)
			(layer "F.CrtYd")
		)
		(fp_line
			(start -0.85 -0.5)
			(end -1.75 -0.5)
			(stroke
				(width 0.05)
				(type solid)
			)
			(layer "F.CrtYd")
		)
		(fp_line
			(start -0.85 0.5)
			(end -0.85 -0.5)
			(stroke
				(width 0.05)
				(type solid)
			)
			(layer "F.CrtYd")
		)
		(fp_line
			(start -0.85 1.4)
			(end -1.75 1.4)
			(stroke
				(width 0.05)
				(type solid)
			)
			(layer "F.CrtYd")
		)
		(fp_line
			(start -0.85 1.65)
			(end -0.85 1.4)
			(stroke
				(width 0.05)
				(type solid)
			)
			(layer "F.CrtYd")
		)
		(fp_line
			(start 0.825 -1.6)
			(end 0.825 -0.45)
			(stroke
				(width 0.05)
				(type solid)
			)
			(layer "F.CrtYd")
		)
		(fp_line
			(start 0.825 -0.45)
			(end 1.75 -0.45)
			(stroke
				(width 0.05)
				(type solid)
			)
			(layer "F.CrtYd")
		)
		(fp_line
			(start 0.85 0.45)
			(end 0.85 1.65)
			(stroke
				(width 0.05)
				(type solid)
			)
			(layer "F.CrtYd")
		)
		(fp_line
			(start 0.85 1.65)
			(end -0.85 1.65)
			(stroke
				(width 0.05)
				(type solid)
			)
			(layer "F.CrtYd")
		)
		(fp_line
			(start 1.75 -0.45)
			(end 1.75 0.45)
			(stroke
				(width 0.05)
				(type solid)
			)
			(layer "F.CrtYd")
		)
		(fp_line
			(start 1.75 0.45)
			(end 0.85 0.45)
			(stroke
				(width 0.05)
				(type solid)
			)
			(layer "F.CrtYd")
		)
		(fp_line
			(start -0.712 -1.325)
			(end -0.712 1.523)
			(stroke
				(width 0.15)
				(type solid)
			)
			(layer "F.Fab")
		)
		(fp_line
			(start -0.712 1.519)
			(end 0.688 1.519)
			(stroke
				(width 0.15)
				(type solid)
			)
			(layer "F.Fab")
		)
		(fp_line
			(start -0.437 -1.526)
			(end -0.712 -1.325)
			(stroke
				(width 0.15)
				(type solid)
			)
			(layer "F.Fab")
		)
		(fp_line
			(start -0.437 -1.526)
			(end 0.688 -1.526)
			(stroke
				(width 0.15)
				(type solid)
			)
			(layer "F.Fab")
		)
		(fp_line
			(start 0.688 1.519)
			(end 0.688 -1.52)
			(stroke
				(width 0.15)
				(type solid)
			)
			(layer "F.Fab")
		)
		(pad "1" smd roundrect
			(at -1.1 -0.951)
			(size 1 0.6)
			(layers "F.Cu" "F.Mask" "F.Paste")
			(roundrect_rratio 0.15)
			(net 533 "/Com Express 7 MGMT/PSON")
			(pinfunction "G")
			(pintype "bidirectional")
			(teardrops
				(best_length_ratio 0.2)
				(max_length 1)
				(best_width_ratio 0.9)
				(max_width 2)
				(curved_edges yes)
				(filter_ratio 0.9)
				(enabled yes)
				(allow_two_segments yes)
				(prefer_zone_connections yes)
			)
		)
		(pad "2" smd roundrect
			(at -1.1 0.949)
			(size 1 0.6)
			(layers "F.Cu" "F.Mask" "F.Paste")
			(roundrect_rratio 0.15)
			(net 1 "GND")
			(pinfunction "S")
			(pintype "bidirectional")
			(teardrops
				(best_length_ratio 0.2)
				(max_length 1)
				(best_width_ratio 0.9)
				(max_width 2)
				(curved_edges yes)
				(filter_ratio 0.9)
				(enabled yes)
				(allow_two_segments yes)
				(prefer_zone_connections yes)
			)
		)
		(pad "3" smd roundrect
			(at 1.1 -0.0005)
			(size 1 0.6)
			(layers "F.Cu" "F.Mask" "F.Paste")
			(roundrect_rratio 0.15)
			(net 534 "Net-(Q1-D)")
			(pinfunction "D")
			(pintype "bidirectional")
			(teardrops
				(best_length_ratio 0.2)
				(max_length 1)
				(best_width_ratio 0.9)
				(max_width 2)
				(curved_edges yes)
				(filter_ratio 0.9)
				(enabled yes)
				(allow_two_segments yes)
				(prefer_zone_connections yes)
			)
		)
	)
	(footprint "antmicro-footprints:TSSOP-8_3x3mm_P0.65mm"
		(layer "F.Cu")
		(at 142.877 149.258 -90)
		(property "Reference" "U42"
			(at -1.248 1.827 90)
			(layer "F.SilkS")
			(effects
				(font
					(size 0.7 0.7)
					(thickness 0.15)
				)
				(justify right bottom)
			)
		)
		(property "Value" "NTS0102_TSSOP"
			(at 0 2.8 90)
			(layer "F.Fab")
			(effects
				(font
					(size 0.7 0.7)
					(thickness 0.15)
				)
				(justify right bottom)
			)
		)
		(property "Datasheet" "https://www.mouser.com/datasheet/2/302/NTS0102-1127324.pdf"
			(at 0 0 270)
			(layer "F.Fab")
			(hide yes)
			(effects
				(font
					(size 1.27 1.27)
					(thickness 0.15)
				)
			)
		)
		(property "Author" "Antmicro"
			(at -6.381 292.135 0)
			(layer "F.Fab")
			(hide yes)
			(effects
				(font
					(size 1 1)
					(thickness 0.15)
				)
			)
		)
		(property "License" "Apache-2.0"
			(at -6.381 292.135 0)
			(layer "F.Fab")
			(hide yes)
			(effects
				(font
					(size 1 1)
					(thickness 0.15)
				)
			)
		)
		(property "MPN" "NTS0102DP"
			(at -6.381 292.135 0)
			(layer "F.Fab")
			(hide yes)
			(effects
				(font
					(size 1 1)
					(thickness 0.15)
				)
			)
		)
		(property "Manufacturer" "NXP"
			(at -6.381 292.135 0)
			(layer "F.Fab")
			(hide yes)
			(effects
				(font
					(size 1 1)
					(thickness 0.15)
				)
			)
		)
		(sheetname "KR to SFI #1")
		(sheetfile "kr_sfi.kicad_sch")
		(attr smd)
		(fp_line
			(start -1.55 1.561)
			(end 1.552 1.561)
			(stroke
				(width 0.15)
				(type solid)
			)
			(layer "F.SilkS")
		)
		(fp_line
			(start -1.525 -1.537)
			(end 1.552 -1.539)
			(stroke
				(width 0.15)
				(type solid)
			)
			(layer "F.SilkS")
		)
		(fp_circle
			(center -1.87 -1.4)
			(end -1.82 -1.4)
			(stroke
				(width 0.15)
				(type solid)
			)
			(fill yes)
			(layer "F.SilkS")
		)
		(fp_rect
			(start -3.15 -1.789)
			(end 3.15 1.811)
			(stroke
				(width 0.05)
				(type solid)
			)
			(fill no)
			(layer "F.CrtYd")
		)
		(fp_line
			(start -1.55 1.561)
			(end 1.552 1.561)
			(stroke
				(width 0.15)
				(type solid)
			)
			(layer "F.Fab")
		)
		(fp_line
			(start -1.55 -0.937)
			(end -1.55 1.561)
			(stroke
				(width 0.15)
				(type solid)
			)
			(layer "F.Fab")
		)
		(fp_line
			(start -1.55 -0.937)
			(end -0.949 -1.539)
			(stroke
				(width 0.15)
				(type solid)
			)
			(layer "F.Fab")
		)
		(fp_line
			(start -0.949 -1.539)
			(end 1.552 -1.539)
			(stroke
				(width 0.15)
				(type solid)
			)
			(layer "F.Fab")
		)
		(fp_line
			(start 1.552 -1.539)
			(end 1.552 1.561)
			(stroke
				(width 0.15)
				(type solid)
			)
			(layer "F.Fab")
		)
		(pad "1" smd roundrect
			(at -2.148 -0.962 270)
			(size 1.47 0.4)
			(layers "F.Cu" "F.Mask" "F.Paste")
			(roundrect_rratio 0.25)
			(net 430 "/2xSFP+/MDIO0.MDC")
			(pinfunction "B_{2}")
			(pintype "bidirectional")
			(teardrops
				(best_length_ratio 0.2)
				(max_length 1)
				(best_width_ratio 0.9)
				(max_width 2)
				(curved_edges yes)
				(filter_ratio 0.9)
				(enabled yes)
				(allow_two_segments yes)
				(prefer_zone_connections yes)
			)
		)
		(pad "2" smd roundrect
			(at -2.148 -0.313 270)
			(size 1.47 0.4)
			(layers "F.Cu" "F.Mask" "F.Paste")
			(roundrect_rratio 0.25)
			(net 1 "GND")
			(pinfunction "GND")
			(pintype "power_in")
			(teardrops
				(best_length_ratio 0.2)
				(max_length 1)
				(best_width_ratio 0.9)
				(max_width 2)
				(curved_edges yes)
				(filter_ratio 0.9)
				(enabled yes)
				(allow_two_segments yes)
				(prefer_zone_connections yes)
			)
		)
		(pad "3" smd roundrect
			(at -2.148 0.338 270)
			(size 1.47 0.4)
			(layers "F.Cu" "F.Mask" "F.Paste")
			(roundrect_rratio 0.25)
			(net 78 "+1V8")
			(pinfunction "VCC_{A}")
			(pintype "power_in")
			(teardrops
				(best_length_ratio 0.2)
				(max_length 1)
				(best_width_ratio 0.9)
				(max_width 2)
				(curved_edges yes)
				(filter_ratio 0.9)
				(enabled yes)
				(allow_two_segments yes)
				(prefer_zone_connections yes)
			)
		)
		(pad "4" smd roundrect
			(at -2.148 0.987 270)
			(size 1.47 0.4)
			(layers "F.Cu" "F.Mask" "F.Paste")
			(roundrect_rratio 0.25)
			(net 650 "/2xSFP+/KR to SFI #1/MDC_R")
			(pinfunction "A_{2}")
			(pintype "bidirectional")
			(teardrops
				(best_length_ratio 0.2)
				(max_length 1)
				(best_width_ratio 0.9)
				(max_width 2)
				(curved_edges yes)
				(filter_ratio 0.9)
				(enabled yes)
				(allow_two_segments yes)
				(prefer_zone_connections yes)
			)
		)
		(pad "5" smd roundrect
			(at 2.151 0.987 270)
			(size 1.47 0.4)
			(layers "F.Cu" "F.Mask" "F.Paste")
			(roundrect_rratio 0.25)
			(net 648 "/2xSFP+/KR to SFI #1/MDIO_R")
			(pinfunction "A_{1}")
			(pintype "bidirectional")
			(teardrops
				(best_length_ratio 0.2)
				(max_length 1)
				(best_width_ratio 0.9)
				(max_width 2)
				(curved_edges yes)
				(filter_ratio 0.9)
				(enabled yes)
				(allow_two_segments yes)
				(prefer_zone_connections yes)
			)
		)
		(pad "6" smd roundrect
			(at 2.151 0.338 270)
			(size 1.47 0.4)
			(layers "F.Cu" "F.Mask" "F.Paste")
			(roundrect_rratio 0.25)
			(net 78 "+1V8")
			(pinfunction "OE")
			(pintype "input")
			(teardrops
				(best_length_ratio 0.2)
				(max_length 1)
				(best_width_ratio 0.9)
				(max_width 2)
				(curved_edges yes)
				(filter_ratio 0.9)
				(enabled yes)
				(allow_two_segments yes)
				(prefer_zone_connections yes)
			)
		)
		(pad "7" smd roundrect
			(at 2.151 -0.313 270)
			(size 1.47 0.4)
			(layers "F.Cu" "F.Mask" "F.Paste")
			(roundrect_rratio 0.25)
			(net 2 "+3V3")
			(pinfunction "VCC_{B}")
			(pintype "power_in")
			(teardrops
				(best_length_ratio 0.2)
				(max_length 1)
				(best_width_ratio 0.9)
				(max_width 2)
				(curved_edges yes)
				(filter_ratio 0.9)
				(enabled yes)
				(allow_two_segments yes)
				(prefer_zone_connections yes)
			)
		)
		(pad "8" smd roundrect
			(at 2.151 -0.962 270)
			(size 1.47 0.4)
			(layers "F.Cu" "F.Mask" "F.Paste")
			(roundrect_rratio 0.25)
			(net 491 "/2xSFP+/MDIO0.MDIO")
			(pinfunction "B_{1}")
			(pintype "bidirectional")
			(teardrops
				(best_length_ratio 0.2)
				(max_length 1)
				(best_width_ratio 0.9)
				(max_width 2)
				(curved_edges yes)
				(filter_ratio 0.9)
				(enabled yes)
				(allow_two_segments yes)
				(prefer_zone_connections yes)
			)
		)
	)
	(footprint "antmicro-footprints:LED_0603_1608Metric_Y"
		(layer "F.Cu")
		(at 146.49 156.17 180)
		(descr "LED SMD 0603 Yellow")
		(tags "LED SMD 0603 Yellow")
		(property "Reference" "D4"
			(at 2.69 -0.44 180)
			(layer "F.SilkS")
			(effects
				(font
					(size 0.7 0.7)
					(thickness 0.15)
				)
				(justify left bottom)
			)
		)
		(property "Value" "LED_Y_0603_LTST-C191KSKT"
			(at 0 1.6 180)
			(layer "F.Fab")
			(effects
				(font
					(size 0.7 0.7)
					(thickness 0.15)
				)
				(justify left bottom)
			)
		)
		(property "Datasheet" "https://optoelectronics.liteon.com/upload/download/DS22-2000-224/LTST-C191KSKT.PDF"
			(at 0 0 180)
			(layer "F.Fab")
			(hide yes)
			(effects
				(font
					(size 1.27 1.27)
					(thickness 0.15)
				)
			)
		)
		(property "Author" "Antmicro"
			(at 292.98 312.34 0)
			(layer "F.Fab")
			(hide yes)
			(effects
				(font
					(size 1 1)
					(thickness 0.15)
				)
			)
		)
		(property "Color" "Yellow"
			(at 292.98 312.34 0)
			(layer "F.Fab")
			(hide yes)
			(effects
				(font
					(size 1 1)
					(thickness 0.15)
				)
			)
		)
		(property "License" "Apache-2.0"
			(at 292.98 312.34 0)
			(layer "F.Fab")
			(hide yes)
			(effects
				(font
					(size 1 1)
					(thickness 0.15)
				)
			)
		)
		(property "MPN" "LTST-C191KSKT"
			(at 292.98 312.34 0)
			(layer "F.Fab")
			(hide yes)
			(effects
				(font
					(size 1 1)
					(thickness 0.15)
				)
			)
		)
		(property "Manufacturer" "Lite-On"
			(at 292.98 312.34 0)
			(layer "F.Fab")
			(hide yes)
			(effects
				(font
					(size 1 1)
					(thickness 0.15)
				)
			)
		)
		(sheetname "2xSFP+")
		(sheetfile "2xSFP+.kicad_sch")
		(attr smd)
		(fp_line
			(start 0.22 0.35)
			(end -0.22 0.35)
			(stroke
				(width 0.15)
				(type solid)
			)
			(layer "F.SilkS")
		)
		(fp_line
			(start 0.22 -0.35)
			(end -0.22 -0.35)
			(stroke
				(width 0.15)
				(type solid)
			)
			(layer "F.SilkS")
		)
		(fp_line
			(start 0.105328 0.201008)
			(end 0.105328 -0.198992)
			(stroke
				(width 0.1)
				(type solid)
			)
			(layer "F.SilkS")
		)
		(fp_line
			(start 0.105328 0.201008)
			(end -0.094672 0.001008)
			(stroke
				(width 0.1)
				(type solid)
			)
			(layer "F.SilkS")
		)
		(fp_line
			(start 0.105328 0.001008)
			(end 0.24 0.001)
			(stroke
				(width 0.1)
				(type solid)
			)
			(layer "F.SilkS")
		)
		(fp_line
			(start -0.094672 0.201008)
			(end -0.094672 -0.198992)
			(stroke
				(width 0.1)
				(type solid)
			)
			(layer "F.SilkS")
		)
		(fp_line
			(start -0.094672 0.001008)
			(end 0.105328 -0.198992)
			(stroke
				(width 0.1)
				(type solid)
			)
			(layer "F.SilkS")
		)
		(fp_line
			(start -0.094672 0.001008)
			(end -0.24 0.001008)
			(stroke
				(width 0.1)
				(type solid)
			)
			(layer "F.SilkS")
		)
		(fp_line
			(start -1.18 -0.319)
			(end -1.18 0.321)
			(stroke
				(width 0.15)
				(type solid)
			)
			(layer "F.SilkS")
		)
		(fp_rect
			(start 1.25 0.65)
			(end -1.25 -0.65)
			(stroke
				(width 0.05)
				(type solid)
			)
			(fill no)
			(layer "F.CrtYd")
		)
		(fp_line
			(start 0.599 0)
			(end 0.201 0)
			(stroke
				(width 0.15)
				(type solid)
			)
			(layer "F.Fab")
		)
		(fp_line
			(start 0.201 0.2)
			(end 0.201 0)
			(stroke
				(width 0.15)
				(type solid)
			)
			(layer "F.Fab")
		)
		(fp_line
			(start 0.201 0)
			(end 0.201 -0.202)
			(stroke
				(width 0.15)
				(type solid)
			)
			(layer "F.Fab")
		)
		(fp_line
			(start 0.201 -0.202)
			(end -0.101 0)
			(stroke
				(width 0.15)
				(type solid)
			)
			(layer "F.Fab")
		)
		(fp_line
			(start -0.101 0)
			(end 0.201 0.2)
			(stroke
				(width 0.15)
				(type solid)
			)
			(layer "F.Fab")
		)
		(fp_line
			(start -0.199 0.2)
			(end -0.199 0.1)
			(stroke
				(width 0.15)
				(type solid)
			)
			(layer "F.Fab")
		)
		(fp_line
			(start -0.199 0)
			(end -0.597 0)
			(stroke
				(width 0.15)
				(type solid)
			)
			(layer "F.Fab")
		)
		(fp_line
			(start -0.199 -0.202)
			(end -0.199 0.1)
			(stroke
				(width 0.15)
				(type solid)
			)
			(layer "F.Fab")
		)
		(fp_rect
			(start 0.848 0.4)
			(end -0.85 -0.402)
			(stroke
				(width 0.15)
				(type solid)
			)
			(fill no)
			(layer "F.Fab")
		)
		(pad "1" smd roundrect
			(at -0.7 0)
			(size 0.8 1)
			(layers "F.Cu" "F.Mask" "F.Paste")
			(roundrect_rratio 0.2)
			(net 899 "Net-(D4-C)")
			(pinfunction "C")
			(pintype "passive")
			(teardrops
				(best_length_ratio 0.2)
				(max_length 1)
				(best_width_ratio 0.9)
				(max_width 2)
				(curved_edges yes)
				(filter_ratio 0.9)
				(enabled yes)
				(allow_two_segments yes)
				(prefer_zone_connections yes)
			)
		)
		(pad "2" smd roundrect
			(at 0.7 0)
			(size 0.8 1)
			(layers "F.Cu" "F.Mask" "F.Paste")
			(roundrect_rratio 0.2)
			(net 2 "+3V3")
			(pinfunction "A")
			(pintype "passive")
			(teardrops
				(best_length_ratio 0.2)
				(max_length 1)
				(best_width_ratio 0.9)
				(max_width 2)
				(curved_edges yes)
				(filter_ratio 0.9)
				(enabled yes)
				(allow_two_segments yes)
				(prefer_zone_connections yes)
			)
		)
	)
	(footprint "antmicro-footprints:R_0402_1005Metric"
		(layer "F.Cu")
		(at 252.615 83.174999 180)
		(descr "Resistor SMD 0402")
		(tags "resistor SMD 0402")
		(property "Reference" "R145"
			(at 0.825 -0.435001 0)
			(layer "F.SilkS")
			(effects
				(font
					(size 0.7 0.7)
					(thickness 0.15)
				)
				(justify right bottom)
			)
		)
		(property "Value" "R_10k_0402"
			(at -1.011843 1.772047 0)
			(layer "F.Fab")
			(effects
				(font
					(size 0.7 0.7)
					(thickness 0.15)
				)
				(justify right bottom)
			)
		)
		(property "Datasheet" "https://www.bourns.com/docs/product-datasheets/cr.pdf"
			(at 0 0 180)
			(layer "F.Fab")
			(hide yes)
			(effects
				(font
					(size 1.27 1.27)
					(thickness 0.15)
				)
			)
		)
		(property "Author" "Antmicro"
			(at 505.23 166.349998 0)
			(layer "F.Fab")
			(hide yes)
			(effects
				(font
					(size 1 1)
					(thickness 0.15)
				)
			)
		)
		(property "License" "Apache-2.0"
			(at 505.23 166.349998 0)
			(layer "F.Fab")
			(hide yes)
			(effects
				(font
					(size 1 1)
					(thickness 0.15)
				)
			)
		)
		(property "MPN" "CR0402-FX-1002GLF"
			(at 505.23 166.349998 0)
			(layer "F.Fab")
			(hide yes)
			(effects
				(font
					(size 1 1)
					(thickness 0.15)
				)
			)
		)
		(property "Manufacturer" "Bourns"
			(at 505.23 166.349998 0)
			(layer "F.Fab")
			(hide yes)
			(effects
				(font
					(size 1 1)
					(thickness 0.15)
				)
			)
		)
		(property "Public" "False"
			(at 505.23 166.349998 0)
			(layer "F.Fab")
			(hide yes)
			(effects
				(font
					(size 1 1)
					(thickness 0.15)
				)
			)
		)
		(property "Tolerance" "1%"
			(at 505.23 166.349998 0)
			(layer "F.Fab")
			(hide yes)
			(effects
				(font
					(size 1 1)
					(thickness 0.15)
				)
			)
		)
		(property "Val" "10k"
			(at 505.23 166.349998 0)
			(layer "F.Fab")
			(hide yes)
			(effects
				(font
					(size 1 1)
					(thickness 0.15)
				)
			)
		)
		(sheetname "Misc")
		(sheetfile "misc.kicad_sch")
		(attr smd)
		(fp_rect
			(start -0.925 -0.47)
			(end 0.925 0.47)
			(stroke
				(width 0.05)
				(type default)
			)
			(fill no)
			(layer "F.CrtYd")
		)
		(fp_rect
			(start -0.5 -0.25)
			(end 0.5 0.25)
			(stroke
				(width 0.15)
				(type solid)
			)
			(fill no)
			(layer "F.Fab")
		)
		(pad "1" smd roundrect
			(at -0.48 0 180)
			(size 0.59 0.64)
			(layers "F.Cu" "F.Mask" "F.Paste")
			(roundrect_rratio 0.25)
			(net 589 "/Misc/~{ADDRSEL}")
			(pintype "passive")
			(teardrops
				(best_length_ratio 0.2)
				(max_length 1)
				(best_width_ratio 0.9)
				(max_width 2)
				(curved_edges yes)
				(filter_ratio 0.9)
				(enabled yes)
				(allow_two_segments yes)
				(prefer_zone_connections yes)
			)
		)
		(pad "2" smd roundrect
			(at 0.48 0 180)
			(size 0.59 0.64)
			(layers "F.Cu" "F.Mask" "F.Paste")
			(roundrect_rratio 0.25)
			(net 2 "+3V3")
			(pintype "passive")
			(teardrops
				(best_length_ratio 0.2)
				(max_length 1)
				(best_width_ratio 0.9)
				(max_width 2)
				(curved_edges yes)
				(filter_ratio 0.9)
				(enabled yes)
				(allow_two_segments yes)
				(prefer_zone_connections yes)
			)
		)
	)
	(footprint "antmicro-footprints:R_0402_1005Metric"
		(layer "F.Cu")
		(at 219.432501 133.1 90)
		(descr "Resistor SMD 0402")
		(tags "resistor SMD 0402")
		(property "Reference" "R316"
			(at -1.31 2.317499 90)
			(layer "F.SilkS")
			(effects
				(font
					(size 0.7 0.7)
					(thickness 0.15)
				)
				(justify left bottom)
			)
		)
		(property "Value" "R_0R_0402"
			(at -1.011843 1.772047 90)
			(layer "F.Fab")
			(effects
				(font
					(size 0.7 0.7)
					(thickness 0.15)
				)
				(justify left bottom)
			)
		)
		(property "Datasheet" "https://industrial.panasonic.com/cdbs/www-data/pdf/RDA0000/AOA0000C301.pdf"
			(at 0 0 90)
			(layer "F.Fab")
			(hide yes)
			(effects
				(font
					(size 1.27 1.27)
					(thickness 0.15)
				)
			)
		)
		(property "Author" "Antmicro"
			(at 352.532501 -86.332501 0)
			(layer "F.Fab")
			(hide yes)
			(effects
				(font
					(size 1 1)
					(thickness 0.15)
				)
			)
		)
		(property "Current" "1A"
			(at 352.532501 -86.332501 0)
			(layer "F.Fab")
			(hide yes)
			(effects
				(font
					(size 1 1)
					(thickness 0.15)
				)
			)
		)
		(property "License" "Apache-2.0"
			(at 352.532501 -86.332501 0)
			(layer "F.Fab")
			(hide yes)
			(effects
				(font
					(size 1 1)
					(thickness 0.15)
				)
			)
		)
		(property "MPN" "ERJ2GE0R00X"
			(at 352.532501 -86.332501 0)
			(layer "F.Fab")
			(hide yes)
			(effects
				(font
					(size 1 1)
					(thickness 0.15)
				)
			)
		)
		(property "Manufacturer" "Panasonic"
			(at 352.532501 -86.332501 0)
			(layer "F.Fab")
			(hide yes)
			(effects
				(font
					(size 1 1)
					(thickness 0.15)
				)
			)
		)
		(property "Public" "False"
			(at 352.532501 -86.332501 0)
			(layer "F.Fab")
			(hide yes)
			(effects
				(font
					(size 1 1)
					(thickness 0.15)
				)
			)
		)
		(property "Tolerance" ""
			(at 352.532501 -86.332501 0)
			(layer "F.Fab")
			(hide yes)
			(effects
				(font
					(size 1 1)
					(thickness 0.15)
				)
			)
		)
		(property "Val" "0R"
			(at 352.532501 -86.332501 0)
			(layer "F.Fab")
			(hide yes)
			(effects
				(font
					(size 1 1)
					(thickness 0.15)
				)
			)
		)
		(sheetname "PCIe misc")
		(sheetfile "pcie_misc.kicad_sch")
		(attr smd dnp)
		(fp_rect
			(start -0.925 -0.47)
			(end 0.925 0.47)
			(stroke
				(width 0.05)
				(type default)
			)
			(fill no)
			(layer "F.CrtYd")
		)
		(fp_rect
			(start -0.5 -0.25)
			(end 0.5 0.25)
			(stroke
				(width 0.15)
				(type solid)
			)
			(fill no)
			(layer "F.Fab")
		)
		(pad "1" smd roundrect
			(at -0.48 0 90)
			(size 0.59 0.64)
			(layers "F.Cu" "F.Mask" "F.Paste")
			(roundrect_rratio 0.25)
			(net 526 "/Backplane/~{PRSNT}")
			(pintype "passive")
			(teardrops
				(best_length_ratio 0.2)
				(max_length 1)
				(best_width_ratio 0.9)
				(max_width 2)
				(curved_edges yes)
				(filter_ratio 0.9)
				(enabled yes)
				(allow_two_segments yes)
				(prefer_zone_connections yes)
			)
		)
		(pad "2" smd roundrect
			(at 0.48 0 90)
			(size 0.59 0.64)
			(layers "F.Cu" "F.Mask" "F.Paste")
			(roundrect_rratio 0.25)
			(net 605 "Net-(U37-~{OE3})")
			(pintype "passive")
			(teardrops
				(best_length_ratio 0.2)
				(max_length 1)
				(best_width_ratio 0.9)
				(max_width 2)
				(curved_edges yes)
				(filter_ratio 0.9)
				(enabled yes)
				(allow_two_segments yes)
				(prefer_zone_connections yes)
			)
		)
	)
	(footprint "antmicro-footprints:C_0402_1005Metric"
		(layer "F.Cu")
		(at 190.720296 137.31618 135)
		(descr "Capacitor SMD 0402")
		(tags "capacitor SMD 0402")
		(property "Reference" "C118"
			(at 3.844168 0.29978 135)
			(layer "F.SilkS")
			(effects
				(font
					(size 0.7 0.7)
					(thickness 0.15)
				)
				(justify left top)
			)
		)
		(property "Value" "C_100n_0402"
			(at -1.022927 2.155213 135)
			(layer "F.Fab")
			(effects
				(font
					(size 0.7 0.7)
					(thickness 0.15)
				)
				(justify left top)
			)
		)
		(property "Datasheet" "https://www.murata.com/products/productdetail?partno=GRM155R61H104KE14%23"
			(at 0 0 135)
			(layer "B.Fab")
			(hide yes)
			(effects
				(font
					(size 1.27 1.27)
					(thickness 0.15)
				)
				(justify mirror)
			)
		)
		(property "Author" "Antmicro"
			(at 326.514 57.788 45)
			(layer "F.Fab")
			(hide yes)
			(effects
				(font
					(size 1 1)
					(thickness 0.15)
				)
			)
		)
		(property "Dielectric" "X5R"
			(at 326.514 57.788 45)
			(layer "F.Fab")
			(hide yes)
			(effects
				(font
					(size 1 1)
					(thickness 0.15)
				)
			)
		)
		(property "License" "Apache-2.0"
			(at 326.514 57.788 45)
			(layer "F.Fab")
			(hide yes)
			(effects
				(font
					(size 1 1)
					(thickness 0.15)
				)
			)
		)
		(property "MPN" "GRM155R61H104KE14D"
			(at 326.514 57.788 45)
			(layer "F.Fab")
			(hide yes)
			(effects
				(font
					(size 1 1)
					(thickness 0.15)
				)
			)
		)
		(property "Manufacturer" "Murata"
			(at 326.514 57.788 45)
			(layer "F.Fab")
			(hide yes)
			(effects
				(font
					(size 1 1)
					(thickness 0.15)
				)
			)
		)
		(property "Public" "False"
			(at 326.514 57.788 45)
			(layer "F.Fab")
			(hide yes)
			(effects
				(font
					(size 1 1)
					(thickness 0.15)
				)
			)
		)
		(property "Val" "100n"
			(at 326.514 57.788 45)
			(layer "F.Fab")
			(hide yes)
			(effects
				(font
					(size 1 1)
					(thickness 0.15)
				)
			)
		)
		(property "Voltage" "50V"
			(at 326.514 57.788 45)
			(layer "F.Fab")
			(hide yes)
			(effects
				(font
					(size 1 1)
					(thickness 0.15)
				)
			)
		)
		(sheetname "PCIe redriver")
		(sheetfile "pcie_redriver.kicad_sch")
		(attr smd)
		(fp_poly
			(pts
				(xy -0.925 -0.47) (xy 0.925 -0.47) (xy 0.925 0.47) (xy -0.925 0.47)
			)
			(stroke
				(width 0.05)
				(type default)
			)
			(fill no)
			(layer "F.CrtYd")
		)
		(fp_line
			(start 0.504 -0.25)
			(end 0.504 0.248)
			(stroke
				(width 0.15)
				(type solid)
			)
			(layer "F.Fab")
		)
		(fp_line
			(start 0.504 0.248)
			(end -0.494 0.248)
			(stroke
				(width 0.15)
				(type solid)
			)
			(layer "F.Fab")
		)
		(fp_line
			(start -0.494 -0.25)
			(end 0.504 -0.25)
			(stroke
				(width 0.15)
				(type solid)
			)
			(layer "F.Fab")
		)
		(fp_line
			(start -0.494 0.248)
			(end -0.494 -0.25)
			(stroke
				(width 0.15)
				(type solid)
			)
			(layer "F.Fab")
		)
		(pad "1" smd roundrect
			(at -0.48 0 135)
			(size 0.59 0.64)
			(layers "F.Cu" "F.Mask" "F.Paste")
			(roundrect_rratio 0.25)
			(net 1 "GND")
			(pintype "passive")
			(teardrops
				(best_length_ratio 0.2)
				(max_length 1)
				(best_width_ratio 0.9)
				(max_width 2)
				(curved_edges yes)
				(filter_ratio 0.9)
				(enabled yes)
				(allow_two_segments yes)
				(prefer_zone_connections yes)
			)
		)
		(pad "2" smd roundrect
			(at 0.48 0 135)
			(size 0.59 0.64)
			(layers "F.Cu" "F.Mask" "F.Paste")
			(roundrect_rratio 0.25)
			(net 2 "+3V3")
			(pintype "passive")
			(teardrops
				(best_length_ratio 0.2)
				(max_length 1)
				(best_width_ratio 0.9)
				(max_width 2)
				(curved_edges yes)
				(filter_ratio 0.9)
				(enabled yes)
				(allow_two_segments yes)
				(prefer_zone_connections yes)
			)
		)
	)
	(footprint "antmicro-footprints:SOIC-8_5.3x5.3x2mm_P1.27mm"
		(layer "F.Cu")
		(at 252.922145 161.93 180)
		(descr "8-Pin SOIC 208-mil")
		(property "Reference" "U36"
			(at -1.227855 3.84 180)
			(layer "F.SilkS")
			(effects
				(font
					(size 0.7 0.7)
					(thickness 0.15)
				)
				(justify right top)
			)
		)
		(property "Value" "W25Q32FV_SOIC-8"
			(at 0 3.8 0)
			(layer "F.Fab")
			(effects
				(font
					(size 0.7 0.7)
					(thickness 0.15)
				)
				(justify right top)
			)
		)
		(property "Datasheet" "https://media.digikey.com/pdf/Data%20Sheets/Winbond%20PDFs/W25Q32FV.pdf"
			(at 0 0 0)
			(layer "F.Fab")
			(hide yes)
			(effects
				(font
					(size 1.27 1.27)
					(thickness 0.15)
				)
			)
		)
		(property "Author" "Antmicro"
			(at 308.762145 -27.337855 90)
			(layer "F.Fab")
			(hide yes)
			(effects
				(font
					(size 1 1)
					(thickness 0.15)
				)
			)
		)
		(property "License" "Apache-2.0"
			(at 308.762145 -27.337855 90)
			(layer "F.Fab")
			(hide yes)
			(effects
				(font
					(size 1 1)
					(thickness 0.15)
				)
			)
		)
		(property "MPN" "W25Q32FVSSIG"
			(at 308.762145 -27.337855 90)
			(layer "F.Fab")
			(hide yes)
			(effects
				(font
					(size 1 1)
					(thickness 0.15)
				)
			)
		)
		(property "Manufacturer" "Winbond"
			(at 308.762145 -27.337855 90)
			(layer "F.Fab")
			(hide yes)
			(effects
				(font
					(size 1 1)
					(thickness 0.15)
				)
			)
		)
		(sheetname "Com Express 7 MGMT")
		(sheetfile "com_express_7_mgmt.kicad_sch")
		(attr smd)
		(fp_line
			(start -2.8 -2.641)
			(end -4.4 -2.641)
			(stroke
				(width 0.15)
				(type solid)
			)
			(layer "F.SilkS")
		)
		(fp_circle
			(center -4.85 -1.905)
			(end -4.8 -1.855)
			(stroke
				(width 0.15)
				(type solid)
			)
			(fill yes)
			(layer "F.SilkS")
		)
		(fp_rect
			(start 4.675 -3)
			(end -4.675 3)
			(stroke
				(width 0.05)
				(type solid)
			)
			(fill no)
			(layer "F.CrtYd")
		)
		(fp_line
			(start 2.64 2.64)
			(end -2.641 2.64)
			(stroke
				(width 0.15)
				(type solid)
			)
			(layer "F.Fab")
		)
		(fp_line
			(start 2.64 -2.641)
			(end 2.64 2.64)
			(stroke
				(width 0.15)
				(type solid)
			)
			(layer "F.Fab")
		)
		(fp_line
			(start -2.641 2.64)
			(end -2.641 -2.641)
			(stroke
				(width 0.15)
				(type solid)
			)
			(layer "F.Fab")
		)
		(fp_line
			(start -2.641 -1.371)
			(end -1.371 -2.641)
			(stroke
				(width 0.15)
				(type solid)
			)
			(layer "F.Fab")
		)
		(fp_line
			(start -2.641 -2.641)
			(end 2.64 -2.641)
			(stroke
				(width 0.15)
				(type solid)
			)
			(layer "F.Fab")
		)
		(pad "1" smd roundrect
			(at -3.601 -1.905 270)
			(size 0.65 1.65)
			(layers "F.Cu" "F.Mask" "F.Paste")
			(roundrect_rratio 0.25)
			(net 397 "/Com Express 7 MGMT/SPI.~{CS}")
			(pinfunction "~{CS}")
			(pintype "input")
			(teardrops
				(best_length_ratio 0.2)
				(max_length 1)
				(best_width_ratio 0.9)
				(max_width 2)
				(curved_edges yes)
				(filter_ratio 0.9)
				(enabled yes)
				(allow_two_segments yes)
				(prefer_zone_connections yes)
			)
		)
		(pad "2" smd roundrect
			(at -3.601 -0.635 270)
			(size 0.65 1.65)
			(layers "F.Cu" "F.Mask" "F.Paste")
			(roundrect_rratio 0.25)
			(net 338 "/Com Express 7 MGMT/SPI.MISO")
			(pinfunction "SO(D1)")
			(pintype "bidirectional")
			(teardrops
				(best_length_ratio 0.2)
				(max_length 1)
				(best_width_ratio 0.9)
				(max_width 2)
				(curved_edges yes)
				(filter_ratio 0.9)
				(enabled yes)
				(allow_two_segments yes)
				(prefer_zone_connections yes)
			)
		)
		(pad "3" smd roundrect
			(at -3.601 0.633 270)
			(size 0.65 1.65)
			(layers "F.Cu" "F.Mask" "F.Paste")
			(roundrect_rratio 0.25)
			(net 601 "Net-(U36-~{WP}(D2))")
			(pinfunction "~{WP}(D2)")
			(pintype "bidirectional")
			(teardrops
				(best_length_ratio 0.2)
				(max_length 1)
				(best_width_ratio 0.9)
				(max_width 2)
				(curved_edges yes)
				(filter_ratio 0.9)
				(enabled yes)
				(allow_two_segments yes)
				(prefer_zone_connections yes)
			)
		)
		(pad "4" smd roundrect
			(at -3.601 1.904 270)
			(size 0.65 1.65)
			(layers "F.Cu" "F.Mask" "F.Paste")
			(roundrect_rratio 0.25)
			(net 1 "GND")
			(pinfunction "GND")
			(pintype "power_in")
			(teardrops
				(best_length_ratio 0.2)
				(max_length 1)
				(best_width_ratio 0.9)
				(max_width 2)
				(curved_edges yes)
				(filter_ratio 0.9)
				(enabled yes)
				(allow_two_segments yes)
				(prefer_zone_connections yes)
			)
		)
		(pad "5" smd roundrect
			(at 3.6 1.904 270)
			(size 0.65 1.65)
			(layers "F.Cu" "F.Mask" "F.Paste")
			(roundrect_rratio 0.25)
			(net 341 "/Com Express 7 MGMT/SPI.MOSI")
			(pinfunction "SI(D0)")
			(pintype "bidirectional")
			(teardrops
				(best_length_ratio 0.2)
				(max_length 1)
				(best_width_ratio 0.9)
				(max_width 2)
				(curved_edges yes)
				(filter_ratio 0.9)
				(enabled yes)
				(allow_two_segments yes)
				(prefer_zone_connections yes)
			)
		)
		(pad "6" smd roundrect
			(at 3.6 0.633 270)
			(size 0.65 1.65)
			(layers "F.Cu" "F.Mask" "F.Paste")
			(roundrect_rratio 0.25)
			(net 340 "/Com Express 7 MGMT/SPI.CLK")
			(pinfunction "SCK")
			(pintype "input")
			(teardrops
				(best_length_ratio 0.2)
				(max_length 1)
				(best_width_ratio 0.9)
				(max_width 2)
				(curved_edges yes)
				(filter_ratio 0.9)
				(enabled yes)
				(allow_two_segments yes)
				(prefer_zone_connections yes)
			)
		)
		(pad "7" smd roundrect
			(at 3.6 -0.635 270)
			(size 0.65 1.65)
			(layers "F.Cu" "F.Mask" "F.Paste")
			(roundrect_rratio 0.25)
			(net 600 "Net-(U36-~{HOLD}(D3))")
			(pinfunction "~{HOLD}(D3)")
			(pintype "bidirectional")
			(teardrops
				(best_length_ratio 0.2)
				(max_length 1)
				(best_width_ratio 0.9)
				(max_width 2)
				(curved_edges yes)
				(filter_ratio 0.9)
				(enabled yes)
				(allow_two_segments yes)
				(prefer_zone_connections yes)
			)
		)
		(pad "8" smd roundrect
			(at 3.6 -1.905 270)
			(size 0.65 1.65)
			(layers "F.Cu" "F.Mask" "F.Paste")
			(roundrect_rratio 0.25)
			(net 85 "/Com Express 7 MGMT/MAFS_POWER")
			(pinfunction "VCC")
			(pintype "power_in")
			(teardrops
				(best_length_ratio 0.2)
				(max_length 1)
				(best_width_ratio 0.9)
				(max_width 2)
				(curved_edges yes)
				(filter_ratio 0.9)
				(enabled yes)
				(allow_two_segments yes)
				(prefer_zone_connections yes)
			)
		)
	)
	(footprint "antmicro-footprints:R_0402_1005Metric"
		(layer "F.Cu")
		(at 192.186128 141.609025 135)
		(descr "Resistor SMD 0402")
		(tags "resistor SMD 0402")
		(property "Reference" "R222"
			(at -1.064088 0.369744 135)
			(layer "F.SilkS")
			(effects
				(font
					(size 0.7 0.7)
					(thickness 0.15)
				)
				(justify left top)
			)
		)
		(property "Value" "R_1k_0402"
			(at -1.011843 1.772046 135)
			(layer "F.Fab")
			(effects
				(font
					(size 0.7 0.7)
					(thickness 0.15)
				)
				(justify left top)
			)
		)
		(property "Datasheet" "https://www.bourns.com/docs/product-datasheets/cr.pdf"
			(at 0 0 135)
			(layer "B.Fab")
			(hide yes)
			(effects
				(font
					(size 1.27 1.27)
					(thickness 0.15)
				)
				(justify mirror)
			)
		)
		(property "Author" "Antmicro"
			(at 332.585 55.715 45)
			(layer "F.Fab")
			(hide yes)
			(effects
				(font
					(size 1 1)
					(thickness 0.15)
				)
			)
		)
		(property "License" "Apache-2.0"
			(at 332.585 55.715 45)
			(layer "F.Fab")
			(hide yes)
			(effects
				(font
					(size 1 1)
					(thickness 0.15)
				)
			)
		)
		(property "MPN" "CR0402-FX-1001GLF"
			(at 332.585 55.715 45)
			(layer "F.Fab")
			(hide yes)
			(effects
				(font
					(size 1 1)
					(thickness 0.15)
				)
			)
		)
		(property "Manufacturer" "Bourns"
			(at 332.585 55.715 45)
			(layer "F.Fab")
			(hide yes)
			(effects
				(font
					(size 1 1)
					(thickness 0.15)
				)
			)
		)
		(property "Public" "False"
			(at 332.585 55.715 45)
			(layer "F.Fab")
			(hide yes)
			(effects
				(font
					(size 1 1)
					(thickness 0.15)
				)
			)
		)
		(property "Tolerance" "1%"
			(at 332.585 55.715 45)
			(layer "F.Fab")
			(hide yes)
			(effects
				(font
					(size 1 1)
					(thickness 0.15)
				)
			)
		)
		(property "Val" "1k"
			(at 332.585 55.715 45)
			(layer "F.Fab")
			(hide yes)
			(effects
				(font
					(size 1 1)
					(thickness 0.15)
				)
			)
		)
		(sheetname "PCIe redriver")
		(sheetfile "pcie_redriver.kicad_sch")
		(attr smd dnp)
		(fp_poly
			(pts
				(xy -0.925 -0.47) (xy 0.925 -0.47) (xy 0.925 0.47) (xy -0.925 0.47)
			)
			(stroke
				(width 0.05)
				(type default)
			)
			(fill no)
			(layer "F.CrtYd")
		)
		(fp_poly
			(pts
				(xy -0.5 -0.25) (xy 0.5 -0.25) (xy 0.5 0.25) (xy -0.5 0.25)
			)
			(stroke
				(width 0.15)
				(type solid)
			)
			(fill no)
			(layer "F.Fab")
		)
		(pad "1" smd roundrect
			(at -0.48 0 135)
			(size 0.59 0.64)
			(layers "F.Cu" "F.Mask" "F.Paste")
			(roundrect_rratio 0.25)
			(net 1 "GND")
			(pintype "passive")
			(teardrops
				(best_length_ratio 0.2)
				(max_length 1)
				(best_width_ratio 0.9)
				(max_width 2)
				(curved_edges yes)
				(filter_ratio 0.9)
				(enabled yes)
				(allow_two_segments yes)
				(prefer_zone_connections yes)
			)
		)
		(pad "2" smd roundrect
			(at 0.48 0 135)
			(size 0.59 0.64)
			(layers "F.Cu" "F.Mask" "F.Paste")
			(roundrect_rratio 0.25)
			(net 974 "/PCIe redriver/RX_FG1")
			(pintype "passive")
			(teardrops
				(best_length_ratio 0.2)
				(max_length 1)
				(best_width_ratio 0.9)
				(max_width 2)
				(curved_edges yes)
				(filter_ratio 0.9)
				(enabled yes)
				(allow_two_segments yes)
				(prefer_zone_connections yes)
			)
		)
	)
	(footprint "antmicro-footprints:C_0402_1005Metric"
		(layer "F.Cu")
		(at 117.4 146.301 90)
		(descr "Capacitor SMD 0402")
		(tags "capacitor SMD 0402")
		(property "Reference" "C116"
			(at 10.541 1.6 90)
			(layer "F.SilkS")
			(effects
				(font
					(size 0.7 0.7)
					(thickness 0.15)
				)
				(justify left bottom)
			)
		)
		(property "Value" "C_100n_0402"
			(at -1.022927 2.155213 90)
			(layer "F.Fab")
			(effects
				(font
					(size 0.7 0.7)
					(thickness 0.15)
				)
				(justify left bottom)
			)
		)
		(property "Datasheet" "https://www.murata.com/products/productdetail?partno=GRM155R61H104KE14%23"
			(at 0 0 90)
			(layer "F.Fab")
			(hide yes)
			(effects
				(font
					(size 1.27 1.27)
					(thickness 0.15)
				)
			)
		)
		(property "Author" "Antmicro"
			(at 263.701 28.901 0)
			(layer "F.Fab")
			(hide yes)
			(effects
				(font
					(size 1 1)
					(thickness 0.15)
				)
			)
		)
		(property "Dielectric" "X5R"
			(at 263.701 28.901 0)
			(layer "F.Fab")
			(hide yes)
			(effects
				(font
					(size 1 1)
					(thickness 0.15)
				)
			)
		)
		(property "License" "Apache-2.0"
			(at 263.701 28.901 0)
			(layer "F.Fab")
			(hide yes)
			(effects
				(font
					(size 1 1)
					(thickness 0.15)
				)
			)
		)
		(property "MPN" "GRM155R61H104KE14D"
			(at 263.701 28.901 0)
			(layer "F.Fab")
			(hide yes)
			(effects
				(font
					(size 1 1)
					(thickness 0.15)
				)
			)
		)
		(property "Manufacturer" "Murata"
			(at 263.701 28.901 0)
			(layer "F.Fab")
			(hide yes)
			(effects
				(font
					(size 1 1)
					(thickness 0.15)
				)
			)
		)
		(property "Public" "False"
			(at 263.701 28.901 0)
			(layer "F.Fab")
			(hide yes)
			(effects
				(font
					(size 1 1)
					(thickness 0.15)
				)
			)
		)
		(property "Val" "100n"
			(at 263.701 28.901 0)
			(layer "F.Fab")
			(hide yes)
			(effects
				(font
					(size 1 1)
					(thickness 0.15)
				)
			)
		)
		(property "Voltage" "50V"
			(at 263.701 28.901 0)
			(layer "F.Fab")
			(hide yes)
			(effects
				(font
					(size 1 1)
					(thickness 0.15)
				)
			)
		)
		(sheetname "PCIe redriver")
		(sheetfile "pcie_redriver.kicad_sch")
		(attr smd)
		(fp_rect
			(start -0.925 -0.47)
			(end 0.925 0.47)
			(stroke
				(width 0.05)
				(type default)
			)
			(fill no)
			(layer "F.CrtYd")
		)
		(fp_line
			(start 0.504 -0.25)
			(end 0.504 0.248)
			(stroke
				(width 0.15)
				(type solid)
			)
			(layer "F.Fab")
		)
		(fp_line
			(start -0.494 -0.25)
			(end 0.504 -0.25)
			(stroke
				(width 0.15)
				(type solid)
			)
			(layer "F.Fab")
		)
		(fp_line
			(start 0.504 0.248)
			(end -0.494 0.248)
			(stroke
				(width 0.15)
				(type solid)
			)
			(layer "F.Fab")
		)
		(fp_line
			(start -0.494 0.248)
			(end -0.494 -0.25)
			(stroke
				(width 0.15)
				(type solid)
			)
			(layer "F.Fab")
		)
		(pad "1" smd roundrect
			(at -0.48 0 90)
			(size 0.59 0.64)
			(layers "F.Cu" "F.Mask" "F.Paste")
			(roundrect_rratio 0.25)
			(net 1 "GND")
			(pintype "passive")
			(teardrops
				(best_length_ratio 0.2)
				(max_length 1)
				(best_width_ratio 0.9)
				(max_width 2)
				(curved_edges yes)
				(filter_ratio 0.9)
				(enabled yes)
				(allow_two_segments yes)
				(prefer_zone_connections yes)
			)
		)
		(pad "2" smd roundrect
			(at 0.48 0 90)
			(size 0.59 0.64)
			(layers "F.Cu" "F.Mask" "F.Paste")
			(roundrect_rratio 0.25)
			(net 2 "+3V3")
			(pintype "passive")
			(teardrops
				(best_length_ratio 0.2)
				(max_length 1)
				(best_width_ratio 0.9)
				(max_width 2)
				(curved_edges yes)
				(filter_ratio 0.9)
				(enabled yes)
				(allow_two_segments yes)
				(prefer_zone_connections yes)
			)
		)
	)
	(footprint "antmicro-footprints:R_0402_1005Metric"
		(layer "F.Cu")
		(at 252.665001 87.45)
		(descr "Resistor SMD 0402")
		(tags "resistor SMD 0402")
		(property "Reference" "R149"
			(at -0.865001 0.440001 0)
			(layer "F.SilkS")
			(effects
				(font
					(size 0.7 0.7)
					(thickness 0.15)
				)
				(justify right bottom)
			)
		)
		(property "Value" "R_0R_0402"
			(at -1.011843 1.772047 0)
			(layer "F.Fab")
			(effects
				(font
					(size 0.7 0.7)
					(thickness 0.15)
				)
				(justify left bottom)
			)
		)
		(property "Datasheet" "https://industrial.panasonic.com/cdbs/www-data/pdf/RDA0000/AOA0000C301.pdf"
			(at 0 0 0)
			(layer "F.Fab")
			(hide yes)
			(effects
				(font
					(size 1.27 1.27)
					(thickness 0.15)
				)
			)
		)
		(property "Author" "Antmicro"
			(at 0 0 0)
			(layer "F.Fab")
			(hide yes)
			(effects
				(font
					(size 1 1)
					(thickness 0.15)
				)
			)
		)
		(property "Current" "1A"
			(at 0 0 0)
			(layer "F.Fab")
			(hide yes)
			(effects
				(font
					(size 1 1)
					(thickness 0.15)
				)
			)
		)
		(property "License" "Apache-2.0"
			(at 0 0 0)
			(layer "F.Fab")
			(hide yes)
			(effects
				(font
					(size 1 1)
					(thickness 0.15)
				)
			)
		)
		(property "MPN" "ERJ2GE0R00X"
			(at 0 0 0)
			(layer "F.Fab")
			(hide yes)
			(effects
				(font
					(size 1 1)
					(thickness 0.15)
				)
			)
		)
		(property "Manufacturer" "Panasonic"
			(at 0 0 0)
			(layer "F.Fab")
			(hide yes)
			(effects
				(font
					(size 1 1)
					(thickness 0.15)
				)
			)
		)
		(property "Public" "False"
			(at 0 0 0)
			(layer "F.Fab")
			(hide yes)
			(effects
				(font
					(size 1 1)
					(thickness 0.15)
				)
			)
		)
		(property "Tolerance" ""
			(at 0 0 0)
			(layer "F.Fab")
			(hide yes)
			(effects
				(font
					(size 1 1)
					(thickness 0.15)
				)
			)
		)
		(property "Val" "0R"
			(at 0 0 0)
			(layer "F.Fab")
			(hide yes)
			(effects
				(font
					(size 1 1)
					(thickness 0.15)
				)
			)
		)
		(sheetname "Misc")
		(sheetfile "misc.kicad_sch")
		(attr smd)
		(fp_rect
			(start -0.925 -0.47)
			(end 0.925 0.47)
			(stroke
				(width 0.05)
				(type default)
			)
			(fill no)
			(layer "F.CrtYd")
		)
		(fp_rect
			(start -0.5 -0.25)
			(end 0.5 0.25)
			(stroke
				(width 0.15)
				(type solid)
			)
			(fill no)
			(layer "F.Fab")
		)
		(pad "1" smd roundrect
			(at -0.48 0)
			(size 0.59 0.64)
			(layers "F.Cu" "F.Mask" "F.Paste")
			(roundrect_rratio 0.25)
			(net 65 "+12V")
			(pintype "passive")
			(teardrops
				(best_length_ratio 0.2)
				(max_length 1)
				(best_width_ratio 0.9)
				(max_width 2)
				(curved_edges yes)
				(filter_ratio 0.9)
				(enabled yes)
				(allow_two_segments yes)
				(prefer_zone_connections yes)
			)
		)
		(pad "2" smd roundrect
			(at 0.48 0)
			(size 0.59 0.64)
			(layers "F.Cu" "F.Mask" "F.Paste")
			(roundrect_rratio 0.25)
			(net 591 "Net-(U24-+12V_{IN})")
			(pintype "passive")
			(teardrops
				(best_length_ratio 0.2)
				(max_length 1)
				(best_width_ratio 0.9)
				(max_width 2)
				(curved_edges yes)
				(filter_ratio 0.9)
				(enabled yes)
				(allow_two_segments yes)
				(prefer_zone_connections yes)
			)
		)
	)
	(footprint "antmicro-footprints:LED_0603_1608Metric_G"
		(layer "F.Cu")
		(at 112.4 69.86 90)
		(descr "LED SMD 0603 Green")
		(tags "LED SMD 0603 Green")
		(property "Reference" "D11"
			(at -3.4 0.4 90)
			(layer "F.SilkS")
			(effects
				(font
					(size 0.7 0.7)
					(thickness 0.15)
				)
				(justify left bottom)
			)
		)
		(property "Value" "LED_G_0603_LTST-C190GKT"
			(at -0.001 1.599 90)
			(layer "F.Fab")
			(effects
				(font
					(size 0.7 0.7)
					(thickness 0.15)
				)
				(justify left bottom)
			)
		)
		(property "Datasheet" "https://media.digikey.com/pdf/Data%20Sheets/Lite-On%20PDFs/LTST-C190GKT.pdf"
			(at 0 0 90)
			(layer "F.Fab")
			(hide yes)
			(effects
				(font
					(size 1.27 1.27)
					(thickness 0.15)
				)
			)
		)
		(property "Author" "Antmicro"
			(at 182.26 -42.54 0)
			(layer "F.Fab")
			(hide yes)
			(effects
				(font
					(size 1 1)
					(thickness 0.15)
				)
			)
		)
		(property "Color" "Green"
			(at 182.26 -42.54 0)
			(layer "F.Fab")
			(hide yes)
			(effects
				(font
					(size 1 1)
					(thickness 0.15)
				)
			)
		)
		(property "License" "Apache-2.0"
			(at 182.26 -42.54 0)
			(layer "F.Fab")
			(hide yes)
			(effects
				(font
					(size 1 1)
					(thickness 0.15)
				)
			)
		)
		(property "MPN" "LTST-C190GKT"
			(at 182.26 -42.54 0)
			(layer "F.Fab")
			(hide yes)
			(effects
				(font
					(size 1 1)
					(thickness 0.15)
				)
			)
		)
		(property "Manufacturer" "Lite-On"
			(at 182.26 -42.54 0)
			(layer "F.Fab")
			(hide yes)
			(effects
				(font
					(size 1 1)
					(thickness 0.15)
				)
			)
		)
		(property "Public" "False"
			(at 182.26 -42.54 0)
			(layer "F.Fab")
			(hide yes)
			(effects
				(font
					(size 1 1)
					(thickness 0.15)
				)
			)
		)
		(sheetname "USB-C console")
		(sheetfile "usb-c_console.kicad_sch")
		(attr smd)
		(fp_line
			(start 0.22 -0.35)
			(end -0.22 -0.35)
			(stroke
				(width 0.15)
				(type solid)
			)
			(layer "F.SilkS")
		)
		(fp_line
			(start -1.18 -0.319)
			(end -1.18 0.321)
			(stroke
				(width 0.15)
				(type solid)
			)
			(layer "F.SilkS")
		)
		(fp_line
			(start 0.105328 0.001008)
			(end 0.24 0.001)
			(stroke
				(width 0.1)
				(type solid)
			)
			(layer "F.SilkS")
		)
		(fp_line
			(start -0.094672 0.001008)
			(end 0.105328 -0.198992)
			(stroke
				(width 0.1)
				(type solid)
			)
			(layer "F.SilkS")
		)
		(fp_line
			(start -0.094672 0.001008)
			(end -0.24 0.001008)
			(stroke
				(width 0.1)
				(type solid)
			)
			(layer "F.SilkS")
		)
		(fp_line
			(start 0.105328 0.201008)
			(end 0.105328 -0.198992)
			(stroke
				(width 0.1)
				(type solid)
			)
			(layer "F.SilkS")
		)
		(fp_line
			(start 0.105328 0.201008)
			(end -0.094672 0.001008)
			(stroke
				(width 0.1)
				(type solid)
			)
			(layer "F.SilkS")
		)
		(fp_line
			(start -0.094672 0.201008)
			(end -0.094672 -0.198992)
			(stroke
				(width 0.1)
				(type solid)
			)
			(layer "F.SilkS")
		)
		(fp_line
			(start 0.22 0.35)
			(end -0.22 0.35)
			(stroke
				(width 0.15)
				(type solid)
			)
			(layer "F.SilkS")
		)
		(fp_rect
			(start 1.25 0.65)
			(end -1.25 -0.65)
			(stroke
				(width 0.05)
				(type solid)
			)
			(fill no)
			(layer "F.CrtYd")
		)
		(fp_line
			(start 0.201 -0.202)
			(end -0.101 0)
			(stroke
				(width 0.15)
				(type solid)
			)
			(layer "F.Fab")
		)
		(fp_line
			(start -0.199 -0.202)
			(end -0.199 0.1)
			(stroke
				(width 0.15)
				(type solid)
			)
			(layer "F.Fab")
		)
		(fp_line
			(start 0.599 0)
			(end 0.201 0)
			(stroke
				(width 0.15)
				(type solid)
			)
			(layer "F.Fab")
		)
		(fp_line
			(start 0.201 0)
			(end 0.201 -0.202)
			(stroke
				(width 0.15)
				(type solid)
			)
			(layer "F.Fab")
		)
		(fp_line
			(start -0.101 0)
			(end 0.201 0.2)
			(stroke
				(width 0.15)
				(type solid)
			)
			(layer "F.Fab")
		)
		(fp_line
			(start -0.199 0)
			(end -0.597 0)
			(stroke
				(width 0.15)
				(type solid)
			)
			(layer "F.Fab")
		)
		(fp_line
			(start 0.201 0.2)
			(end 0.201 0)
			(stroke
				(width 0.15)
				(type solid)
			)
			(layer "F.Fab")
		)
		(fp_line
			(start -0.199 0.2)
			(end -0.199 0.1)
			(stroke
				(width 0.15)
				(type solid)
			)
			(layer "F.Fab")
		)
		(fp_rect
			(start 0.848 0.4)
			(end -0.85 -0.402)
			(stroke
				(width 0.15)
				(type solid)
			)
			(fill no)
			(layer "F.Fab")
		)
		(pad "1" smd roundrect
			(at -0.7 0 270)
			(size 0.8 1)
			(layers "F.Cu" "F.Mask" "F.Paste")
			(roundrect_rratio 0.2)
			(net 127 "/USB-C console/FTDI_LED_RX")
			(pinfunction "C")
			(pintype "passive")
			(teardrops
				(best_length_ratio 0.2)
				(max_length 1)
				(best_width_ratio 0.9)
				(max_width 2)
				(curved_edges yes)
				(filter_ratio 0.9)
				(enabled yes)
				(allow_two_segments yes)
				(prefer_zone_connections yes)
			)
		)
		(pad "2" smd roundrect
			(at 0.7 0 270)
			(size 0.8 1)
			(layers "F.Cu" "F.Mask" "F.Paste")
			(roundrect_rratio 0.2)
			(net 933 "Net-(D11-A)")
			(pinfunction "A")
			(pintype "passive")
			(teardrops
				(best_length_ratio 0.2)
				(max_length 1)
				(best_width_ratio 0.9)
				(max_width 2)
				(curved_edges yes)
				(filter_ratio 0.9)
				(enabled yes)
				(allow_two_segments yes)
				(prefer_zone_connections yes)
			)
		)
	)
	(footprint "antmicro-footprints:R_0402_1005Metric"
		(layer "F.Cu")
		(at 130.08 116.6 180)
		(descr "Resistor SMD 0402")
		(tags "resistor SMD 0402")
		(property "Reference" "R22"
			(at 0.780999 0.45 0)
			(layer "F.SilkS")
			(effects
				(font
					(size 0.7 0.7)
					(thickness 0.15)
				)
				(justify right top)
			)
		)
		(property "Value" "R_0R_0402"
			(at -1.011843 1.772046 0)
			(layer "F.Fab")
			(effects
				(font
					(size 0.7 0.7)
					(thickness 0.15)
				)
				(justify right top)
			)
		)
		(property "Datasheet" "https://industrial.panasonic.com/cdbs/www-data/pdf/RDA0000/AOA0000C301.pdf"
			(at 0 0 0)
			(layer "F.Fab")
			(hide yes)
			(effects
				(font
					(size 1.27 1.27)
					(thickness 0.15)
				)
			)
		)
		(property "Author" "Antmicro"
			(at 354.241 -58.059 90)
			(layer "F.Fab")
			(hide yes)
			(effects
				(font
					(size 1 1)
					(thickness 0.15)
				)
			)
		)
		(property "Current" "1A"
			(at 354.241 -58.059 90)
			(layer "F.Fab")
			(hide yes)
			(effects
				(font
					(size 1 1)
					(thickness 0.15)
				)
			)
		)
		(property "License" "Apache-2.0"
			(at 354.241 -58.059 90)
			(layer "F.Fab")
			(hide yes)
			(effects
				(font
					(size 1 1)
					(thickness 0.15)
				)
			)
		)
		(property "MPN" "ERJ2GE0R00X"
			(at 354.241 -58.059 90)
			(layer "F.Fab")
			(hide yes)
			(effects
				(font
					(size 1 1)
					(thickness 0.15)
				)
			)
		)
		(property "Manufacturer" "Panasonic"
			(at 354.241 -58.059 90)
			(layer "F.Fab")
			(hide yes)
			(effects
				(font
					(size 1 1)
					(thickness 0.15)
				)
			)
		)
		(property "Public" "False"
			(at 354.241 -58.059 90)
			(layer "F.Fab")
			(hide yes)
			(effects
				(font
					(size 1 1)
					(thickness 0.15)
				)
			)
		)
		(property "Tolerance" ""
			(at 354.241 -58.059 90)
			(layer "F.Fab")
			(hide yes)
			(effects
				(font
					(size 1 1)
					(thickness 0.15)
				)
			)
		)
		(property "Val" "0R"
			(at 354.241 -58.059 90)
			(layer "F.Fab")
			(hide yes)
			(effects
				(font
					(size 1 1)
					(thickness 0.15)
				)
			)
		)
		(sheetname "2xUSB3.0+RJ45")
		(sheetfile "usb3+rj45.kicad_sch")
		(attr smd)
		(fp_rect
			(start -0.925 -0.47)
			(end 0.925 0.47)
			(stroke
				(width 0.05)
				(type default)
			)
			(fill no)
			(layer "F.CrtYd")
		)
		(fp_rect
			(start -0.5 -0.25)
			(end 0.5 0.25)
			(stroke
				(width 0.15)
				(type solid)
			)
			(fill no)
			(layer "F.Fab")
		)
		(pad "1" smd roundrect
			(at -0.48 0 180)
			(size 0.59 0.64)
			(layers "F.Cu" "F.Mask" "F.Paste")
			(roundrect_rratio 0.25)
			(net 375 "/2xUSB3.0+RJ45/USB_2.D+")
			(pintype "passive")
			(teardrops
				(best_length_ratio 0.2)
				(max_length 1)
				(best_width_ratio 0.9)
				(max_width 2)
				(curved_edges yes)
				(filter_ratio 0.9)
				(enabled yes)
				(allow_two_segments yes)
				(prefer_zone_connections yes)
			)
		)
		(pad "2" smd roundrect
			(at 0.48 0 180)
			(size 0.59 0.64)
			(layers "F.Cu" "F.Mask" "F.Paste")
			(roundrect_rratio 0.25)
			(net 126 "/2xUSB3.0+RJ45/P2_D+")
			(pintype "passive")
			(teardrops
				(best_length_ratio 0.2)
				(max_length 1)
				(best_width_ratio 0.9)
				(max_width 2)
				(curved_edges yes)
				(filter_ratio 0.9)
				(enabled yes)
				(allow_two_segments yes)
				(prefer_zone_connections yes)
			)
		)
	)
	(footprint "antmicro-footprints:LED_0603_1608Metric_G"
		(layer "F.Cu")
		(at 201.70861 74.802163 90)
		(descr "LED SMD 0603 Green")
		(tags "LED SMD 0603 Green")
		(property "Reference" "D26"
			(at -1.1 -0.55 90)
			(layer "F.SilkS")
			(effects
				(font
					(size 0.7 0.7)
					(thickness 0.15)
				)
				(justify left bottom)
			)
		)
		(property "Value" "LED_G_0603_LTST-C190GKT"
			(at -0.001 1.599 90)
			(layer "F.Fab")
			(effects
				(font
					(size 0.7 0.7)
					(thickness 0.15)
				)
				(justify left bottom)
			)
		)
		(property "Datasheet" "https://media.digikey.com/pdf/Data%20Sheets/Lite-On%20PDFs/LTST-C190GKT.pdf"
			(at 0 0 90)
			(layer "F.Fab")
			(hide yes)
			(effects
				(font
					(size 1.27 1.27)
					(thickness 0.15)
				)
			)
		)
		(property "Author" "Antmicro"
			(at 276.510773 -126.906447 0)
			(layer "F.Fab")
			(hide yes)
			(effects
				(font
					(size 1 1)
					(thickness 0.15)
				)
			)
		)
		(property "Color" "Green"
			(at 276.510773 -126.906447 0)
			(layer "F.Fab")
			(hide yes)
			(effects
				(font
					(size 1 1)
					(thickness 0.15)
				)
			)
		)
		(property "License" "Apache-2.0"
			(at 276.510773 -126.906447 0)
			(layer "F.Fab")
			(hide yes)
			(effects
				(font
					(size 1 1)
					(thickness 0.15)
				)
			)
		)
		(property "MPN" "LTST-C190GKT"
			(at 276.510773 -126.906447 0)
			(layer "F.Fab")
			(hide yes)
			(effects
				(font
					(size 1 1)
					(thickness 0.15)
				)
			)
		)
		(property "Manufacturer" "Lite-On"
			(at 276.510773 -126.906447 0)
			(layer "F.Fab")
			(hide yes)
			(effects
				(font
					(size 1 1)
					(thickness 0.15)
				)
			)
		)
		(property "Public" "False"
			(at 276.510773 -126.906447 0)
			(layer "F.Fab")
			(hide yes)
			(effects
				(font
					(size 1 1)
					(thickness 0.15)
				)
			)
		)
		(sheetname "Power")
		(sheetfile "power.kicad_sch")
		(attr smd)
		(fp_line
			(start 0.22 -0.35)
			(end -0.22 -0.35)
			(stroke
				(width 0.15)
				(type solid)
			)
			(layer "F.SilkS")
		)
		(fp_line
			(start -1.18 -0.319)
			(end -1.18 0.321)
			(stroke
				(width 0.15)
				(type solid)
			)
			(layer "F.SilkS")
		)
		(fp_line
			(start 0.105328 0.001008)
			(end 0.24 0.001)
			(stroke
				(width 0.1)
				(type solid)
			)
			(layer "F.SilkS")
		)
		(fp_line
			(start -0.094672 0.001008)
			(end 0.105328 -0.198992)
			(stroke
				(width 0.1)
				(type solid)
			)
			(layer "F.SilkS")
		)
		(fp_line
			(start -0.094672 0.001008)
			(end -0.24 0.001008)
			(stroke
				(width 0.1)
				(type solid)
			)
			(layer "F.SilkS")
		)
		(fp_line
			(start 0.105328 0.201008)
			(end 0.105328 -0.198992)
			(stroke
				(width 0.1)
				(type solid)
			)
			(layer "F.SilkS")
		)
		(fp_line
			(start 0.105328 0.201008)
			(end -0.094672 0.001008)
			(stroke
				(width 0.1)
				(type solid)
			)
			(layer "F.SilkS")
		)
		(fp_line
			(start -0.094672 0.201008)
			(end -0.094672 -0.198992)
			(stroke
				(width 0.1)
				(type solid)
			)
			(layer "F.SilkS")
		)
		(fp_line
			(start 0.22 0.35)
			(end -0.22 0.35)
			(stroke
				(width 0.15)
				(type solid)
			)
			(layer "F.SilkS")
		)
		(fp_rect
			(start 1.25 0.65)
			(end -1.25 -0.65)
			(stroke
				(width 0.05)
				(type solid)
			)
			(fill no)
			(layer "F.CrtYd")
		)
		(fp_line
			(start 0.201 -0.202)
			(end -0.101 0)
			(stroke
				(width 0.15)
				(type solid)
			)
			(layer "F.Fab")
		)
		(fp_line
			(start -0.199 -0.202)
			(end -0.199 0.1)
			(stroke
				(width 0.15)
				(type solid)
			)
			(layer "F.Fab")
		)
		(fp_line
			(start 0.599 0)
			(end 0.201 0)
			(stroke
				(width 0.15)
				(type solid)
			)
			(layer "F.Fab")
		)
		(fp_line
			(start 0.201 0)
			(end 0.201 -0.202)
			(stroke
				(width 0.15)
				(type solid)
			)
			(layer "F.Fab")
		)
		(fp_line
			(start -0.101 0)
			(end 0.201 0.2)
			(stroke
				(width 0.15)
				(type solid)
			)
			(layer "F.Fab")
		)
		(fp_line
			(start -0.199 0)
			(end -0.597 0)
			(stroke
				(width 0.15)
				(type solid)
			)
			(layer "F.Fab")
		)
		(fp_line
			(start 0.201 0.2)
			(end 0.201 0)
			(stroke
				(width 0.15)
				(type solid)
			)
			(layer "F.Fab")
		)
		(fp_line
			(start -0.199 0.2)
			(end -0.199 0.1)
			(stroke
				(width 0.15)
				(type solid)
			)
			(layer "F.Fab")
		)
		(fp_rect
			(start 0.848 0.4)
			(end -0.85 -0.402)
			(stroke
				(width 0.15)
				(type solid)
			)
			(fill no)
			(layer "F.Fab")
		)
		(pad "1" smd roundrect
			(at -0.7 0 270)
			(size 0.8 1)
			(layers "F.Cu" "F.Mask" "F.Paste")
			(roundrect_rratio 0.2)
			(net 979 "Net-(D26-C)")
			(pinfunction "C")
			(pintype "passive")
			(teardrops
				(best_length_ratio 0.2)
				(max_length 1)
				(best_width_ratio 0.9)
				(max_width 2)
				(curved_edges yes)
				(filter_ratio 0.9)
				(enabled yes)
				(allow_two_segments yes)
				(prefer_zone_connections yes)
			)
		)
		(pad "2" smd roundrect
			(at 0.7 0 270)
			(size 0.8 1)
			(layers "F.Cu" "F.Mask" "F.Paste")
			(roundrect_rratio 0.2)
			(net 62 "+12V_AON")
			(pinfunction "A")
			(pintype "passive")
			(teardrops
				(best_length_ratio 0.2)
				(max_length 1)
				(best_width_ratio 0.9)
				(max_width 2)
				(curved_edges yes)
				(filter_ratio 0.9)
				(enabled yes)
				(allow_two_segments yes)
				(prefer_zone_connections yes)
			)
		)
	)
	(footprint "antmicro-footprints:C_0402_1005Metric"
		(layer "F.Cu")
		(at 240.8 132.36 -90)
		(descr "Capacitor SMD 0402")
		(tags "capacitor SMD 0402")
		(property "Reference" "C216"
			(at 0.8 0.37 90)
			(layer "F.SilkS")
			(effects
				(font
					(size 0.7 0.7)
					(thickness 0.15)
				)
				(justify right top)
			)
		)
		(property "Value" "C_100n_0402"
			(at -1.022927 2.155213 90)
			(layer "F.Fab")
			(effects
				(font
					(size 0.7 0.7)
					(thickness 0.15)
				)
				(justify right top)
			)
		)
		(property "Datasheet" "https://www.murata.com/products/productdetail?partno=GRM155R61H104KE14%23"
			(at 0 0 90)
			(layer "F.Fab")
			(hide yes)
			(effects
				(font
					(size 1.27 1.27)
					(thickness 0.15)
				)
			)
		)
		(property "MPN" "GRM155R61H104KE14D"
			(at 0 0 270)
			(unlocked yes)
			(layer "F.Fab")
			(hide yes)
			(effects
				(font
					(size 1 1)
					(thickness 0.15)
				)
			)
		)
		(property "Manufacturer" "Murata"
			(at 0 0 270)
			(unlocked yes)
			(layer "F.Fab")
			(hide yes)
			(effects
				(font
					(size 1 1)
					(thickness 0.15)
				)
			)
		)
		(property "License" "Apache-2.0"
			(at 0 0 270)
			(unlocked yes)
			(layer "F.Fab")
			(hide yes)
			(effects
				(font
					(size 1 1)
					(thickness 0.15)
				)
			)
		)
		(property "Author" "Antmicro"
			(at 0 0 270)
			(unlocked yes)
			(layer "F.Fab")
			(hide yes)
			(effects
				(font
					(size 1 1)
					(thickness 0.15)
				)
			)
		)
		(property "Val" "100n"
			(at 0 0 270)
			(unlocked yes)
			(layer "F.Fab")
			(hide yes)
			(effects
				(font
					(size 1 1)
					(thickness 0.15)
				)
			)
		)
		(property "Voltage" "50V"
			(at 0 0 270)
			(unlocked yes)
			(layer "F.Fab")
			(hide yes)
			(effects
				(font
					(size 1 1)
					(thickness 0.15)
				)
			)
		)
		(property "Dielectric" "X5R"
			(at 0 0 270)
			(unlocked yes)
			(layer "F.Fab")
			(hide yes)
			(effects
				(font
					(size 1 1)
					(thickness 0.15)
				)
			)
		)
		(property "Public" "False"
			(at 0 0 270)
			(unlocked yes)
			(layer "F.Fab")
			(hide yes)
			(effects
				(font
					(size 1 1)
					(thickness 0.15)
				)
			)
		)
		(sheetname "Com Express 7 MGMT")
		(sheetfile "com_express_7_mgmt.kicad_sch")
		(attr smd)
		(fp_rect
			(start -0.925 -0.47)
			(end 0.925 0.47)
			(stroke
				(width 0.05)
				(type default)
			)
			(fill no)
			(layer "F.CrtYd")
		)
		(fp_line
			(start -0.494 0.248)
			(end -0.494 -0.25)
			(stroke
				(width 0.15)
				(type solid)
			)
			(layer "F.Fab")
		)
		(fp_line
			(start 0.504 0.248)
			(end -0.494 0.248)
			(stroke
				(width 0.15)
				(type solid)
			)
			(layer "F.Fab")
		)
		(fp_line
			(start -0.494 -0.25)
			(end 0.504 -0.25)
			(stroke
				(width 0.15)
				(type solid)
			)
			(layer "F.Fab")
		)
		(fp_line
			(start 0.504 -0.25)
			(end 0.504 0.248)
			(stroke
				(width 0.15)
				(type solid)
			)
			(layer "F.Fab")
		)
		(pad "1" smd roundrect
			(at -0.48 0 270)
			(size 0.59 0.64)
			(layers "F.Cu" "F.Mask" "F.Paste")
			(roundrect_rratio 0.25)
			(net 1 "GND")
			(pintype "passive")
			(teardrops
				(best_length_ratio 0.2)
				(max_length 1)
				(best_width_ratio 0.9)
				(max_width 2)
				(curved_edges yes)
				(filter_ratio 0.9)
				(enabled yes)
				(allow_two_segments yes)
				(prefer_zone_connections yes)
			)
		)
		(pad "2" smd roundrect
			(at 0.48 0 270)
			(size 0.59 0.64)
			(layers "F.Cu" "F.Mask" "F.Paste")
			(roundrect_rratio 0.25)
			(net 533 "/Com Express 7 MGMT/PSON")
			(pintype "passive")
			(teardrops
				(best_length_ratio 0.2)
				(max_length 1)
				(best_width_ratio 0.9)
				(max_width 2)
				(curved_edges yes)
				(filter_ratio 0.9)
				(enabled yes)
				(allow_two_segments yes)
				(prefer_zone_connections yes)
			)
		)
	)
	(footprint "antmicro-footprints:TP_SMD_0.75mm"
		(layer "F.Cu")
		(at 147.25 129.56)
		(property "Reference" "TP76"
			(at 0.45 -1.25 90)
			(layer "F.SilkS")
			(effects
				(font
					(size 0.7 0.7)
					(thickness 0.15)
				)
				(justify left bottom)
			)
		)
		(property "Value" "TP_0.75mm_SMD"
			(at 0 1.2 0)
			(layer "F.Fab")
			(effects
				(font
					(size 0.7 0.7)
					(thickness 0.15)
				)
				(justify left bottom)
			)
		)
		(property "Author" "Antmicro"
			(at 0 0 0)
			(layer "F.Fab")
			(hide yes)
			(effects
				(font
					(size 1 1)
					(thickness 0.15)
				)
			)
		)
		(property "License" "Apache-2.0"
			(at 0 0 0)
			(layer "F.Fab")
			(hide yes)
			(effects
				(font
					(size 1 1)
					(thickness 0.15)
				)
			)
		)
		(property "MPN" ""
			(at 0 0 0)
			(layer "F.Fab")
			(hide yes)
			(effects
				(font
					(size 1 1)
					(thickness 0.15)
				)
			)
		)
		(property "Manufacturer" ""
			(at 0 0 0)
			(layer "F.Fab")
			(hide yes)
			(effects
				(font
					(size 1 1)
					(thickness 0.15)
				)
			)
		)
		(property "Public" "False"
			(at 0 0 0)
			(layer "F.Fab")
			(hide yes)
			(effects
				(font
					(size 1 1)
					(thickness 0.15)
				)
			)
		)
		(sheetname "KR to SFI #1")
		(sheetfile "kr_sfi.kicad_sch")
		(attr exclude_from_pos_files exclude_from_bom)
		(fp_circle
			(center 0 0)
			(end 0.475 0)
			(stroke
				(width 0.05)
				(type default)
			)
			(fill no)
			(layer "F.CrtYd")
		)
		(pad "1" smd circle
			(at 0 0)
			(size 0.75 0.75)
			(layers "F.Cu" "F.Mask")
			(net 739 "Net-(U43B-LS_OK_{OUT_B})")
			(pinfunction "1")
			(pintype "passive")
			(teardrops
				(best_length_ratio 0.4)
				(max_length 1)
				(best_width_ratio 0.9)
				(max_width 2)
				(curved_edges yes)
				(filter_ratio 0.9)
				(enabled yes)
				(allow_two_segments yes)
				(prefer_zone_connections yes)
			)
		)
	)
	(footprint "antmicro-footprints:R_0402_1005Metric"
		(layer "F.Cu")
		(at 312.765499 97.4365 -90)
		(descr "Resistor SMD 0402")
		(tags "resistor SMD 0402")
		(property "Reference" "R107"
			(at -10.1265 -4.734501 90)
			(layer "F.SilkS")
			(effects
				(font
					(size 0.7 0.7)
					(thickness 0.15)
				)
				(justify right bottom)
			)
		)
		(property "Value" "R_15k_0402"
			(at -1.011843 1.772047 90)
			(layer "F.Fab")
			(effects
				(font
					(size 0.7 0.7)
					(thickness 0.15)
				)
				(justify right bottom)
			)
		)
		(property "Datasheet" "https://www.bourns.com/docs/product-datasheets/cr.pdf"
			(at 0 0 270)
			(layer "F.Fab")
			(hide yes)
			(effects
				(font
					(size 1.27 1.27)
					(thickness 0.15)
				)
			)
		)
		(property "Author" "Antmicro"
			(at 215.328999 410.201999 0)
			(layer "F.Fab")
			(hide yes)
			(effects
				(font
					(size 1 1)
					(thickness 0.15)
				)
			)
		)
		(property "License" "Apache-2.0"
			(at 215.328999 410.201999 0)
			(layer "F.Fab")
			(hide yes)
			(effects
				(font
					(size 1 1)
					(thickness 0.15)
				)
			)
		)
		(property "MPN" "CR0402-FX-1502GLF"
			(at 215.328999 410.201999 0)
			(layer "F.Fab")
			(hide yes)
			(effects
				(font
					(size 1 1)
					(thickness 0.15)
				)
			)
		)
		(property "Manufacturer" "Bourns"
			(at 215.328999 410.201999 0)
			(layer "F.Fab")
			(hide yes)
			(effects
				(font
					(size 1 1)
					(thickness 0.15)
				)
			)
		)
		(property "Public" "False"
			(at 215.328999 410.201999 0)
			(layer "F.Fab")
			(hide yes)
			(effects
				(font
					(size 1 1)
					(thickness 0.15)
				)
			)
		)
		(property "Tolerance" "1%"
			(at 215.328999 410.201999 0)
			(layer "F.Fab")
			(hide yes)
			(effects
				(font
					(size 1 1)
					(thickness 0.15)
				)
			)
		)
		(property "Val" "15k"
			(at 215.328999 410.201999 0)
			(layer "F.Fab")
			(hide yes)
			(effects
				(font
					(size 1 1)
					(thickness 0.15)
				)
			)
		)
		(sheetname "Power")
		(sheetfile "power.kicad_sch")
		(attr smd)
		(fp_rect
			(start -0.925 -0.47)
			(end 0.925 0.47)
			(stroke
				(width 0.05)
				(type default)
			)
			(fill no)
			(layer "F.CrtYd")
		)
		(fp_rect
			(start -0.5 -0.25)
			(end 0.5 0.25)
			(stroke
				(width 0.15)
				(type solid)
			)
			(fill no)
			(layer "F.Fab")
		)
		(pad "1" smd roundrect
			(at -0.48 0 270)
			(size 0.59 0.64)
			(layers "F.Cu" "F.Mask" "F.Paste")
			(roundrect_rratio 0.25)
			(net 584 "Net-(U21-EN)")
			(pintype "passive")
			(teardrops
				(best_length_ratio 0.2)
				(max_length 1)
				(best_width_ratio 0.9)
				(max_width 2)
				(curved_edges yes)
				(filter_ratio 0.9)
				(enabled yes)
				(allow_two_segments yes)
				(prefer_zone_connections yes)
			)
		)
		(pad "2" smd roundrect
			(at 0.48 0 270)
			(size 0.59 0.64)
			(layers "F.Cu" "F.Mask" "F.Paste")
			(roundrect_rratio 0.25)
			(net 62 "+12V_AON")
			(pintype "passive")
			(teardrops
				(best_length_ratio 0.2)
				(max_length 1)
				(best_width_ratio 0.9)
				(max_width 2)
				(curved_edges yes)
				(filter_ratio 0.9)
				(enabled yes)
				(allow_two_segments yes)
				(prefer_zone_connections yes)
			)
		)
	)
	(footprint "antmicro-footprints:R_0402_1005Metric"
		(layer "F.Cu")
		(at 113.4 150.36 -90)
		(descr "Resistor SMD 0402")
		(tags "resistor SMD 0402")
		(property "Reference" "R209"
			(at -0.46 -4.5 90)
			(layer "F.SilkS")
			(effects
				(font
					(size 0.7 0.7)
					(thickness 0.15)
				)
				(justify right bottom)
			)
		)
		(property "Value" "R_1k_0402"
			(at -1.011843 1.772047 90)
			(layer "F.Fab")
			(effects
				(font
					(size 0.7 0.7)
					(thickness 0.15)
				)
				(justify right bottom)
			)
		)
		(property "Datasheet" "https://www.bourns.com/docs/product-datasheets/cr.pdf"
			(at 0 0 270)
			(layer "F.Fab")
			(hide yes)
			(effects
				(font
					(size 1.27 1.27)
					(thickness 0.15)
				)
			)
		)
		(property "Author" "Antmicro"
			(at -36.96 263.76 0)
			(layer "F.Fab")
			(hide yes)
			(effects
				(font
					(size 1 1)
					(thickness 0.15)
				)
			)
		)
		(property "License" "Apache-2.0"
			(at -36.96 263.76 0)
			(layer "F.Fab")
			(hide yes)
			(effects
				(font
					(size 1 1)
					(thickness 0.15)
				)
			)
		)
		(property "MPN" "CR0402-FX-1001GLF"
			(at -36.96 263.76 0)
			(layer "F.Fab")
			(hide yes)
			(effects
				(font
					(size 1 1)
					(thickness 0.15)
				)
			)
		)
		(property "Manufacturer" "Bourns"
			(at -36.96 263.76 0)
			(layer "F.Fab")
			(hide yes)
			(effects
				(font
					(size 1 1)
					(thickness 0.15)
				)
			)
		)
		(property "Public" "False"
			(at -36.96 263.76 0)
			(layer "F.Fab")
			(hide yes)
			(effects
				(font
					(size 1 1)
					(thickness 0.15)
				)
			)
		)
		(property "Tolerance" "1%"
			(at -36.96 263.76 0)
			(layer "F.Fab")
			(hide yes)
			(effects
				(font
					(size 1 1)
					(thickness 0.15)
				)
			)
		)
		(property "Val" "1k"
			(at -36.96 263.76 0)
			(layer "F.Fab")
			(hide yes)
			(effects
				(font
					(size 1 1)
					(thickness 0.15)
				)
			)
		)
		(sheetname "PCIe redriver")
		(sheetfile "pcie_redriver.kicad_sch")
		(attr smd)
		(fp_rect
			(start -0.925 -0.47)
			(end 0.925 0.47)
			(stroke
				(width 0.05)
				(type default)
			)
			(fill no)
			(layer "F.CrtYd")
		)
		(fp_rect
			(start -0.5 -0.25)
			(end 0.5 0.25)
			(stroke
				(width 0.15)
				(type solid)
			)
			(fill no)
			(layer "F.Fab")
		)
		(pad "1" smd roundrect
			(at -0.48 0 270)
			(size 0.59 0.64)
			(layers "F.Cu" "F.Mask" "F.Paste")
			(roundrect_rratio 0.25)
			(net 1 "GND")
			(pintype "passive")
			(teardrops
				(best_length_ratio 0.2)
				(max_length 1)
				(best_width_ratio 0.9)
				(max_width 2)
				(curved_edges yes)
				(filter_ratio 0.9)
				(enabled yes)
				(allow_two_segments yes)
				(prefer_zone_connections yes)
			)
		)
		(pad "2" smd roundrect
			(at 0.48 0 270)
			(size 0.59 0.64)
			(layers "F.Cu" "F.Mask" "F.Paste")
			(roundrect_rratio 0.25)
			(net 626 "/PCIe redriver/TX_FG0")
			(pintype "passive")
			(teardrops
				(best_length_ratio 0.2)
				(max_length 1)
				(best_width_ratio 0.9)
				(max_width 2)
				(curved_edges yes)
				(filter_ratio 0.9)
				(enabled yes)
				(allow_two_segments yes)
				(prefer_zone_connections yes)
			)
		)
	)
	(footprint "antmicro-footprints:SOD-123FL"
		(layer "F.Cu")
		(at 308.5 149.11 -90)
		(property "Reference" "D24"
			(at -2.5 -0.8 180)
			(layer "F.SilkS")
			(effects
				(font
					(size 0.7 0.7)
					(thickness 0.15)
				)
				(justify right bottom)
			)
		)
		(property "Value" "SMF4L15A"
			(at 0 1.967 90)
			(layer "F.Fab")
			(effects
				(font
					(size 0.7 0.7)
					(thickness 0.15)
				)
				(justify right bottom)
			)
		)
		(property "Datasheet" "https://www.littelfuse.com/media?resourcetype=datasheets&itemid=d2ba8fab-1de3-4176-8530-f36ecb0b8799&filename=smf4l"
			(at 0 0 270)
			(layer "F.Fab")
			(hide yes)
			(effects
				(font
					(size 1.27 1.27)
					(thickness 0.15)
				)
			)
		)
		(property "Author" "Antmicro"
			(at 159.39 457.61 0)
			(layer "F.Fab")
			(hide yes)
			(effects
				(font
					(size 1 1)
					(thickness 0.15)
				)
			)
		)
		(property "License" "Apache-2.0"
			(at 159.39 457.61 0)
			(layer "F.Fab")
			(hide yes)
			(effects
				(font
					(size 1 1)
					(thickness 0.15)
				)
			)
		)
		(property "MPN" "SMF4L15A"
			(at 159.39 457.61 0)
			(layer "F.Fab")
			(hide yes)
			(effects
				(font
					(size 1 1)
					(thickness 0.15)
				)
			)
		)
		(property "Manufacturer" "Littelfuse"
			(at 159.39 457.61 0)
			(layer "F.Fab")
			(hide yes)
			(effects
				(font
					(size 1 1)
					(thickness 0.15)
				)
			)
		)
		(property "Public" "False"
			(at 159.39 457.61 0)
			(layer "F.Fab")
			(hide yes)
			(effects
				(font
					(size 1 1)
					(thickness 0.15)
				)
			)
		)
		(sheetname "Power")
		(sheetfile "power.kicad_sch")
		(attr smd)
		(fp_line
			(start -2.3 1.1)
			(end 0 1.1)
			(stroke
				(width 0.15)
				(type solid)
			)
			(layer "F.SilkS")
		)
		(fp_line
			(start -2.3 -1.1)
			(end -2.3 1.1)
			(stroke
				(width 0.15)
				(type solid)
			)
			(layer "F.SilkS")
		)
		(fp_line
			(start 0 -1.1)
			(end -2.3 -1.1)
			(stroke
				(width 0.15)
				(type solid)
			)
			(layer "F.SilkS")
		)
		(fp_rect
			(start -2.35 -1.125)
			(end 2.35 1.125)
			(stroke
				(width 0.05)
				(type solid)
			)
			(fill no)
			(layer "F.CrtYd")
		)
		(fp_rect
			(start -1.825 -0.875)
			(end 1.824 0.873)
			(stroke
				(width 0.15)
				(type solid)
			)
			(fill no)
			(layer "F.Fab")
		)
		(fp_rect
			(start -0.775 -0.875)
			(end -0.525 0.875)
			(stroke
				(width 0.15)
				(type solid)
			)
			(fill yes)
			(layer "F.Fab")
		)
		(pad "1" smd roundrect
			(at -1.43 0 270)
			(size 1.34 1.8)
			(layers "F.Cu" "F.Mask" "F.Paste")
			(roundrect_rratio 0.14)
			(net 145 "Net-(D24-C)")
			(pinfunction "C")
			(pintype "passive")
			(teardrops
				(best_length_ratio 0.2)
				(max_length 1)
				(best_width_ratio 0.9)
				(max_width 2)
				(curved_edges yes)
				(filter_ratio 0.9)
				(enabled yes)
				(allow_two_segments yes)
				(prefer_zone_connections yes)
			)
		)
		(pad "2" smd roundrect
			(at 1.429 0 270)
			(size 1.34 1.8)
			(layers "F.Cu" "F.Mask" "F.Paste")
			(roundrect_rratio 0.14)
			(net 1 "GND")
			(pinfunction "A")
			(pintype "passive")
			(teardrops
				(best_length_ratio 0.2)
				(max_length 1)
				(best_width_ratio 0.9)
				(max_width 2)
				(curved_edges yes)
				(filter_ratio 0.9)
				(enabled yes)
				(allow_two_segments yes)
				(prefer_zone_connections yes)
			)
		)
	)
	(footprint "antmicro-footprints:C_0402_1005Metric"
		(layer "F.Cu")
		(at 304.85 146.61 180)
		(descr "Capacitor SMD 0402")
		(tags "capacitor SMD 0402")
		(property "Reference" "C203"
			(at -1.35 0.5 0)
			(layer "F.SilkS")
			(effects
				(font
					(size 0.7 0.7)
					(thickness 0.15)
				)
				(justify right bottom)
			)
		)
		(property "Value" "C_100n_0402"
			(at -1.022927 2.155213 0)
			(layer "F.Fab")
			(effects
				(font
					(size 0.7 0.7)
					(thickness 0.15)
				)
				(justify right bottom)
			)
		)
		(property "Datasheet" "https://www.murata.com/products/productdetail?partno=GRM155R61H104KE14%23"
			(at 0 0 180)
			(layer "F.Fab")
			(hide yes)
			(effects
				(font
					(size 1.27 1.27)
					(thickness 0.15)
				)
			)
		)
		(property "Author" "Antmicro"
			(at 609.7 293.22 0)
			(layer "F.Fab")
			(hide yes)
			(effects
				(font
					(size 1 1)
					(thickness 0.15)
				)
			)
		)
		(property "Dielectric" "X5R"
			(at 609.7 293.22 0)
			(layer "F.Fab")
			(hide yes)
			(effects
				(font
					(size 1 1)
					(thickness 0.15)
				)
			)
		)
		(property "License" "Apache-2.0"
			(at 609.7 293.22 0)
			(layer "F.Fab")
			(hide yes)
			(effects
				(font
					(size 1 1)
					(thickness 0.15)
				)
			)
		)
		(property "MPN" "GRM155R61H104KE14D"
			(at 609.7 293.22 0)
			(layer "F.Fab")
			(hide yes)
			(effects
				(font
					(size 1 1)
					(thickness 0.15)
				)
			)
		)
		(property "Manufacturer" "Murata"
			(at 609.7 293.22 0)
			(layer "F.Fab")
			(hide yes)
			(effects
				(font
					(size 1 1)
					(thickness 0.15)
				)
			)
		)
		(property "Public" "False"
			(at 609.7 293.22 0)
			(layer "F.Fab")
			(hide yes)
			(effects
				(font
					(size 1 1)
					(thickness 0.15)
				)
			)
		)
		(property "Val" "100n"
			(at 609.7 293.22 0)
			(layer "F.Fab")
			(hide yes)
			(effects
				(font
					(size 1 1)
					(thickness 0.15)
				)
			)
		)
		(property "Voltage" "50V"
			(at 609.7 293.22 0)
			(layer "F.Fab")
			(hide yes)
			(effects
				(font
					(size 1 1)
					(thickness 0.15)
				)
			)
		)
		(sheetname "Power")
		(sheetfile "power.kicad_sch")
		(attr smd)
		(fp_rect
			(start -0.925 -0.47)
			(end 0.925 0.47)
			(stroke
				(width 0.05)
				(type default)
			)
			(fill no)
			(layer "F.CrtYd")
		)
		(fp_line
			(start 0.504 0.248)
			(end -0.494 0.248)
			(stroke
				(width 0.15)
				(type solid)
			)
			(layer "F.Fab")
		)
		(fp_line
			(start 0.504 -0.25)
			(end 0.504 0.248)
			(stroke
				(width 0.15)
				(type solid)
			)
			(layer "F.Fab")
		)
		(fp_line
			(start -0.494 0.248)
			(end -0.494 -0.25)
			(stroke
				(width 0.15)
				(type solid)
			)
			(layer "F.Fab")
		)
		(fp_line
			(start -0.494 -0.25)
			(end 0.504 -0.25)
			(stroke
				(width 0.15)
				(type solid)
			)
			(layer "F.Fab")
		)
		(pad "1" smd roundrect
			(at -0.48 0 180)
			(size 0.59 0.64)
			(layers "F.Cu" "F.Mask" "F.Paste")
			(roundrect_rratio 0.25)
			(net 1 "GND")
			(pintype "passive")
			(teardrops
				(best_length_ratio 0.2)
				(max_length 1)
				(best_width_ratio 0.9)
				(max_width 2)
				(curved_edges yes)
				(filter_ratio 0.9)
				(enabled yes)
				(allow_two_segments yes)
				(prefer_zone_connections yes)
			)
		)
		(pad "2" smd roundrect
			(at 0.48 0 180)
			(size 0.59 0.64)
			(layers "F.Cu" "F.Mask" "F.Paste")
			(roundrect_rratio 0.25)
			(net 73 "+3V3_AON")
			(pintype "passive")
			(teardrops
				(best_length_ratio 0.2)
				(max_length 1)
				(best_width_ratio 0.9)
				(max_width 2)
				(curved_edges yes)
				(filter_ratio 0.9)
				(enabled yes)
				(allow_two_segments yes)
				(prefer_zone_connections yes)
			)
		)
	)
	(footprint "antmicro-footprints:C_0603_1608Metric"
		(layer "F.Cu")
		(at 314.224999 103.15 -90)
		(descr "Capacitor SMD 0603")
		(tags "capacitor 0603")
		(property "Reference" "C40"
			(at -3.34 -0.425001 90)
			(layer "F.SilkS")
			(effects
				(font
					(size 0.7 0.7)
					(thickness 0.15)
				)
				(justify right bottom)
			)
		)
		(property "Value" "C_22u_16V_0603"
			(at -1.42757 1.770288 90)
			(layer "F.Fab")
			(effects
				(font
					(size 0.7 0.7)
					(thickness 0.15)
				)
				(justify right bottom)
			)
		)
		(property "Datasheet" "https://product.samsungsem.com/mlcc/CL10A226MO7JZN.do"
			(at 0 0 270)
			(layer "F.Fab")
			(hide yes)
			(effects
				(font
					(size 1.27 1.27)
					(thickness 0.15)
				)
			)
		)
		(property "Author" "Antmicro"
			(at 211.074999 417.374999 0)
			(layer "F.Fab")
			(hide yes)
			(effects
				(font
					(size 1 1)
					(thickness 0.15)
				)
			)
		)
		(property "Dielectric" ""
			(at 211.074999 417.374999 0)
			(layer "F.Fab")
			(hide yes)
			(effects
				(font
					(size 1 1)
					(thickness 0.15)
				)
			)
		)
		(property "License" "Apache-2.0"
			(at 211.074999 417.374999 0)
			(layer "F.Fab")
			(hide yes)
			(effects
				(font
					(size 1 1)
					(thickness 0.15)
				)
			)
		)
		(property "MPN" "CL10A226MO7JZNC"
			(at 211.074999 417.374999 0)
			(layer "F.Fab")
			(hide yes)
			(effects
				(font
					(size 1 1)
					(thickness 0.15)
				)
			)
		)
		(property "Manufacturer" "Samsung Electro-Mechanics"
			(at 211.074999 417.374999 0)
			(layer "F.Fab")
			(hide yes)
			(effects
				(font
					(size 1 1)
					(thickness 0.15)
				)
			)
		)
		(property "Public" "False"
			(at 211.074999 417.374999 0)
			(layer "F.Fab")
			(hide yes)
			(effects
				(font
					(size 1 1)
					(thickness 0.15)
				)
			)
		)
		(property "Val" "22u"
			(at 211.074999 417.374999 0)
			(layer "F.Fab")
			(hide yes)
			(effects
				(font
					(size 1 1)
					(thickness 0.15)
				)
			)
		)
		(property "Voltage" "16V"
			(at 211.074999 417.374999 0)
			(layer "F.Fab")
			(hide yes)
			(effects
				(font
					(size 1 1)
					(thickness 0.15)
				)
			)
		)
		(sheetname "Power")
		(sheetfile "power.kicad_sch")
		(attr smd)
		(fp_line
			(start -0.15 0.4)
			(end 0.15 0.4)
			(stroke
				(width 0.15)
				(type solid)
			)
			(layer "F.SilkS")
		)
		(fp_line
			(start -0.15 -0.4)
			(end 0.15 -0.4)
			(stroke
				(width 0.15)
				(type solid)
			)
			(layer "F.SilkS")
		)
		(fp_rect
			(start -1.25 -0.65)
			(end 1.25 0.65)
			(stroke
				(width 0.05)
				(type solid)
			)
			(fill no)
			(layer "F.CrtYd")
		)
		(fp_rect
			(start -0.8 -0.4)
			(end 0.8 0.4)
			(stroke
				(width 0.15)
				(type solid)
			)
			(fill no)
			(layer "F.Fab")
		)
		(pad "1" smd roundrect
			(at -0.7 0 270)
			(size 0.8 1)
			(layers "F.Cu" "F.Mask" "F.Paste")
			(roundrect_rratio 0.2)
			(net 1 "GND")
			(pintype "passive")
			(teardrops
				(best_length_ratio 0.2)
				(max_length 1)
				(best_width_ratio 0.9)
				(max_width 2)
				(curved_edges yes)
				(filter_ratio 0.9)
				(enabled yes)
				(allow_two_segments yes)
				(prefer_zone_connections yes)
			)
		)
		(pad "2" smd roundrect
			(at 0.7 0 270)
			(size 0.8 1)
			(layers "F.Cu" "F.Mask" "F.Paste")
			(roundrect_rratio 0.2)
			(net 62 "+12V_AON")
			(pintype "passive")
			(teardrops
				(best_length_ratio 0.2)
				(max_length 1)
				(best_width_ratio 0.9)
				(max_width 2)
				(curved_edges yes)
				(filter_ratio 0.9)
				(enabled yes)
				(allow_two_segments yes)
				(prefer_zone_connections yes)
			)
		)
	)
	(footprint "antmicro-footprints:R_0402_1005Metric"
		(layer "F.Cu")
		(at 112.4 150.36 -90)
		(descr "Resistor SMD 0402")
		(tags "resistor SMD 0402")
		(property "Reference" "R211"
			(at -0.46 -4.5 90)
			(layer "F.SilkS")
			(effects
				(font
					(size 0.7 0.7)
					(thickness 0.15)
				)
				(justify right bottom)
			)
		)
		(property "Value" "R_1k_0402"
			(at -1.011843 1.772047 90)
			(layer "F.Fab")
			(effects
				(font
					(size 0.7 0.7)
					(thickness 0.15)
				)
				(justify right bottom)
			)
		)
		(property "Datasheet" "https://www.bourns.com/docs/product-datasheets/cr.pdf"
			(at 0 0 270)
			(layer "F.Fab")
			(hide yes)
			(effects
				(font
					(size 1.27 1.27)
					(thickness 0.15)
				)
			)
		)
		(property "Author" "Antmicro"
			(at -37.96 262.76 0)
			(layer "F.Fab")
			(hide yes)
			(effects
				(font
					(size 1 1)
					(thickness 0.15)
				)
			)
		)
		(property "License" "Apache-2.0"
			(at -37.96 262.76 0)
			(layer "F.Fab")
			(hide yes)
			(effects
				(font
					(size 1 1)
					(thickness 0.15)
				)
			)
		)
		(property "MPN" "CR0402-FX-1001GLF"
			(at -37.96 262.76 0)
			(layer "F.Fab")
			(hide yes)
			(effects
				(font
					(size 1 1)
					(thickness 0.15)
				)
			)
		)
		(property "Manufacturer" "Bourns"
			(at -37.96 262.76 0)
			(layer "F.Fab")
			(hide yes)
			(effects
				(font
					(size 1 1)
					(thickness 0.15)
				)
			)
		)
		(property "Public" "False"
			(at -37.96 262.76 0)
			(layer "F.Fab")
			(hide yes)
			(effects
				(font
					(size 1 1)
					(thickness 0.15)
				)
			)
		)
		(property "Tolerance" "1%"
			(at -37.96 262.76 0)
			(layer "F.Fab")
			(hide yes)
			(effects
				(font
					(size 1 1)
					(thickness 0.15)
				)
			)
		)
		(property "Val" "1k"
			(at -37.96 262.76 0)
			(layer "F.Fab")
			(hide yes)
			(effects
				(font
					(size 1 1)
					(thickness 0.15)
				)
			)
		)
		(sheetname "PCIe redriver")
		(sheetfile "pcie_redriver.kicad_sch")
		(attr smd dnp)
		(fp_rect
			(start -0.925 -0.47)
			(end 0.925 0.47)
			(stroke
				(width 0.05)
				(type default)
			)
			(fill no)
			(layer "F.CrtYd")
		)
		(fp_rect
			(start -0.5 -0.25)
			(end 0.5 0.25)
			(stroke
				(width 0.15)
				(type solid)
			)
			(fill no)
			(layer "F.Fab")
		)
		(pad "1" smd roundrect
			(at -0.48 0 270)
			(size 0.59 0.64)
			(layers "F.Cu" "F.Mask" "F.Paste")
			(roundrect_rratio 0.25)
			(net 1 "GND")
			(pintype "passive")
			(teardrops
				(best_length_ratio 0.2)
				(max_length 1)
				(best_width_ratio 0.9)
				(max_width 2)
				(curved_edges yes)
				(filter_ratio 0.9)
				(enabled yes)
				(allow_two_segments yes)
				(prefer_zone_connections yes)
			)
		)
		(pad "2" smd roundrect
			(at 0.48 0 270)
			(size 0.59 0.64)
			(layers "F.Cu" "F.Mask" "F.Paste")
			(roundrect_rratio 0.25)
			(net 627 "/PCIe redriver/TX_FG1")
			(pintype "passive")
			(teardrops
				(best_length_ratio 0.2)
				(max_length 1)
				(best_width_ratio 0.9)
				(max_width 2)
				(curved_edges yes)
				(filter_ratio 0.9)
				(enabled yes)
				(allow_two_segments yes)
				(prefer_zone_connections yes)
			)
		)
	)
	(footprint "antmicro-footprints:R_0201"
		(layer "F.Cu")
		(at 128.41 147.935 -90)
		(descr "Resistor SMD 0201")
		(tags "resistor SMD 0201")
		(property "Reference" "R312"
			(at 3.6 -0.29 90)
			(layer "F.SilkS")
			(effects
				(font
					(size 0.7 0.7)
					(thickness 0.15)
				)
				(justify right bottom)
			)
		)
		(property "Value" "R_0R_0201"
			(at 0 1.25 90)
			(layer "F.Fab")
			(effects
				(font
					(size 0.7 0.7)
					(thickness 0.15)
				)
				(justify right bottom)
			)
		)
		(property "Datasheet" "https://www.bourns.com/docs/product-datasheets/cr.pdf"
			(at 0 0 270)
			(layer "F.Fab")
			(hide yes)
			(effects
				(font
					(size 1.27 1.27)
					(thickness 0.15)
				)
			)
		)
		(property "Author" "Antmicro"
			(at -19.525 276.345 0)
			(layer "F.Fab")
			(hide yes)
			(effects
				(font
					(size 1 1)
					(thickness 0.15)
				)
			)
		)
		(property "License" "Apache-2.0"
			(at -19.525 276.345 0)
			(layer "F.Fab")
			(hide yes)
			(effects
				(font
					(size 1 1)
					(thickness 0.15)
				)
			)
		)
		(property "MPN" "CR0201-FX-0R00GLF"
			(at -19.525 276.345 0)
			(layer "F.Fab")
			(hide yes)
			(effects
				(font
					(size 1 1)
					(thickness 0.15)
				)
			)
		)
		(property "Manufacturer" "Bourns"
			(at -19.525 276.345 0)
			(layer "F.Fab")
			(hide yes)
			(effects
				(font
					(size 1 1)
					(thickness 0.15)
				)
			)
		)
		(property "Tolerance" "1%"
			(at -19.525 276.345 0)
			(layer "F.Fab")
			(hide yes)
			(effects
				(font
					(size 1 1)
					(thickness 0.15)
				)
			)
		)
		(property "Val" "0R"
			(at -19.525 276.345 0)
			(layer "F.Fab")
			(hide yes)
			(effects
				(font
					(size 1 1)
					(thickness 0.15)
				)
			)
		)
		(sheetname "KR to SFI #2")
		(sheetfile "kr_sfi.kicad_sch")
		(attr smd dnp)
		(fp_rect
			(start -0.7 -0.35)
			(end 0.7 0.35)
			(stroke
				(width 0.05)
				(type default)
			)
			(fill no)
			(layer "F.CrtYd")
		)
		(fp_rect
			(start -0.3 -0.15)
			(end 0.298 0.148)
			(stroke
				(width 0.15)
				(type solid)
			)
			(fill no)
			(layer "F.Fab")
		)
		(pad "" smd roundrect
			(at -0.346 0 270)
			(size 0.318 0.36)
			(layers "F.Paste")
			(roundrect_rratio 0.25)
			(teardrops
				(best_length_ratio 0.2)
				(max_length 1)
				(best_width_ratio 0.9)
				(max_width 2)
				(curved_edges yes)
				(filter_ratio 0.9)
				(enabled yes)
				(allow_two_segments yes)
				(prefer_zone_connections yes)
			)
		)
		(pad "" smd roundrect
			(at 0.344 0 270)
			(size 0.318 0.36)
			(layers "F.Paste")
			(roundrect_rratio 0.25)
			(teardrops
				(best_length_ratio 0.2)
				(max_length 1)
				(best_width_ratio 0.9)
				(max_width 2)
				(curved_edges yes)
				(filter_ratio 0.9)
				(enabled yes)
				(allow_two_segments yes)
				(prefer_zone_connections yes)
			)
		)
		(pad "1" smd roundrect
			(at -0.32 0 270)
			(size 0.46 0.4)
			(layers "F.Cu" "F.Mask")
			(roundrect_rratio 0.25)
			(net 880 "/2xSFP+/SFI1.TX-")
			(pintype "passive")
			(teardrops
				(best_length_ratio 0.2)
				(max_length 1)
				(best_width_ratio 0.9)
				(max_width 2)
				(curved_edges yes)
				(filter_ratio 0.9)
				(enabled yes)
				(allow_two_segments yes)
				(prefer_zone_connections yes)
			)
		)
		(pad "2" smd roundrect
			(at 0.32 0 270)
			(size 0.46 0.4)
			(layers "F.Cu" "F.Mask")
			(roundrect_rratio 0.25)
			(net 951 "/2xSFP+/KR to SFI #2/BYP_TX-")
			(pintype "passive")
			(teardrops
				(best_length_ratio 0.2)
				(max_length 1)
				(best_width_ratio 0.9)
				(max_width 2)
				(curved_edges yes)
				(filter_ratio 0.9)
				(enabled yes)
				(allow_two_segments yes)
				(prefer_zone_connections yes)
			)
		)
	)
	(footprint "antmicro-footprints:TP_SMD_0.75mm"
		(layer "F.Cu")
		(at 133.64 128.71)
		(property "Reference" "TP80"
			(at 0.51 -3.3 90)
			(layer "F.SilkS")
			(effects
				(font
					(size 0.7 0.7)
					(thickness 0.15)
				)
				(justify left bottom)
			)
		)
		(property "Value" "TP_0.75mm_SMD"
			(at 0 1.2 0)
			(layer "F.Fab")
			(effects
				(font
					(size 0.7 0.7)
					(thickness 0.15)
				)
				(justify left bottom)
			)
		)
		(property "Author" "Antmicro"
			(at 0 0 0)
			(layer "F.Fab")
			(hide yes)
			(effects
				(font
					(size 1 1)
					(thickness 0.15)
				)
			)
		)
		(property "License" "Apache-2.0"
			(at 0 0 0)
			(layer "F.Fab")
			(hide yes)
			(effects
				(font
					(size 1 1)
					(thickness 0.15)
				)
			)
		)
		(property "MPN" ""
			(at 0 0 0)
			(layer "F.Fab")
			(hide yes)
			(effects
				(font
					(size 1 1)
					(thickness 0.15)
				)
			)
		)
		(property "Manufacturer" ""
			(at 0 0 0)
			(layer "F.Fab")
			(hide yes)
			(effects
				(font
					(size 1 1)
					(thickness 0.15)
				)
			)
		)
		(property "Public" "False"
			(at 0 0 0)
			(layer "F.Fab")
			(hide yes)
			(effects
				(font
					(size 1 1)
					(thickness 0.15)
				)
			)
		)
		(sheetname "KR to SFI #2")
		(sheetfile "kr_sfi.kicad_sch")
		(attr exclude_from_pos_files exclude_from_bom)
		(fp_circle
			(center 0 0)
			(end 0.475 0)
			(stroke
				(width 0.05)
				(type default)
			)
			(fill no)
			(layer "F.CrtYd")
		)
		(pad "1" smd circle
			(at 0 0)
			(size 0.75 0.75)
			(layers "F.Cu" "F.Mask")
			(net 743 "/2xSFP+/KR to SFI #2/TDO")
			(pinfunction "1")
			(pintype "passive")
			(teardrops
				(best_length_ratio 0.4)
				(max_length 1)
				(best_width_ratio 0.9)
				(max_width 2)
				(curved_edges yes)
				(filter_ratio 0.9)
				(enabled yes)
				(allow_two_segments yes)
				(prefer_zone_connections yes)
			)
		)
	)
	(footprint "antmicro-footprints:C_0402_1005Metric"
		(layer "F.Cu")
		(at 241.75 128.31 -90)
		(descr "Capacitor SMD 0402")
		(tags "capacitor SMD 0402")
		(property "Reference" "C207"
			(at -1.5 0.5 90)
			(layer "F.SilkS")
			(effects
				(font
					(size 0.7 0.7)
					(thickness 0.15)
				)
				(justify right bottom)
			)
		)
		(property "Value" "C_100n_0402"
			(at -1.022927 2.155213 90)
			(layer "F.Fab")
			(effects
				(font
					(size 0.7 0.7)
					(thickness 0.15)
				)
				(justify right bottom)
			)
		)
		(property "Datasheet" "https://www.murata.com/products/productdetail?partno=GRM155R61H104KE14%23"
			(at 0 0 270)
			(layer "F.Fab")
			(hide yes)
			(effects
				(font
					(size 1.27 1.27)
					(thickness 0.15)
				)
			)
		)
		(property "Author" "Antmicro"
			(at 113.44 370.06 0)
			(layer "F.Fab")
			(hide yes)
			(effects
				(font
					(size 1 1)
					(thickness 0.15)
				)
			)
		)
		(property "Dielectric" "X5R"
			(at 113.44 370.06 0)
			(layer "F.Fab")
			(hide yes)
			(effects
				(font
					(size 1 1)
					(thickness 0.15)
				)
			)
		)
		(property "License" "Apache-2.0"
			(at 113.44 370.06 0)
			(layer "F.Fab")
			(hide yes)
			(effects
				(font
					(size 1 1)
					(thickness 0.15)
				)
			)
		)
		(property "MPN" "GRM155R61H104KE14D"
			(at 113.44 370.06 0)
			(layer "F.Fab")
			(hide yes)
			(effects
				(font
					(size 1 1)
					(thickness 0.15)
				)
			)
		)
		(property "Manufacturer" "Murata"
			(at 113.44 370.06 0)
			(layer "F.Fab")
			(hide yes)
			(effects
				(font
					(size 1 1)
					(thickness 0.15)
				)
			)
		)
		(property "Public" "False"
			(at 113.44 370.06 0)
			(layer "F.Fab")
			(hide yes)
			(effects
				(font
					(size 1 1)
					(thickness 0.15)
				)
			)
		)
		(property "Val" "100n"
			(at 113.44 370.06 0)
			(layer "F.Fab")
			(hide yes)
			(effects
				(font
					(size 1 1)
					(thickness 0.15)
				)
			)
		)
		(property "Voltage" "50V"
			(at 113.44 370.06 0)
			(layer "F.Fab")
			(hide yes)
			(effects
				(font
					(size 1 1)
					(thickness 0.15)
				)
			)
		)
		(sheetname "Com Express 7 MGMT")
		(sheetfile "com_express_7_mgmt.kicad_sch")
		(attr smd dnp)
		(fp_rect
			(start -0.925 -0.47)
			(end 0.925 0.47)
			(stroke
				(width 0.05)
				(type default)
			)
			(fill no)
			(layer "F.CrtYd")
		)
		(fp_line
			(start -0.494 0.248)
			(end -0.494 -0.25)
			(stroke
				(width 0.15)
				(type solid)
			)
			(layer "F.Fab")
		)
		(fp_line
			(start 0.504 0.248)
			(end -0.494 0.248)
			(stroke
				(width 0.15)
				(type solid)
			)
			(layer "F.Fab")
		)
		(fp_line
			(start -0.494 -0.25)
			(end 0.504 -0.25)
			(stroke
				(width 0.15)
				(type solid)
			)
			(layer "F.Fab")
		)
		(fp_line
			(start 0.504 -0.25)
			(end 0.504 0.248)
			(stroke
				(width 0.15)
				(type solid)
			)
			(layer "F.Fab")
		)
		(pad "1" smd roundrect
			(at -0.48 0 270)
			(size 0.59 0.64)
			(layers "F.Cu" "F.Mask" "F.Paste")
			(roundrect_rratio 0.25)
			(net 1 "GND")
			(pintype "passive")
			(teardrops
				(best_length_ratio 0.2)
				(max_length 1)
				(best_width_ratio 0.9)
				(max_width 2)
				(curved_edges yes)
				(filter_ratio 0.9)
				(enabled yes)
				(allow_two_segments yes)
				(prefer_zone_connections yes)
			)
		)
		(pad "2" smd roundrect
			(at 0.48 0 270)
			(size 0.59 0.64)
			(layers "F.Cu" "F.Mask" "F.Paste")
			(roundrect_rratio 0.25)
			(net 48 "Net-(U34-ONT)")
			(pintype "passive")
			(teardrops
				(best_length_ratio 0.2)
				(max_length 1)
				(best_width_ratio 0.9)
				(max_width 2)
				(curved_edges yes)
				(filter_ratio 0.9)
				(enabled yes)
				(allow_two_segments yes)
				(prefer_zone_connections yes)
			)
		)
	)
	(footprint "antmicro-footprints:R_0402_1005Metric"
		(layer "F.Cu")
		(at 211.28 127.09 180)
		(descr "Resistor SMD 0402")
		(tags "resistor SMD 0402")
		(property "Reference" "R182"
			(at 0.83 -0.12 0)
			(layer "F.SilkS")
			(effects
				(font
					(size 0.7 0.7)
					(thickness 0.15)
				)
				(justify right bottom)
			)
		)
		(property "Value" "R_1k_0402"
			(at -1.011843 1.772047 0)
			(layer "F.Fab")
			(effects
				(font
					(size 0.7 0.7)
					(thickness 0.15)
				)
				(justify right bottom)
			)
		)
		(property "Datasheet" "https://www.bourns.com/docs/product-datasheets/cr.pdf"
			(at 0 0 180)
			(layer "F.Fab")
			(hide yes)
			(effects
				(font
					(size 1.27 1.27)
					(thickness 0.15)
				)
			)
		)
		(property "Author" "Antmicro"
			(at 422.56 254.18 0)
			(layer "F.Fab")
			(hide yes)
			(effects
				(font
					(size 1 1)
					(thickness 0.15)
				)
			)
		)
		(property "License" "Apache-2.0"
			(at 422.56 254.18 0)
			(layer "F.Fab")
			(hide yes)
			(effects
				(font
					(size 1 1)
					(thickness 0.15)
				)
			)
		)
		(property "MPN" "CR0402-FX-1001GLF"
			(at 422.56 254.18 0)
			(layer "F.Fab")
			(hide yes)
			(effects
				(font
					(size 1 1)
					(thickness 0.15)
				)
			)
		)
		(property "Manufacturer" "Bourns"
			(at 422.56 254.18 0)
			(layer "F.Fab")
			(hide yes)
			(effects
				(font
					(size 1 1)
					(thickness 0.15)
				)
			)
		)
		(property "Public" "False"
			(at 422.56 254.18 0)
			(layer "F.Fab")
			(hide yes)
			(effects
				(font
					(size 1 1)
					(thickness 0.15)
				)
			)
		)
		(property "Tolerance" "1%"
			(at 422.56 254.18 0)
			(layer "F.Fab")
			(hide yes)
			(effects
				(font
					(size 1 1)
					(thickness 0.15)
				)
			)
		)
		(property "Val" "1k"
			(at 422.56 254.18 0)
			(layer "F.Fab")
			(hide yes)
			(effects
				(font
					(size 1 1)
					(thickness 0.15)
				)
			)
		)
		(sheetname "PCIe misc")
		(sheetfile "pcie_misc.kicad_sch")
		(attr smd)
		(fp_rect
			(start -0.925 -0.47)
			(end 0.925 0.47)
			(stroke
				(width 0.05)
				(type default)
			)
			(fill no)
			(layer "F.CrtYd")
		)
		(fp_rect
			(start -0.5 -0.25)
			(end 0.5 0.25)
			(stroke
				(width 0.15)
				(type solid)
			)
			(fill no)
			(layer "F.Fab")
		)
		(pad "1" smd roundrect
			(at -0.48 0 180)
			(size 0.59 0.64)
			(layers "F.Cu" "F.Mask" "F.Paste")
			(roundrect_rratio 0.25)
			(net 602 "Net-(U37-~{OE0})")
			(pintype "passive")
			(teardrops
				(best_length_ratio 0.2)
				(max_length 1)
				(best_width_ratio 0.9)
				(max_width 2)
				(curved_edges yes)
				(filter_ratio 0.9)
				(enabled yes)
				(allow_two_segments yes)
				(prefer_zone_connections yes)
			)
		)
		(pad "2" smd roundrect
			(at 0.48 0 180)
			(size 0.59 0.64)
			(layers "F.Cu" "F.Mask" "F.Paste")
			(roundrect_rratio 0.25)
			(net 1 "GND")
			(pintype "passive")
			(teardrops
				(best_length_ratio 0.2)
				(max_length 1)
				(best_width_ratio 0.9)
				(max_width 2)
				(curved_edges yes)
				(filter_ratio 0.9)
				(enabled yes)
				(allow_two_segments yes)
				(prefer_zone_connections yes)
			)
		)
	)
	(footprint "antmicro-footprints:C_0402_1005Metric"
		(layer "F.Cu")
		(at 300.55 95.31 -90)
		(descr "Capacitor SMD 0402")
		(tags "capacitor SMD 0402")
		(property "Reference" "C67"
			(at -1.15 0.5 90)
			(layer "F.SilkS")
			(effects
				(font
					(size 0.7 0.7)
					(thickness 0.15)
				)
				(justify right bottom)
			)
		)
		(property "Value" "C_1u_0402"
			(at -1.022927 2.155213 90)
			(layer "F.Fab")
			(effects
				(font
					(size 0.7 0.7)
					(thickness 0.15)
				)
				(justify right bottom)
			)
		)
		(property "Datasheet" "https://product.tdk.com/en/search/capacitor/ceramic/mlcc/info?part_no=C1005X6S1A105K050BC"
			(at 0 0 270)
			(layer "F.Fab")
			(hide yes)
			(effects
				(font
					(size 1.27 1.27)
					(thickness 0.15)
				)
			)
		)
		(property "Author" "Antmicro"
			(at 205.24 395.86 0)
			(layer "F.Fab")
			(hide yes)
			(effects
				(font
					(size 1 1)
					(thickness 0.15)
				)
			)
		)
		(property "Dielectric" ""
			(at 205.24 395.86 0)
			(layer "F.Fab")
			(hide yes)
			(effects
				(font
					(size 1 1)
					(thickness 0.15)
				)
			)
		)
		(property "License" "Apache-2.0"
			(at 205.24 395.86 0)
			(layer "F.Fab")
			(hide yes)
			(effects
				(font
					(size 1 1)
					(thickness 0.15)
				)
			)
		)
		(property "MPN" "C1005X6S1A105K050BC"
			(at 205.24 395.86 0)
			(layer "F.Fab")
			(hide yes)
			(effects
				(font
					(size 1 1)
					(thickness 0.15)
				)
			)
		)
		(property "Manufacturer" "TDK"
			(at 205.24 395.86 0)
			(layer "F.Fab")
			(hide yes)
			(effects
				(font
					(size 1 1)
					(thickness 0.15)
				)
			)
		)
		(property "Public" "False"
			(at 205.24 395.86 0)
			(layer "F.Fab")
			(hide yes)
			(effects
				(font
					(size 1 1)
					(thickness 0.15)
				)
			)
		)
		(property "Val" "1u"
			(at 205.24 395.86 0)
			(layer "F.Fab")
			(hide yes)
			(effects
				(font
					(size 1 1)
					(thickness 0.15)
				)
			)
		)
		(property "Voltage" ""
			(at 205.24 395.86 0)
			(layer "F.Fab")
			(hide yes)
			(effects
				(font
					(size 1 1)
					(thickness 0.15)
				)
			)
		)
		(sheetname "Power")
		(sheetfile "power.kicad_sch")
		(attr smd)
		(fp_rect
			(start -0.925 -0.47)
			(end 0.925 0.47)
			(stroke
				(width 0.05)
				(type default)
			)
			(fill no)
			(layer "F.CrtYd")
		)
		(fp_line
			(start -0.494 0.248)
			(end -0.494 -0.25)
			(stroke
				(width 0.15)
				(type solid)
			)
			(layer "F.Fab")
		)
		(fp_line
			(start 0.504 0.248)
			(end -0.494 0.248)
			(stroke
				(width 0.15)
				(type solid)
			)
			(layer "F.Fab")
		)
		(fp_line
			(start -0.494 -0.25)
			(end 0.504 -0.25)
			(stroke
				(width 0.15)
				(type solid)
			)
			(layer "F.Fab")
		)
		(fp_line
			(start 0.504 -0.25)
			(end 0.504 0.248)
			(stroke
				(width 0.15)
				(type solid)
			)
			(layer "F.Fab")
		)
		(pad "1" smd roundrect
			(at -0.48 0 270)
			(size 0.59 0.64)
			(layers "F.Cu" "F.Mask" "F.Paste")
			(roundrect_rratio 0.25)
			(net 1 "GND")
			(pintype "passive")
			(teardrops
				(best_length_ratio 0.2)
				(max_length 1)
				(best_width_ratio 0.9)
				(max_width 2)
				(curved_edges yes)
				(filter_ratio 0.9)
				(enabled yes)
				(allow_two_segments yes)
				(prefer_zone_connections yes)
			)
		)
		(pad "2" smd roundrect
			(at 0.48 0 270)
			(size 0.59 0.64)
			(layers "F.Cu" "F.Mask" "F.Paste")
			(roundrect_rratio 0.25)
			(net 77 "+5V_AON")
			(pintype "passive")
			(teardrops
				(best_length_ratio 0.2)
				(max_length 1)
				(best_width_ratio 0.9)
				(max_width 2)
				(curved_edges yes)
				(filter_ratio 0.9)
				(enabled yes)
				(allow_two_segments yes)
				(prefer_zone_connections yes)
			)
		)
	)
	(footprint "antmicro-footprints:SOT-23-3"
		(layer "F.Cu")
		(at 317.1 112.66)
		(property "Reference" "Q10"
			(at 1.85 -0.6 90)
			(layer "F.SilkS")
			(effects
				(font
					(size 0.7 0.7)
					(thickness 0.15)
				)
				(justify left bottom)
			)
		)
		(property "Value" "MMBT3904LT1G"
			(at -1.9 2.7 0)
			(layer "F.Fab")
			(effects
				(font
					(size 0.7 0.7)
					(thickness 0.15)
				)
				(justify left bottom)
			)
		)
		(property "Datasheet" "https://eu.mouser.com/datasheet/2/308/1/MMBT3904LT1_D-2316262.pdf"
			(at 0 0 0)
			(layer "F.Fab")
			(hide yes)
			(effects
				(font
					(size 1.27 1.27)
					(thickness 0.15)
				)
			)
		)
		(property "Author" "Antmicro"
			(at 0 0 0)
			(layer "F.Fab")
			(hide yes)
			(effects
				(font
					(size 1 1)
					(thickness 0.15)
				)
			)
		)
		(property "License" "Apache-2.0"
			(at 0 0 0)
			(layer "F.Fab")
			(hide yes)
			(effects
				(font
					(size 1 1)
					(thickness 0.15)
				)
			)
		)
		(property "MPN" "MMBT3904LT1G"
			(at 0 0 0)
			(layer "F.Fab")
			(hide yes)
			(effects
				(font
					(size 1 1)
					(thickness 0.15)
				)
			)
		)
		(property "Manufacturer" "Onsemi"
			(at 0 0 0)
			(layer "F.Fab")
			(hide yes)
			(effects
				(font
					(size 1 1)
					(thickness 0.15)
				)
			)
		)
		(property "Public" "False"
			(at 0 0 0)
			(layer "F.Fab")
			(hide yes)
			(effects
				(font
					(size 1 1)
					(thickness 0.15)
				)
			)
		)
		(property ki_fp_filters "SOT?323*")
		(sheetname "Misc")
		(sheetfile "misc.kicad_sch")
		(attr smd)
		(fp_line
			(start -1.45 -1.35)
			(end -0.85 -1.35)
			(stroke
				(width 0.15)
				(type solid)
			)
			(layer "F.SilkS")
		)
		(fp_line
			(start -0.85 -1.35)
			(end -0.7 -1.5)
			(stroke
				(width 0.15)
				(type solid)
			)
			(layer "F.SilkS")
		)
		(fp_line
			(start -0.7 1.5)
			(end -0.7 1.35)
			(stroke
				(width 0.15)
				(type solid)
			)
			(layer "F.SilkS")
		)
		(fp_line
			(start 0.7 -1.5)
			(end -0.7 -1.5)
			(stroke
				(width 0.15)
				(type solid)
			)
			(layer "F.SilkS")
		)
		(fp_line
			(start 0.7 -0.4)
			(end 0.7 -1.5)
			(stroke
				(width 0.15)
				(type solid)
			)
			(layer "F.SilkS")
		)
		(fp_line
			(start 0.7 0.4)
			(end 0.7 1.5)
			(stroke
				(width 0.15)
				(type solid)
			)
			(layer "F.SilkS")
		)
		(fp_line
			(start 0.7 1.5)
			(end -0.7 1.5)
			(stroke
				(width 0.15)
				(type solid)
			)
			(layer "F.SilkS")
		)
		(fp_line
			(start -1.75 -0.5)
			(end -1.75 -1.4)
			(stroke
				(width 0.05)
				(type solid)
			)
			(layer "F.CrtYd")
		)
		(fp_line
			(start -1.75 0.5)
			(end -0.85 0.5)
			(stroke
				(width 0.05)
				(type solid)
			)
			(layer "F.CrtYd")
		)
		(fp_line
			(start -1.75 1.4)
			(end -1.75 0.5)
			(stroke
				(width 0.05)
				(type solid)
			)
			(layer "F.CrtYd")
		)
		(fp_line
			(start -0.9 -1.6)
			(end -0.9 -1.4)
			(stroke
				(width 0.05)
				(type solid)
			)
			(layer "F.CrtYd")
		)
		(fp_line
			(start -0.9 -1.6)
			(end 0.825 -1.6)
			(stroke
				(width 0.05)
				(type solid)
			)
			(layer "F.CrtYd")
		)
		(fp_line
			(start -0.9 -1.4)
			(end -1.75 -1.4)
			(stroke
				(width 0.05)
				(type solid)
			)
			(layer "F.CrtYd")
		)
		(fp_line
			(start -0.85 -0.5)
			(end -1.75 -0.5)
			(stroke
				(width 0.05)
				(type solid)
			)
			(layer "F.CrtYd")
		)
		(fp_line
			(start -0.85 0.5)
			(end -0.85 -0.5)
			(stroke
				(width 0.05)
				(type solid)
			)
			(layer "F.CrtYd")
		)
		(fp_line
			(start -0.85 1.4)
			(end -1.75 1.4)
			(stroke
				(width 0.05)
				(type solid)
			)
			(layer "F.CrtYd")
		)
		(fp_line
			(start -0.85 1.65)
			(end -0.85 1.4)
			(stroke
				(width 0.05)
				(type solid)
			)
			(layer "F.CrtYd")
		)
		(fp_line
			(start 0.825 -1.6)
			(end 0.825 -0.45)
			(stroke
				(width 0.05)
				(type solid)
			)
			(layer "F.CrtYd")
		)
		(fp_line
			(start 0.825 -0.45)
			(end 1.75 -0.45)
			(stroke
				(width 0.05)
				(type solid)
			)
			(layer "F.CrtYd")
		)
		(fp_line
			(start 0.85 0.45)
			(end 0.85 1.65)
			(stroke
				(width 0.05)
				(type solid)
			)
			(layer "F.CrtYd")
		)
		(fp_line
			(start 0.85 1.65)
			(end -0.85 1.65)
			(stroke
				(width 0.05)
				(type solid)
			)
			(layer "F.CrtYd")
		)
		(fp_line
			(start 1.75 -0.45)
			(end 1.75 0.45)
			(stroke
				(width 0.05)
				(type solid)
			)
			(layer "F.CrtYd")
		)
		(fp_line
			(start 1.75 0.45)
			(end 0.85 0.45)
			(stroke
				(width 0.05)
				(type solid)
			)
			(layer "F.CrtYd")
		)
		(fp_line
			(start -0.712 -1.325)
			(end -0.712 1.523)
			(stroke
				(width 0.15)
				(type solid)
			)
			(layer "F.Fab")
		)
		(fp_line
			(start -0.712 1.519)
			(end 0.688 1.519)
			(stroke
				(width 0.15)
				(type solid)
			)
			(layer "F.Fab")
		)
		(fp_line
			(start -0.437 -1.526)
			(end -0.712 -1.325)
			(stroke
				(width 0.15)
				(type solid)
			)
			(layer "F.Fab")
		)
		(fp_line
			(start -0.437 -1.526)
			(end 0.688 -1.526)
			(stroke
				(width 0.15)
				(type solid)
			)
			(layer "F.Fab")
		)
		(fp_line
			(start 0.688 1.519)
			(end 0.688 -1.52)
			(stroke
				(width 0.15)
				(type solid)
			)
			(layer "F.Fab")
		)
		(pad "1" smd roundrect
			(at -1.1 -0.951)
			(size 1 0.6)
			(layers "F.Cu" "F.Mask" "F.Paste")
			(roundrect_rratio 0.15)
			(net 543 "Net-(Q10-B)")
			(pinfunction "B")
			(pintype "input")
			(teardrops
				(best_length_ratio 0.2)
				(max_length 1)
				(best_width_ratio 0.9)
				(max_width 2)
				(curved_edges yes)
				(filter_ratio 0.9)
				(enabled yes)
				(allow_two_segments yes)
				(prefer_zone_connections yes)
			)
		)
		(pad "2" smd roundrect
			(at -1.1 0.949)
			(size 1 0.6)
			(layers "F.Cu" "F.Mask" "F.Paste")
			(roundrect_rratio 0.15)
			(net 544 "Net-(Q10-E)")
			(pinfunction "E")
			(pintype "passive")
			(teardrops
				(best_length_ratio 0.2)
				(max_length 1)
				(best_width_ratio 0.9)
				(max_width 2)
				(curved_edges yes)
				(filter_ratio 0.9)
				(enabled yes)
				(allow_two_segments yes)
				(prefer_zone_connections yes)
			)
		)
		(pad "3" smd roundrect
			(at 1.1 -0.0005)
			(size 1 0.6)
			(layers "F.Cu" "F.Mask" "F.Paste")
			(roundrect_rratio 0.15)
			(net 543 "Net-(Q10-B)")
			(pinfunction "C")
			(pintype "passive")
			(teardrops
				(best_length_ratio 0.2)
				(max_length 1)
				(best_width_ratio 0.9)
				(max_width 2)
				(curved_edges yes)
				(filter_ratio 0.9)
				(enabled yes)
				(allow_two_segments yes)
				(prefer_zone_connections yes)
			)
		)
	)
	(footprint "antmicro-footprints:R_0201"
		(layer "F.Cu")
		(at 150.33 147.961 -90)
		(descr "Resistor SMD 0201")
		(tags "resistor SMD 0201")
		(property "Reference" "R276"
			(at 3.62 -0.57 90)
			(layer "F.SilkS")
			(effects
				(font
					(size 0.7 0.7)
					(thickness 0.15)
				)
				(justify right bottom)
			)
		)
		(property "Value" "R_0R_0201"
			(at 0 1.25 90)
			(layer "F.Fab")
			(effects
				(font
					(size 0.7 0.7)
					(thickness 0.15)
				)
				(justify right bottom)
			)
		)
		(property "Datasheet" "https://www.bourns.com/docs/product-datasheets/cr.pdf"
			(at 0 0 270)
			(layer "F.Fab")
			(hide yes)
			(effects
				(font
					(size 1.27 1.27)
					(thickness 0.15)
				)
			)
		)
		(property "Author" "Antmicro"
			(at 2.369 298.291 0)
			(layer "F.Fab")
			(hide yes)
			(effects
				(font
					(size 1 1)
					(thickness 0.15)
				)
			)
		)
		(property "License" "Apache-2.0"
			(at 2.369 298.291 0)
			(layer "F.Fab")
			(hide yes)
			(effects
				(font
					(size 1 1)
					(thickness 0.15)
				)
			)
		)
		(property "MPN" "CR0201-FX-0R00GLF"
			(at 2.369 298.291 0)
			(layer "F.Fab")
			(hide yes)
			(effects
				(font
					(size 1 1)
					(thickness 0.15)
				)
			)
		)
		(property "Manufacturer" "Bourns"
			(at 2.369 298.291 0)
			(layer "F.Fab")
			(hide yes)
			(effects
				(font
					(size 1 1)
					(thickness 0.15)
				)
			)
		)
		(property "Tolerance" "1%"
			(at 2.369 298.291 0)
			(layer "F.Fab")
			(hide yes)
			(effects
				(font
					(size 1 1)
					(thickness 0.15)
				)
			)
		)
		(property "Val" "0R"
			(at 2.369 298.291 0)
			(layer "F.Fab")
			(hide yes)
			(effects
				(font
					(size 1 1)
					(thickness 0.15)
				)
			)
		)
		(sheetname "KR to SFI #1")
		(sheetfile "kr_sfi.kicad_sch")
		(attr smd dnp)
		(fp_rect
			(start -0.7 -0.35)
			(end 0.7 0.35)
			(stroke
				(width 0.05)
				(type default)
			)
			(fill no)
			(layer "F.CrtYd")
		)
		(fp_rect
			(start -0.3 -0.15)
			(end 0.298 0.148)
			(stroke
				(width 0.15)
				(type solid)
			)
			(fill no)
			(layer "F.Fab")
		)
		(pad "" smd roundrect
			(at -0.346 0 270)
			(size 0.318 0.36)
			(layers "F.Paste")
			(roundrect_rratio 0.25)
			(teardrops
				(best_length_ratio 0.2)
				(max_length 1)
				(best_width_ratio 0.9)
				(max_width 2)
				(curved_edges yes)
				(filter_ratio 0.9)
				(enabled yes)
				(allow_two_segments yes)
				(prefer_zone_connections yes)
			)
		)
		(pad "" smd roundrect
			(at 0.344 0 270)
			(size 0.318 0.36)
			(layers "F.Paste")
			(roundrect_rratio 0.25)
			(teardrops
				(best_length_ratio 0.2)
				(max_length 1)
				(best_width_ratio 0.9)
				(max_width 2)
				(curved_edges yes)
				(filter_ratio 0.9)
				(enabled yes)
				(allow_two_segments yes)
				(prefer_zone_connections yes)
			)
		)
		(pad "1" smd roundrect
			(at -0.32 0 270)
			(size 0.46 0.4)
			(layers "F.Cu" "F.Mask")
			(roundrect_rratio 0.25)
			(net 170 "/2xSFP+/SFI0.RX-")
			(pintype "passive")
			(teardrops
				(best_length_ratio 0.2)
				(max_length 1)
				(best_width_ratio 0.9)
				(max_width 2)
				(curved_edges yes)
				(filter_ratio 0.9)
				(enabled yes)
				(allow_two_segments yes)
				(prefer_zone_connections yes)
			)
		)
		(pad "2" smd roundrect
			(at 0.32 0 270)
			(size 0.46 0.4)
			(layers "F.Cu" "F.Mask")
			(roundrect_rratio 0.25)
			(net 967 "/2xSFP+/KR to SFI #1/BYP_RX-")
			(pintype "passive")
			(teardrops
				(best_length_ratio 0.2)
				(max_length 1)
				(best_width_ratio 0.9)
				(max_width 2)
				(curved_edges yes)
				(filter_ratio 0.9)
				(enabled yes)
				(allow_two_segments yes)
				(prefer_zone_connections yes)
			)
		)
	)
	(footprint "antmicro-footprints:C_0201"
		(layer "F.Cu")
		(at 156.332 147.31 90)
		(descr "Capacitor SMD 0201")
		(tags "capacitor SMD 0201")
		(property "Reference" "C154"
			(at -4.125 0.618 90)
			(layer "F.SilkS")
			(effects
				(font
					(size 0.7 0.7)
					(thickness 0.15)
				)
				(justify left bottom)
			)
		)
		(property "Value" "C_100n_0201_25V"
			(at 0 1.4 90)
			(layer "F.Fab")
			(effects
				(font
					(size 0.7 0.7)
					(thickness 0.15)
				)
				(justify left bottom)
			)
		)
		(property "Datasheet" "https://product.tdk.com/en/search/capacitor/ceramic/mlcc/info?part_no=C0603X5R1E104K030BB"
			(at 0 0 90)
			(layer "F.Fab")
			(hide yes)
			(effects
				(font
					(size 1.27 1.27)
					(thickness 0.15)
				)
			)
		)
		(property "Author" "Antmicro"
			(at 303.642 -9.022 0)
			(layer "F.Fab")
			(hide yes)
			(effects
				(font
					(size 1 1)
					(thickness 0.15)
				)
			)
		)
		(property "Dielectric" ""
			(at 303.642 -9.022 0)
			(layer "F.Fab")
			(hide yes)
			(effects
				(font
					(size 1 1)
					(thickness 0.15)
				)
			)
		)
		(property "License" "Apache-2.0"
			(at 303.642 -9.022 0)
			(layer "F.Fab")
			(hide yes)
			(effects
				(font
					(size 1 1)
					(thickness 0.15)
				)
			)
		)
		(property "MPN" "C0603X5R1E104K030BB"
			(at 303.642 -9.022 0)
			(layer "F.Fab")
			(hide yes)
			(effects
				(font
					(size 1 1)
					(thickness 0.15)
				)
			)
		)
		(property "Manufacturer" "TDK"
			(at 303.642 -9.022 0)
			(layer "F.Fab")
			(hide yes)
			(effects
				(font
					(size 1 1)
					(thickness 0.15)
				)
			)
		)
		(property "Public" "False"
			(at 303.642 -9.022 0)
			(layer "F.Fab")
			(hide yes)
			(effects
				(font
					(size 1 1)
					(thickness 0.15)
				)
			)
		)
		(property "Val" "100n"
			(at 303.642 -9.022 0)
			(layer "F.Fab")
			(hide yes)
			(effects
				(font
					(size 1 1)
					(thickness 0.15)
				)
			)
		)
		(property "Voltage" "25V"
			(at 303.642 -9.022 0)
			(layer "F.Fab")
			(hide yes)
			(effects
				(font
					(size 1 1)
					(thickness 0.15)
				)
			)
		)
		(sheetname "KR to SFI #1")
		(sheetfile "kr_sfi.kicad_sch")
		(attr smd)
		(fp_rect
			(start -0.7 -0.35)
			(end 0.7 0.35)
			(stroke
				(width 0.05)
				(type default)
			)
			(fill no)
			(layer "F.CrtYd")
		)
		(fp_rect
			(start 0.3 0.15)
			(end -0.301 -0.149)
			(stroke
				(width 0.15)
				(type solid)
			)
			(fill no)
			(layer "F.Fab")
		)
		(pad "" smd roundrect
			(at -0.349 -0.002 90)
			(size 0.318 0.36)
			(layers "F.Paste")
			(roundrect_rratio 0.25)
			(teardrops
				(best_length_ratio 0.2)
				(max_length 1)
				(best_width_ratio 0.9)
				(max_width 2)
				(curved_edges yes)
				(filter_ratio 0.9)
				(enabled yes)
				(allow_two_segments yes)
				(prefer_zone_connections yes)
			)
		)
		(pad "" smd roundrect
			(at 0.341 -0.002 90)
			(size 0.318 0.36)
			(layers "F.Paste")
			(roundrect_rratio 0.25)
			(teardrops
				(best_length_ratio 0.2)
				(max_length 1)
				(best_width_ratio 0.9)
				(max_width 2)
				(curved_edges yes)
				(filter_ratio 0.9)
				(enabled yes)
				(allow_two_segments yes)
				(prefer_zone_connections yes)
			)
		)
		(pad "1" smd roundrect
			(at -0.321 -0.002 90)
			(size 0.46 0.4)
			(layers "F.Cu" "F.Mask")
			(roundrect_rratio 0.25)
			(net 113 "/2xSFP+/10GKR_SFP0.TX-")
			(pintype "passive")
			(teardrops
				(best_length_ratio 0.2)
				(max_length 1)
				(best_width_ratio 0.9)
				(max_width 2)
				(curved_edges yes)
				(filter_ratio 0.9)
				(enabled yes)
				(allow_two_segments yes)
				(prefer_zone_connections yes)
			)
		)
		(pad "2" smd roundrect
			(at 0.32 -0.002 90)
			(size 0.46 0.4)
			(layers "F.Cu" "F.Mask")
			(roundrect_rratio 0.25)
			(net 114 "/2xSFP+/KR to SFI #1/KR_C.TX-")
			(pintype "passive")
			(teardrops
				(best_length_ratio 0.2)
				(max_length 1)
				(best_width_ratio 0.9)
				(max_width 2)
				(curved_edges yes)
				(filter_ratio 0.9)
				(enabled yes)
				(allow_two_segments yes)
				(prefer_zone_connections yes)
			)
		)
	)
	(footprint "antmicro-footprints:C_Pol_EIA-D"
		(layer "F.Cu")
		(at 317.324999 103.3 90)
		(property "Reference" "C39"
			(at -5.96 2.375001 90)
			(layer "F.SilkS")
			(effects
				(font
					(size 0.7 0.7)
					(thickness 0.15)
				)
				(justify left bottom)
			)
		)
		(property "Value" "C_Pol_68u_16V_Panasonic-TQC-D"
			(at 0 3.4 90)
			(layer "F.Fab")
			(effects
				(font
					(size 0.7 0.7)
					(thickness 0.15)
				)
				(justify left bottom)
			)
		)
		(property "Datasheet" "https://industrial.panasonic.com/sa/products/pt/aluminum-cap-smd/models/16TQC68MYF"
			(at 0 0 90)
			(layer "F.Fab")
			(hide yes)
			(effects
				(font
					(size 1.27 1.27)
					(thickness 0.15)
				)
			)
		)
		(property "Author" "Antmicro"
			(at 420.624999 -214.024999 0)
			(layer "F.Fab")
			(hide yes)
			(effects
				(font
					(size 1 1)
					(thickness 0.15)
				)
			)
		)
		(property "Dielectric" "template_dielectric"
			(at 420.624999 -214.024999 0)
			(layer "F.Fab")
			(hide yes)
			(effects
				(font
					(size 1 1)
					(thickness 0.15)
				)
			)
		)
		(property "License" "Apache-2.0"
			(at 420.624999 -214.024999 0)
			(layer "F.Fab")
			(hide yes)
			(effects
				(font
					(size 1 1)
					(thickness 0.15)
				)
			)
		)
		(property "MPN" "16TQC68MYF"
			(at 420.624999 -214.024999 0)
			(layer "F.Fab")
			(hide yes)
			(effects
				(font
					(size 1 1)
					(thickness 0.15)
				)
			)
		)
		(property "Manufacturer" "Panasonic"
			(at 420.624999 -214.024999 0)
			(layer "F.Fab")
			(hide yes)
			(effects
				(font
					(size 1 1)
					(thickness 0.15)
				)
			)
		)
		(property "Public" "False"
			(at 420.624999 -214.024999 0)
			(layer "F.Fab")
			(hide yes)
			(effects
				(font
					(size 1 1)
					(thickness 0.15)
				)
			)
		)
		(property "Val" "68u"
			(at 420.624999 -214.024999 0)
			(layer "F.Fab")
			(hide yes)
			(effects
				(font
					(size 1 1)
					(thickness 0.15)
				)
			)
		)
		(property "Voltage" "16V"
			(at 420.624999 -214.024999 0)
			(layer "F.Fab")
			(hide yes)
			(effects
				(font
					(size 1 1)
					(thickness 0.15)
				)
			)
		)
		(sheetname "Power")
		(sheetfile "power.kicad_sch")
		(attr smd)
		(fp_line
			(start 3.6 -2.2)
			(end 3.6 -1.6)
			(stroke
				(width 0.15)
				(type solid)
			)
			(layer "F.SilkS")
		)
		(fp_line
			(start -3.58 -2.2)
			(end 3.6 -2.2)
			(stroke
				(width 0.15)
				(type solid)
			)
			(layer "F.SilkS")
		)
		(fp_line
			(start -4.1 -2.025)
			(end -4.1 -1.625)
			(stroke
				(width 0.12)
				(type solid)
			)
			(layer "F.SilkS")
		)
		(fp_line
			(start -4.3 -1.825)
			(end -3.9 -1.825)
			(stroke
				(width 0.12)
				(type solid)
			)
			(layer "F.SilkS")
		)
		(fp_line
			(start -3.58 -1.6)
			(end -3.58 -2.2)
			(stroke
				(width 0.15)
				(type solid)
			)
			(layer "F.SilkS")
		)
		(fp_line
			(start 3.6 1.6)
			(end 3.6 2.2)
			(stroke
				(width 0.15)
				(type solid)
			)
			(layer "F.SilkS")
		)
		(fp_line
			(start 3.6 2.2)
			(end -3.58 2.2)
			(stroke
				(width 0.15)
				(type solid)
			)
			(layer "F.SilkS")
		)
		(fp_line
			(start -3.58 2.2)
			(end -3.58 1.6)
			(stroke
				(width 0.15)
				(type solid)
			)
			(layer "F.SilkS")
		)
		(fp_line
			(start 3.77 -2.4)
			(end 3.77 -1.51)
			(stroke
				(width 0.05)
				(type solid)
			)
			(layer "F.CrtYd")
		)
		(fp_line
			(start -3.775 -2.4)
			(end 3.77 -2.4)
			(stroke
				(width 0.05)
				(type solid)
			)
			(layer "F.CrtYd")
		)
		(fp_line
			(start -3.775 -2.4)
			(end -3.775 -1.5)
			(stroke
				(width 0.05)
				(type solid)
			)
			(layer "F.CrtYd")
		)
		(fp_line
			(start 4.505 -1.51)
			(end 4.505 1.5)
			(stroke
				(width 0.05)
				(type solid)
			)
			(layer "F.CrtYd")
		)
		(fp_line
			(start 3.77 -1.51)
			(end 4.505 -1.51)
			(stroke
				(width 0.05)
				(type solid)
			)
			(layer "F.CrtYd")
		)
		(fp_line
			(start -3.775 -1.5)
			(end -4.505 -1.5)
			(stroke
				(width 0.05)
				(type solid)
			)
			(layer "F.CrtYd")
		)
		(fp_line
			(start 4.505 1.51)
			(end 3.77 1.51)
			(stroke
				(width 0.05)
				(type solid)
			)
			(layer "F.CrtYd")
		)
		(fp_line
			(start 3.77 1.51)
			(end 3.77 2.4)
			(stroke
				(width 0.05)
				(type solid)
			)
			(layer "F.CrtYd")
		)
		(fp_line
			(start -3.77 1.51)
			(end -4.505 1.51)
			(stroke
				(width 0.05)
				(type solid)
			)
			(layer "F.CrtYd")
		)
		(fp_line
			(start -4.505 1.51)
			(end -4.505 -1.5)
			(stroke
				(width 0.05)
				(type solid)
			)
			(layer "F.CrtYd")
		)
		(fp_line
			(start 3.77 2.4)
			(end -3.77 2.4)
			(stroke
				(width 0.05)
				(type solid)
			)
			(layer "F.CrtYd")
		)
		(fp_line
			(start -3.77 2.4)
			(end -3.77 1.51)
			(stroke
				(width 0.05)
				(type solid)
			)
			(layer "F.CrtYd")
		)
		(fp_rect
			(start -3.65 -2.15)
			(end 3.65 2.15)
			(stroke
				(width 0.15)
				(type solid)
			)
			(fill no)
			(layer "F.Fab")
		)
		(pad "1" smd roundrect
			(at -3.1 0 90)
			(size 2.31 2.52)
			(layers "F.Cu" "F.Mask" "F.Paste")
			(roundrect_rratio 0.1)
			(net 62 "+12V_AON")
			(pintype "passive")
			(teardrops
				(best_length_ratio 0.2)
				(max_length 1)
				(best_width_ratio 0.9)
				(max_width 2)
				(curved_edges yes)
				(filter_ratio 0.9)
				(enabled yes)
				(allow_two_segments yes)
				(prefer_zone_connections yes)
			)
		)
		(pad "2" smd roundrect
			(at 3.1 0 90)
			(size 2.31 2.52)
			(layers "F.Cu" "F.Mask" "F.Paste")
			(roundrect_rratio 0.1)
			(net 1 "GND")
			(pintype "passive")
			(teardrops
				(best_length_ratio 0.2)
				(max_length 1)
				(best_width_ratio 0.9)
				(max_width 2)
				(curved_edges yes)
				(filter_ratio 0.9)
				(enabled yes)
				(allow_two_segments yes)
				(prefer_zone_connections yes)
			)
		)
	)
	(footprint "antmicro-footprints:SOT-23-3"
		(layer "F.Cu")
		(at 253.775 131.51 90)
		(property "Reference" "D20"
			(at 1.4 0.425 180)
			(layer "F.SilkS")
			(effects
				(font
					(size 0.7 0.7)
					(thickness 0.15)
				)
				(justify left bottom)
			)
		)
		(property "Value" "BAT54C"
			(at -1.9 2.7 90)
			(layer "F.Fab")
			(effects
				(font
					(size 0.7 0.7)
					(thickness 0.15)
				)
				(justify left bottom)
			)
		)
		(property "Datasheet" "https://diotec.com/request/datasheet/bat54.pdf"
			(at 0 0 90)
			(layer "F.Fab")
			(hide yes)
			(effects
				(font
					(size 1.27 1.27)
					(thickness 0.15)
				)
			)
		)
		(property "Author" "Antmicro"
			(at 385.285 -122.265 0)
			(layer "F.Fab")
			(hide yes)
			(effects
				(font
					(size 1 1)
					(thickness 0.15)
				)
			)
		)
		(property "License" "Apache-2.0"
			(at 385.285 -122.265 0)
			(layer "F.Fab")
			(hide yes)
			(effects
				(font
					(size 1 1)
					(thickness 0.15)
				)
			)
		)
		(property "MPN" "BAT54C"
			(at 385.285 -122.265 0)
			(layer "F.Fab")
			(hide yes)
			(effects
				(font
					(size 1 1)
					(thickness 0.15)
				)
			)
		)
		(property "Manufacturer" "Diotec Semiconductor"
			(at 385.285 -122.265 0)
			(layer "F.Fab")
			(hide yes)
			(effects
				(font
					(size 1 1)
					(thickness 0.15)
				)
			)
		)
		(sheetname "Com Express 7 MGMT")
		(sheetfile "com_express_7_mgmt.kicad_sch")
		(attr smd)
		(fp_line
			(start 0.7 -1.5)
			(end -0.7 -1.5)
			(stroke
				(width 0.15)
				(type solid)
			)
			(layer "F.SilkS")
		)
		(fp_line
			(start -0.85 -1.35)
			(end -0.7 -1.5)
			(stroke
				(width 0.15)
				(type solid)
			)
			(layer "F.SilkS")
		)
		(fp_line
			(start -1.45 -1.35)
			(end -0.85 -1.35)
			(stroke
				(width 0.15)
				(type solid)
			)
			(layer "F.SilkS")
		)
		(fp_line
			(start 0.7 -0.4)
			(end 0.7 -1.5)
			(stroke
				(width 0.15)
				(type solid)
			)
			(layer "F.SilkS")
		)
		(fp_line
			(start 0.7 0.4)
			(end 0.7 1.5)
			(stroke
				(width 0.15)
				(type solid)
			)
			(layer "F.SilkS")
		)
		(fp_line
			(start 0.7 1.5)
			(end -0.7 1.5)
			(stroke
				(width 0.15)
				(type solid)
			)
			(layer "F.SilkS")
		)
		(fp_line
			(start -0.7 1.5)
			(end -0.7 1.35)
			(stroke
				(width 0.15)
				(type solid)
			)
			(layer "F.SilkS")
		)
		(fp_line
			(start 0.825 -1.6)
			(end 0.825 -0.45)
			(stroke
				(width 0.05)
				(type solid)
			)
			(layer "F.CrtYd")
		)
		(fp_line
			(start -0.9 -1.6)
			(end 0.825 -1.6)
			(stroke
				(width 0.05)
				(type solid)
			)
			(layer "F.CrtYd")
		)
		(fp_line
			(start -0.9 -1.6)
			(end -0.9 -1.4)
			(stroke
				(width 0.05)
				(type solid)
			)
			(layer "F.CrtYd")
		)
		(fp_line
			(start -0.9 -1.4)
			(end -1.75 -1.4)
			(stroke
				(width 0.05)
				(type solid)
			)
			(layer "F.CrtYd")
		)
		(fp_line
			(start -0.85 -0.5)
			(end -1.75 -0.5)
			(stroke
				(width 0.05)
				(type solid)
			)
			(layer "F.CrtYd")
		)
		(fp_line
			(start -1.75 -0.5)
			(end -1.75 -1.4)
			(stroke
				(width 0.05)
				(type solid)
			)
			(layer "F.CrtYd")
		)
		(fp_line
			(start 1.75 -0.45)
			(end 1.75 0.45)
			(stroke
				(width 0.05)
				(type solid)
			)
			(layer "F.CrtYd")
		)
		(fp_line
			(start 0.825 -0.45)
			(end 1.75 -0.45)
			(stroke
				(width 0.05)
				(type solid)
			)
			(layer "F.CrtYd")
		)
		(fp_line
			(start 1.75 0.45)
			(end 0.85 0.45)
			(stroke
				(width 0.05)
				(type solid)
			)
			(layer "F.CrtYd")
		)
		(fp_line
			(start 0.85 0.45)
			(end 0.85 1.65)
			(stroke
				(width 0.05)
				(type solid)
			)
			(layer "F.CrtYd")
		)
		(fp_line
			(start -0.85 0.5)
			(end -0.85 -0.5)
			(stroke
				(width 0.05)
				(type solid)
			)
			(layer "F.CrtYd")
		)
		(fp_line
			(start -1.75 0.5)
			(end -0.85 0.5)
			(stroke
				(width 0.05)
				(type solid)
			)
			(layer "F.CrtYd")
		)
		(fp_line
			(start -0.85 1.4)
			(end -1.75 1.4)
			(stroke
				(width 0.05)
				(type solid)
			)
			(layer "F.CrtYd")
		)
		(fp_line
			(start -1.75 1.4)
			(end -1.75 0.5)
			(stroke
				(width 0.05)
				(type solid)
			)
			(layer "F.CrtYd")
		)
		(fp_line
			(start 0.85 1.65)
			(end -0.85 1.65)
			(stroke
				(width 0.05)
				(type solid)
			)
			(layer "F.CrtYd")
		)
		(fp_line
			(start -0.85 1.65)
			(end -0.85 1.4)
			(stroke
				(width 0.05)
				(type solid)
			)
			(layer "F.CrtYd")
		)
		(fp_line
			(start -0.437 -1.526)
			(end 0.688 -1.526)
			(stroke
				(width 0.15)
				(type solid)
			)
			(layer "F.Fab")
		)
		(fp_line
			(start -0.437 -1.526)
			(end -0.712 -1.325)
			(stroke
				(width 0.15)
				(type solid)
			)
			(layer "F.Fab")
		)
		(fp_line
			(start -0.712 -1.325)
			(end -0.712 1.523)
			(stroke
				(width 0.15)
				(type solid)
			)
			(layer "F.Fab")
		)
		(fp_line
			(start 0.688 1.519)
			(end 0.688 -1.52)
			(stroke
				(width 0.15)
				(type solid)
			)
			(layer "F.Fab")
		)
		(fp_line
			(start -0.712 1.519)
			(end 0.688 1.519)
			(stroke
				(width 0.15)
				(type solid)
			)
			(layer "F.Fab")
		)
		(pad "1" smd roundrect
			(at -1.1 -0.951 90)
			(size 1 0.6)
			(layers "F.Cu" "F.Mask" "F.Paste")
			(roundrect_rratio 0.15)
			(net 136 "/Com Express 7 MGMT/~{TYPE0}")
			(pinfunction "1")
			(pintype "passive")
			(teardrops
				(best_length_ratio 0.2)
				(max_length 1)
				(best_width_ratio 0.9)
				(max_width 2)
				(curved_edges yes)
				(filter_ratio 0.9)
				(enabled yes)
				(allow_two_segments yes)
				(prefer_zone_connections yes)
			)
		)
		(pad "2" smd roundrect
			(at -1.1 0.949 90)
			(size 1 0.6)
			(layers "F.Cu" "F.Mask" "F.Paste")
			(roundrect_rratio 0.15)
			(net 137 "/Com Express 7 MGMT/~{TYPE2}")
			(pinfunction "2")
			(pintype "passive")
			(teardrops
				(best_length_ratio 0.2)
				(max_length 1)
				(best_width_ratio 0.9)
				(max_width 2)
				(curved_edges yes)
				(filter_ratio 0.9)
				(enabled yes)
				(allow_two_segments yes)
				(prefer_zone_connections yes)
			)
		)
		(pad "3" smd roundrect
			(at 1.1 -0.0005 90)
			(size 1 0.6)
			(layers "F.Cu" "F.Mask" "F.Paste")
			(roundrect_rratio 0.15)
			(net 138 "Net-(U33-1A)")
			(pinfunction "3")
			(pintype "passive")
			(teardrops
				(best_length_ratio 0.2)
				(max_length 1)
				(best_width_ratio 0.9)
				(max_width 2)
				(curved_edges yes)
				(filter_ratio 0.9)
				(enabled yes)
				(allow_two_segments yes)
				(prefer_zone_connections yes)
			)
		)
	)
	(footprint "antmicro-footprints:R_0402_1005Metric"
		(layer "F.Cu")
		(at 299.2 84.01 -90)
		(descr "Resistor SMD 0402")
		(tags "resistor SMD 0402")
		(property "Reference" "R128"
			(at 0.85 -0.45 90)
			(layer "F.SilkS")
			(effects
				(font
					(size 0.7 0.7)
					(thickness 0.15)
				)
				(justify right bottom)
			)
		)
		(property "Value" "R_10k_0402"
			(at -1.011843 1.772047 90)
			(layer "F.Fab")
			(effects
				(font
					(size 0.7 0.7)
					(thickness 0.15)
				)
				(justify right bottom)
			)
		)
		(property "Datasheet" "https://www.bourns.com/docs/product-datasheets/cr.pdf"
			(at 0 0 270)
			(layer "F.Fab")
			(hide yes)
			(effects
				(font
					(size 1.27 1.27)
					(thickness 0.15)
				)
			)
		)
		(property "Author" "Antmicro"
			(at 215.19 383.21 0)
			(layer "F.Fab")
			(hide yes)
			(effects
				(font
					(size 1 1)
					(thickness 0.15)
				)
			)
		)
		(property "License" "Apache-2.0"
			(at 215.19 383.21 0)
			(layer "F.Fab")
			(hide yes)
			(effects
				(font
					(size 1 1)
					(thickness 0.15)
				)
			)
		)
		(property "MPN" "CR0402-FX-1002GLF"
			(at 215.19 383.21 0)
			(layer "F.Fab")
			(hide yes)
			(effects
				(font
					(size 1 1)
					(thickness 0.15)
				)
			)
		)
		(property "Manufacturer" "Bourns"
			(at 215.19 383.21 0)
			(layer "F.Fab")
			(hide yes)
			(effects
				(font
					(size 1 1)
					(thickness 0.15)
				)
			)
		)
		(property "Public" "False"
			(at 215.19 383.21 0)
			(layer "F.Fab")
			(hide yes)
			(effects
				(font
					(size 1 1)
					(thickness 0.15)
				)
			)
		)
		(property "Tolerance" "1%"
			(at 215.19 383.21 0)
			(layer "F.Fab")
			(hide yes)
			(effects
				(font
					(size 1 1)
					(thickness 0.15)
				)
			)
		)
		(property "Val" "10k"
			(at 215.19 383.21 0)
			(layer "F.Fab")
			(hide yes)
			(effects
				(font
					(size 1 1)
					(thickness 0.15)
				)
			)
		)
		(sheetname "M.2 key M #2")
		(sheetfile "m2keym.kicad_sch")
		(attr smd)
		(fp_rect
			(start -0.925 -0.47)
			(end 0.925 0.47)
			(stroke
				(width 0.05)
				(type default)
			)
			(fill no)
			(layer "F.CrtYd")
		)
		(fp_rect
			(start -0.5 -0.25)
			(end 0.5 0.25)
			(stroke
				(width 0.15)
				(type solid)
			)
			(fill no)
			(layer "F.Fab")
		)
		(pad "1" smd roundrect
			(at -0.48 0 270)
			(size 0.59 0.64)
			(layers "F.Cu" "F.Mask" "F.Paste")
			(roundrect_rratio 0.25)
			(net 530 "/M.2 key M #2/~{CLKREQ}")
			(pintype "passive")
			(teardrops
				(best_length_ratio 0.2)
				(max_length 1)
				(best_width_ratio 0.9)
				(max_width 2)
				(curved_edges yes)
				(filter_ratio 0.9)
				(enabled yes)
				(allow_two_segments yes)
				(prefer_zone_connections yes)
			)
		)
		(pad "2" smd roundrect
			(at 0.48 0 270)
			(size 0.59 0.64)
			(layers "F.Cu" "F.Mask" "F.Paste")
			(roundrect_rratio 0.25)
			(net 2 "+3V3")
			(pintype "passive")
			(teardrops
				(best_length_ratio 0.2)
				(max_length 1)
				(best_width_ratio 0.9)
				(max_width 2)
				(curved_edges yes)
				(filter_ratio 0.9)
				(enabled yes)
				(allow_two_segments yes)
				(prefer_zone_connections yes)
			)
		)
	)
	(footprint "antmicro-footprints:C_0402_1005Metric"
		(layer "F.Cu")
		(at 195.401343 135.633266 -45)
		(descr "Capacitor SMD 0402")
		(tags "capacitor SMD 0402")
		(property "Reference" "C135"
			(at 3.864616 -0.431761 135)
			(layer "F.SilkS")
			(effects
				(font
					(size 0.7 0.7)
					(thickness 0.15)
				)
				(justify right top)
			)
		)
		(property "Value" "C_100n_0402"
			(at -1.022927 2.155213 135)
			(layer "F.Fab")
			(effects
				(font
					(size 0.7 0.7)
					(thickness 0.15)
				)
				(justify right top)
			)
		)
		(property "Datasheet" "https://www.murata.com/products/productdetail?partno=GRM155R61H104KE14%23"
			(at 0 0 135)
			(layer "B.Fab")
			(hide yes)
			(effects
				(font
					(size 1.27 1.27)
					(thickness 0.15)
				)
				(justify mirror)
			)
		)
		(property "Author" "Antmicro"
			(at 51.168 -324.134 45)
			(layer "F.Fab")
			(hide yes)
			(effects
				(font
					(size 1 1)
					(thickness 0.15)
				)
			)
		)
		(property "Dielectric" "X5R"
			(at 51.168 -324.134 45)
			(layer "F.Fab")
			(hide yes)
			(effects
				(font
					(size 1 1)
					(thickness 0.15)
				)
			)
		)
		(property "License" "Apache-2.0"
			(at 51.168 -324.134 45)
			(layer "F.Fab")
			(hide yes)
			(effects
				(font
					(size 1 1)
					(thickness 0.15)
				)
			)
		)
		(property "MPN" "GRM155R61H104KE14D"
			(at 51.168 -324.134 45)
			(layer "F.Fab")
			(hide yes)
			(effects
				(font
					(size 1 1)
					(thickness 0.15)
				)
			)
		)
		(property "Manufacturer" "Murata"
			(at 51.168 -324.134 45)
			(layer "F.Fab")
			(hide yes)
			(effects
				(font
					(size 1 1)
					(thickness 0.15)
				)
			)
		)
		(property "Public" "False"
			(at 51.168 -324.134 45)
			(layer "F.Fab")
			(hide yes)
			(effects
				(font
					(size 1 1)
					(thickness 0.15)
				)
			)
		)
		(property "Val" "100n"
			(at 51.168 -324.134 45)
			(layer "F.Fab")
			(hide yes)
			(effects
				(font
					(size 1 1)
					(thickness 0.15)
				)
			)
		)
		(property "Voltage" "50V"
			(at 51.168 -324.134 45)
			(layer "F.Fab")
			(hide yes)
			(effects
				(font
					(size 1 1)
					(thickness 0.15)
				)
			)
		)
		(sheetname "PCIe redriver")
		(sheetfile "pcie_redriver.kicad_sch")
		(attr smd)
		(fp_poly
			(pts
				(xy -0.925 -0.47) (xy 0.925 -0.47) (xy 0.925 0.47) (xy -0.925 0.47)
			)
			(stroke
				(width 0.05)
				(type default)
			)
			(fill no)
			(layer "F.CrtYd")
		)
		(fp_line
			(start -0.494 0.248)
			(end -0.494 -0.25)
			(stroke
				(width 0.15)
				(type solid)
			)
			(layer "F.Fab")
		)
		(fp_line
			(start -0.494 -0.25)
			(end 0.504 -0.25)
			(stroke
				(width 0.15)
				(type solid)
			)
			(layer "F.Fab")
		)
		(fp_line
			(start 0.504 0.248)
			(end -0.494 0.248)
			(stroke
				(width 0.15)
				(type solid)
			)
			(layer "F.Fab")
		)
		(fp_line
			(start 0.504 -0.25)
			(end 0.504 0.248)
			(stroke
				(width 0.15)
				(type solid)
			)
			(layer "F.Fab")
		)
		(pad "1" smd roundrect
			(at -0.48 0 315)
			(size 0.59 0.64)
			(layers "F.Cu" "F.Mask" "F.Paste")
			(roundrect_rratio 0.25)
			(net 1 "GND")
			(pintype "passive")
			(teardrops
				(best_length_ratio 0.2)
				(max_length 1)
				(best_width_ratio 0.9)
				(max_width 2)
				(curved_edges yes)
				(filter_ratio 0.9)
				(enabled yes)
				(allow_two_segments yes)
				(prefer_zone_connections yes)
			)
		)
		(pad "2" smd roundrect
			(at 0.48 0 315)
			(size 0.59 0.64)
			(layers "F.Cu" "F.Mask" "F.Paste")
			(roundrect_rratio 0.25)
			(net 2 "+3V3")
			(pintype "passive")
			(teardrops
				(best_length_ratio 0.2)
				(max_length 1)
				(best_width_ratio 0.9)
				(max_width 2)
				(curved_edges yes)
				(filter_ratio 0.9)
				(enabled yes)
				(allow_two_segments yes)
				(prefer_zone_connections yes)
			)
		)
	)
	(footprint "antmicro-footprints:R_0402_1005Metric"
		(layer "F.Cu")
		(at 211.28 126.09)
		(descr "Resistor SMD 0402")
		(tags "resistor SMD 0402")
		(property "Reference" "R178"
			(at -3.68 0.17 0)
			(layer "F.SilkS")
			(effects
				(font
					(size 0.7 0.7)
					(thickness 0.15)
				)
				(justify left bottom)
			)
		)
		(property "Value" "R_0R_0402"
			(at -1.011843 1.772047 0)
			(layer "F.Fab")
			(effects
				(font
					(size 0.7 0.7)
					(thickness 0.15)
				)
				(justify left bottom)
			)
		)
		(property "Datasheet" "https://industrial.panasonic.com/cdbs/www-data/pdf/RDA0000/AOA0000C301.pdf"
			(at 0 0 0)
			(layer "F.Fab")
			(hide yes)
			(effects
				(font
					(size 1.27 1.27)
					(thickness 0.15)
				)
			)
		)
		(property "Author" "Antmicro"
			(at 0 0 0)
			(layer "F.Fab")
			(hide yes)
			(effects
				(font
					(size 1 1)
					(thickness 0.15)
				)
			)
		)
		(property "Current" "1A"
			(at 0 0 0)
			(layer "F.Fab")
			(hide yes)
			(effects
				(font
					(size 1 1)
					(thickness 0.15)
				)
			)
		)
		(property "License" "Apache-2.0"
			(at 0 0 0)
			(layer "F.Fab")
			(hide yes)
			(effects
				(font
					(size 1 1)
					(thickness 0.15)
				)
			)
		)
		(property "MPN" "ERJ2GE0R00X"
			(at 0 0 0)
			(layer "F.Fab")
			(hide yes)
			(effects
				(font
					(size 1 1)
					(thickness 0.15)
				)
			)
		)
		(property "Manufacturer" "Panasonic"
			(at 0 0 0)
			(layer "F.Fab")
			(hide yes)
			(effects
				(font
					(size 1 1)
					(thickness 0.15)
				)
			)
		)
		(property "Public" "False"
			(at 0 0 0)
			(layer "F.Fab")
			(hide yes)
			(effects
				(font
					(size 1 1)
					(thickness 0.15)
				)
			)
		)
		(property "Tolerance" ""
			(at 0 0 0)
			(layer "F.Fab")
			(hide yes)
			(effects
				(font
					(size 1 1)
					(thickness 0.15)
				)
			)
		)
		(property "Val" "0R"
			(at 0 0 0)
			(layer "F.Fab")
			(hide yes)
			(effects
				(font
					(size 1 1)
					(thickness 0.15)
				)
			)
		)
		(sheetname "PCIe misc")
		(sheetfile "pcie_misc.kicad_sch")
		(attr smd dnp)
		(fp_rect
			(start -0.925 -0.47)
			(end 0.925 0.47)
			(stroke
				(width 0.05)
				(type default)
			)
			(fill no)
			(layer "F.CrtYd")
		)
		(fp_rect
			(start -0.5 -0.25)
			(end 0.5 0.25)
			(stroke
				(width 0.15)
				(type solid)
			)
			(fill no)
			(layer "F.Fab")
		)
		(pad "1" smd roundrect
			(at -0.48 0)
			(size 0.59 0.64)
			(layers "F.Cu" "F.Mask" "F.Paste")
			(roundrect_rratio 0.25)
			(net 529 "/M.2 key M #1/~{CLKREQ}")
			(pintype "passive")
			(teardrops
				(best_length_ratio 0.2)
				(max_length 1)
				(best_width_ratio 0.9)
				(max_width 2)
				(curved_edges yes)
				(filter_ratio 0.9)
				(enabled yes)
				(allow_two_segments yes)
				(prefer_zone_connections yes)
			)
		)
		(pad "2" smd roundrect
			(at 0.48 0)
			(size 0.59 0.64)
			(layers "F.Cu" "F.Mask" "F.Paste")
			(roundrect_rratio 0.25)
			(net 602 "Net-(U37-~{OE0})")
			(pintype "passive")
			(teardrops
				(best_length_ratio 0.2)
				(max_length 1)
				(best_width_ratio 0.9)
				(max_width 2)
				(curved_edges yes)
				(filter_ratio 0.9)
				(enabled yes)
				(allow_two_segments yes)
				(prefer_zone_connections yes)
			)
		)
	)
	(footprint "antmicro-footprints:R_0805_2012Metric"
		(layer "F.Cu")
		(at 304.25 135.813 180)
		(property "Reference" "R114"
			(at -1.35 0.953 0)
			(layer "F.SilkS")
			(effects
				(font
					(size 0.7 0.7)
					(thickness 0.15)
				)
				(justify right bottom)
			)
		)
		(property "Value" "R_0R001_0805"
			(at 0 1.8 0)
			(layer "F.Fab")
			(effects
				(font
					(size 0.7 0.7)
					(thickness 0.15)
				)
				(justify right bottom)
			)
		)
		(property "Datasheet" "https://www.eaton.com/content/dam/eaton/products/electronic-components/resources/data-sheet/eaton-msma-automotive-smd-current-sense-resistor-metal-strip-data-sheet-elx1179.pdf"
			(at 0 0 180)
			(layer "F.Fab")
			(hide yes)
			(effects
				(font
					(size 1.27 1.27)
					(thickness 0.15)
				)
			)
		)
		(property "Author" "Antmicro"
			(at 608.5 271.626 0)
			(layer "F.Fab")
			(hide yes)
			(effects
				(font
					(size 1 1)
					(thickness 0.15)
				)
			)
		)
		(property "License" "Apache-2.0"
			(at 608.5 271.626 0)
			(layer "F.Fab")
			(hide yes)
			(effects
				(font
					(size 1 1)
					(thickness 0.15)
				)
			)
		)
		(property "MPN" "MSMA0805R0010FSM"
			(at 608.5 271.626 0)
			(layer "F.Fab")
			(hide yes)
			(effects
				(font
					(size 1 1)
					(thickness 0.15)
				)
			)
		)
		(property "Manufacturer" "Eaton"
			(at 608.5 271.626 0)
			(layer "F.Fab")
			(hide yes)
			(effects
				(font
					(size 1 1)
					(thickness 0.15)
				)
			)
		)
		(property "Public" "False"
			(at 608.5 271.626 0)
			(layer "F.Fab")
			(hide yes)
			(effects
				(font
					(size 1 1)
					(thickness 0.15)
				)
			)
		)
		(property "Tolerance" "1%"
			(at 608.5 271.626 0)
			(layer "F.Fab")
			(hide yes)
			(effects
				(font
					(size 1 1)
					(thickness 0.15)
				)
			)
		)
		(property "Val" "0R001"
			(at 608.5 271.626 0)
			(layer "F.Fab")
			(hide yes)
			(effects
				(font
					(size 1 1)
					(thickness 0.15)
				)
			)
		)
		(sheetname "Power")
		(sheetfile "power.kicad_sch")
		(attr smd)
		(fp_line
			(start -0.3 -0.701)
			(end 0.298 -0.701)
			(stroke
				(width 0.15)
				(type solid)
			)
			(layer "F.SilkS")
		)
		(fp_line
			(start -0.32 0.699)
			(end 0.28 0.699)
			(stroke
				(width 0.15)
				(type solid)
			)
			(layer "F.SilkS")
		)
		(fp_rect
			(start 1.95 -0.9)
			(end -1.95 0.9)
			(stroke
				(width 0.05)
				(type default)
			)
			(fill no)
			(layer "F.CrtYd")
		)
		(fp_line
			(start 0.949 -0.677)
			(end 0.949 0.675)
			(stroke
				(width 0.15)
				(type solid)
			)
			(layer "F.Fab")
		)
		(fp_line
			(start -0.951 0.68)
			(end 0.949 0.68)
			(stroke
				(width 0.15)
				(type solid)
			)
			(layer "F.Fab")
		)
		(fp_line
			(start -0.951 -0.677)
			(end -0.951 0.675)
			(stroke
				(width 0.15)
				(type solid)
			)
			(layer "F.Fab")
		)
		(fp_line
			(start -0.951 -0.682)
			(end 0.949 -0.682)
			(stroke
				(width 0.15)
				(type solid)
			)
			(layer "F.Fab")
		)
		(pad "1" smd roundrect
			(at -1.1 0 180)
			(size 1.2 1.3)
			(layers "F.Cu" "F.Mask" "F.Paste")
			(roundrect_rratio 0.25)
			(net 76 "Net-(C63-Pad2)")
			(pintype "passive")
			(teardrops
				(best_length_ratio 0.2)
				(max_length 1)
				(best_width_ratio 0.9)
				(max_width 2)
				(curved_edges yes)
				(filter_ratio 0.9)
				(enabled yes)
				(allow_two_segments yes)
				(prefer_zone_connections yes)
			)
		)
		(pad "2" smd roundrect
			(at 1.1 0 180)
			(size 1.2 1.3)
			(layers "F.Cu" "F.Mask" "F.Paste")
			(roundrect_rratio 0.25)
			(net 78 "+1V8")
			(pintype "passive")
			(teardrops
				(best_length_ratio 0.2)
				(max_length 1)
				(best_width_ratio 0.9)
				(max_width 2)
				(curved_edges yes)
				(filter_ratio 0.9)
				(enabled yes)
				(allow_two_segments yes)
				(prefer_zone_connections yes)
			)
		)
	)
	(footprint "antmicro-footprints:R_0402_1005Metric"
		(layer "F.Cu")
		(at 142.37 145.05)
		(descr "Resistor SMD 0402")
		(tags "resistor SMD 0402")
		(property "Reference" "R248"
			(at -3.72 1.16 0)
			(layer "F.SilkS")
			(effects
				(font
					(size 0.7 0.7)
					(thickness 0.15)
				)
				(justify left bottom)
			)
		)
		(property "Value" "R_0R_0402"
			(at -1.011843 1.772047 0)
			(layer "F.Fab")
			(effects
				(font
					(size 0.7 0.7)
					(thickness 0.15)
				)
				(justify left bottom)
			)
		)
		(property "Datasheet" "https://industrial.panasonic.com/cdbs/www-data/pdf/RDA0000/AOA0000C301.pdf"
			(at 0 0 0)
			(layer "F.Fab")
			(hide yes)
			(effects
				(font
					(size 1.27 1.27)
					(thickness 0.15)
				)
			)
		)
		(property "Author" "Antmicro"
			(at 0 0 0)
			(layer "F.Fab")
			(hide yes)
			(effects
				(font
					(size 1 1)
					(thickness 0.15)
				)
			)
		)
		(property "Current" "1A"
			(at 0 0 0)
			(layer "F.Fab")
			(hide yes)
			(effects
				(font
					(size 1 1)
					(thickness 0.15)
				)
			)
		)
		(property "License" "Apache-2.0"
			(at 0 0 0)
			(layer "F.Fab")
			(hide yes)
			(effects
				(font
					(size 1 1)
					(thickness 0.15)
				)
			)
		)
		(property "MPN" "ERJ2GE0R00X"
			(at 0 0 0)
			(layer "F.Fab")
			(hide yes)
			(effects
				(font
					(size 1 1)
					(thickness 0.15)
				)
			)
		)
		(property "Manufacturer" "Panasonic"
			(at 0 0 0)
			(layer "F.Fab")
			(hide yes)
			(effects
				(font
					(size 1 1)
					(thickness 0.15)
				)
			)
		)
		(property "Public" "False"
			(at 0 0 0)
			(layer "F.Fab")
			(hide yes)
			(effects
				(font
					(size 1 1)
					(thickness 0.15)
				)
			)
		)
		(property "Tolerance" ""
			(at 0 0 0)
			(layer "F.Fab")
			(hide yes)
			(effects
				(font
					(size 1 1)
					(thickness 0.15)
				)
			)
		)
		(property "Val" "0R"
			(at 0 0 0)
			(layer "F.Fab")
			(hide yes)
			(effects
				(font
					(size 1 1)
					(thickness 0.15)
				)
			)
		)
		(sheetname "KR to SFI #1")
		(sheetfile "kr_sfi.kicad_sch")
		(attr smd)
		(fp_rect
			(start -0.925 -0.47)
			(end 0.925 0.47)
			(stroke
				(width 0.05)
				(type default)
			)
			(fill no)
			(layer "F.CrtYd")
		)
		(fp_rect
			(start -0.5 -0.25)
			(end 0.5 0.25)
			(stroke
				(width 0.15)
				(type solid)
			)
			(fill no)
			(layer "F.Fab")
		)
		(pad "1" smd roundrect
			(at -0.48 0)
			(size 0.59 0.64)
			(layers "F.Cu" "F.Mask" "F.Paste")
			(roundrect_rratio 0.25)
			(net 650 "/2xSFP+/KR to SFI #1/MDC_R")
			(pintype "passive")
			(teardrops
				(best_length_ratio 0.2)
				(max_length 1)
				(best_width_ratio 0.9)
				(max_width 2)
				(curved_edges yes)
				(filter_ratio 0.9)
				(enabled yes)
				(allow_two_segments yes)
				(prefer_zone_connections yes)
			)
		)
		(pad "2" smd roundrect
			(at 0.48 0)
			(size 0.59 0.64)
			(layers "F.Cu" "F.Mask" "F.Paste")
			(roundrect_rratio 0.25)
			(net 651 "/2xSFP+/KR to SFI #1/MDC")
			(pintype "passive")
			(teardrops
				(best_length_ratio 0.2)
				(max_length 1)
				(best_width_ratio 0.9)
				(max_width 2)
				(curved_edges yes)
				(filter_ratio 0.9)
				(enabled yes)
				(allow_two_segments yes)
				(prefer_zone_connections yes)
			)
		)
	)
	(footprint "antmicro-footprints:R_0402_1005Metric"
		(layer "F.Cu")
		(at 221.16 129.65)
		(descr "Resistor SMD 0402")
		(tags "resistor SMD 0402")
		(property "Reference" "R201"
			(at 0.79 0.46 0)
			(layer "F.SilkS")
			(effects
				(font
					(size 0.7 0.7)
					(thickness 0.15)
				)
				(justify left bottom)
			)
		)
		(property "Value" "R_0R_0402"
			(at -1.011843 1.772047 0)
			(layer "F.Fab")
			(effects
				(font
					(size 0.7 0.7)
					(thickness 0.15)
				)
				(justify left bottom)
			)
		)
		(property "Datasheet" "https://industrial.panasonic.com/cdbs/www-data/pdf/RDA0000/AOA0000C301.pdf"
			(at 0 0 0)
			(layer "F.Fab")
			(hide yes)
			(effects
				(font
					(size 1.27 1.27)
					(thickness 0.15)
				)
			)
		)
		(property "Author" "Antmicro"
			(at 0 0 0)
			(layer "F.Fab")
			(hide yes)
			(effects
				(font
					(size 1 1)
					(thickness 0.15)
				)
			)
		)
		(property "Current" "1A"
			(at 0 0 0)
			(layer "F.Fab")
			(hide yes)
			(effects
				(font
					(size 1 1)
					(thickness 0.15)
				)
			)
		)
		(property "License" "Apache-2.0"
			(at 0 0 0)
			(layer "F.Fab")
			(hide yes)
			(effects
				(font
					(size 1 1)
					(thickness 0.15)
				)
			)
		)
		(property "MPN" "ERJ2GE0R00X"
			(at 0 0 0)
			(layer "F.Fab")
			(hide yes)
			(effects
				(font
					(size 1 1)
					(thickness 0.15)
				)
			)
		)
		(property "Manufacturer" "Panasonic"
			(at 0 0 0)
			(layer "F.Fab")
			(hide yes)
			(effects
				(font
					(size 1 1)
					(thickness 0.15)
				)
			)
		)
		(property "Public" "False"
			(at 0 0 0)
			(layer "F.Fab")
			(hide yes)
			(effects
				(font
					(size 1 1)
					(thickness 0.15)
				)
			)
		)
		(property "Tolerance" ""
			(at 0 0 0)
			(layer "F.Fab")
			(hide yes)
			(effects
				(font
					(size 1 1)
					(thickness 0.15)
				)
			)
		)
		(property "Val" "0R"
			(at 0 0 0)
			(layer "F.Fab")
			(hide yes)
			(effects
				(font
					(size 1 1)
					(thickness 0.15)
				)
			)
		)
		(sheetname "PCIe misc")
		(sheetfile "pcie_misc.kicad_sch")
		(attr smd)
		(fp_rect
			(start -0.925 -0.47)
			(end 0.925 0.47)
			(stroke
				(width 0.05)
				(type default)
			)
			(fill no)
			(layer "F.CrtYd")
		)
		(fp_rect
			(start -0.5 -0.25)
			(end 0.5 0.25)
			(stroke
				(width 0.15)
				(type solid)
			)
			(fill no)
			(layer "F.Fab")
		)
		(pad "1" smd roundrect
			(at -0.48 0)
			(size 0.59 0.64)
			(layers "F.Cu" "F.Mask" "F.Paste")
			(roundrect_rratio 0.25)
			(net 620 "/PCIe misc/DIF4-")
			(pintype "passive")
			(teardrops
				(best_length_ratio 0.2)
				(max_length 1)
				(best_width_ratio 0.9)
				(max_width 2)
				(curved_edges yes)
				(filter_ratio 0.9)
				(enabled yes)
				(allow_two_segments yes)
				(prefer_zone_connections yes)
			)
		)
		(pad "2" smd roundrect
			(at 0.48 0)
			(size 0.59 0.64)
			(layers "F.Cu" "F.Mask" "F.Paste")
			(roundrect_rratio 0.25)
			(net 271 "/M.2 key M #2/PCIE_{REF}.CK-")
			(pintype "passive")
			(teardrops
				(best_length_ratio 0.2)
				(max_length 1)
				(best_width_ratio 0.9)
				(max_width 2)
				(curved_edges yes)
				(filter_ratio 0.9)
				(enabled yes)
				(allow_two_segments yes)
				(prefer_zone_connections yes)
			)
		)
	)
	(footprint "antmicro-footprints:QFN-24-1EP_4x4mm_P0.5_EP2.1x2.1mm"
		(layer "F.Cu")
		(at 159.3 160.61)
		(property "Reference" "U5"
			(at 0.699 3.437 0)
			(layer "F.SilkS")
			(effects
				(font
					(size 0.7 0.7)
					(thickness 0.15)
				)
				(justify left bottom)
			)
		)
		(property "Value" "PCA9539AHF"
			(at 0 3.4 0)
			(layer "F.Fab")
			(effects
				(font
					(size 0.7 0.7)
					(thickness 0.15)
				)
				(justify left bottom)
			)
		)
		(property "Datasheet" "https://www.nxp.com/docs/en/data-sheet/PCA9539A.pdf"
			(at 0 0 0)
			(layer "F.Fab")
			(hide yes)
			(effects
				(font
					(size 1.27 1.27)
					(thickness 0.15)
				)
			)
		)
		(property "Author" "Antmicro"
			(at 0 0 0)
			(layer "F.Fab")
			(hide yes)
			(effects
				(font
					(size 1 1)
					(thickness 0.15)
				)
			)
		)
		(property "License" "Apache-2.0"
			(at 0 0 0)
			(layer "F.Fab")
			(hide yes)
			(effects
				(font
					(size 1 1)
					(thickness 0.15)
				)
			)
		)
		(property "MPN" "PCA9539AHF,128"
			(at 0 0 0)
			(layer "F.Fab")
			(hide yes)
			(effects
				(font
					(size 1 1)
					(thickness 0.15)
				)
			)
		)
		(property "Manufacturer" "NXP"
			(at 0 0 0)
			(layer "F.Fab")
			(hide yes)
			(effects
				(font
					(size 1 1)
					(thickness 0.15)
				)
			)
		)
		(property ki_fp_filters "VFQFN-16-1EP_3x3mm")
		(sheetname "2xSFP+")
		(sheetfile "2xSFP+.kicad_sch")
		(attr smd)
		(fp_line
			(start -2.11 -1.636)
			(end -2.11 -2.11)
			(stroke
				(width 0.15)
				(type solid)
			)
			(layer "F.SilkS")
		)
		(fp_line
			(start -2.11 2.108)
			(end -2.11 1.634)
			(stroke
				(width 0.15)
				(type solid)
			)
			(layer "F.SilkS")
		)
		(fp_line
			(start -1.635 -2.11)
			(end -2.11 -2.11)
			(stroke
				(width 0.15)
				(type solid)
			)
			(layer "F.SilkS")
		)
		(fp_line
			(start -1.635 2.108)
			(end -2.11 2.108)
			(stroke
				(width 0.15)
				(type solid)
			)
			(layer "F.SilkS")
		)
		(fp_line
			(start 1.634 -2.11)
			(end 2.108 -2.11)
			(stroke
				(width 0.15)
				(type solid)
			)
			(layer "F.SilkS")
		)
		(fp_line
			(start 1.634 2.108)
			(end 2.108 2.108)
			(stroke
				(width 0.15)
				(type solid)
			)
			(layer "F.SilkS")
		)
		(fp_line
			(start 2.108 -2.11)
			(end 2.108 -1.635)
			(stroke
				(width 0.15)
				(type solid)
			)
			(layer "F.SilkS")
		)
		(fp_line
			(start 2.108 2.108)
			(end 2.108 1.634)
			(stroke
				(width 0.15)
				(type solid)
			)
			(layer "F.SilkS")
		)
		(fp_circle
			(center -2.3 -2.3)
			(end -2.25 -2.3)
			(stroke
				(width 0.15)
				(type solid)
			)
			(fill yes)
			(layer "F.SilkS")
		)
		(fp_rect
			(start -2.503 -2.503)
			(end 2.5 2.5)
			(stroke
				(width 0.05)
				(type solid)
			)
			(fill no)
			(layer "F.CrtYd")
		)
		(fp_line
			(start -2 -1)
			(end -1 -2)
			(stroke
				(width 0.15)
				(type solid)
			)
			(layer "F.Fab")
		)
		(fp_line
			(start -2 1.999)
			(end -2 -1)
			(stroke
				(width 0.15)
				(type solid)
			)
			(layer "F.Fab")
		)
		(fp_line
			(start -1 -2)
			(end 1.999 -2)
			(stroke
				(width 0.15)
				(type solid)
			)
			(layer "F.Fab")
		)
		(fp_line
			(start 1.999 -2)
			(end 1.999 1.999)
			(stroke
				(width 0.15)
				(type solid)
			)
			(layer "F.Fab")
		)
		(fp_line
			(start 1.999 1.999)
			(end -2 1.999)
			(stroke
				(width 0.15)
				(type solid)
			)
			(layer "F.Fab")
		)
		(pad "" smd roundrect
			(at -0.5 -0.5)
			(size 0.8 0.8)
			(layers "F.Paste")
			(roundrect_rratio 0.238095)
			(teardrops
				(best_length_ratio 0.2)
				(max_length 1)
				(best_width_ratio 0.9)
				(max_width 2)
				(curved_edges yes)
				(filter_ratio 0.9)
				(enabled yes)
				(allow_two_segments yes)
				(prefer_zone_connections yes)
			)
		)
		(pad "" smd roundrect
			(at -0.5 0.5)
			(size 0.8 0.8)
			(layers "F.Paste")
			(roundrect_rratio 0.238095)
			(teardrops
				(best_length_ratio 0.2)
				(max_length 1)
				(best_width_ratio 0.9)
				(max_width 2)
				(curved_edges yes)
				(filter_ratio 0.9)
				(enabled yes)
				(allow_two_segments yes)
				(prefer_zone_connections yes)
			)
		)
		(pad "" smd roundrect
			(at 0.5 -0.5)
			(size 0.8 0.8)
			(layers "F.Paste")
			(roundrect_rratio 0.238095)
			(teardrops
				(best_length_ratio 0.2)
				(max_length 1)
				(best_width_ratio 0.9)
				(max_width 2)
				(curved_edges yes)
				(filter_ratio 0.9)
				(enabled yes)
				(allow_two_segments yes)
				(prefer_zone_connections yes)
			)
		)
		(pad "" smd roundrect
			(at 0.5 0.5)
			(size 0.8 0.8)
			(layers "F.Paste")
			(roundrect_rratio 0.238095)
			(teardrops
				(best_length_ratio 0.2)
				(max_length 1)
				(best_width_ratio 0.9)
				(max_width 2)
				(curved_edges yes)
				(filter_ratio 0.9)
				(enabled yes)
				(allow_two_segments yes)
				(prefer_zone_connections yes)
			)
		)
		(pad "1" smd roundrect
			(at -1.938 -1.25)
			(size 0.825 0.25)
			(layers "F.Cu" "F.Mask" "F.Paste")
			(roundrect_rratio 0.25)
			(net 562 "/2xSFP+/~{LED0_0}")
			(pinfunction "IO0_0")
			(pintype "bidirectional")
			(teardrops
				(best_length_ratio 0.2)
				(max_length 1)
				(best_width_ratio 0.9)
				(max_width 2)
				(curved_edges yes)
				(filter_ratio 0.9)
				(enabled yes)
				(allow_two_segments yes)
				(prefer_zone_connections yes)
			)
		)
		(pad "2" smd roundrect
			(at -1.938 -0.75)
			(size 0.825 0.25)
			(layers "F.Cu" "F.Mask" "F.Paste")
			(roundrect_rratio 0.25)
			(net 563 "/2xSFP+/~{LED0_1}")
			(pinfunction "IO0_1")
			(pintype "bidirectional")
			(teardrops
				(best_length_ratio 0.2)
				(max_length 1)
				(best_width_ratio 0.9)
				(max_width 2)
				(curved_edges yes)
				(filter_ratio 0.9)
				(enabled yes)
				(allow_two_segments yes)
				(prefer_zone_connections yes)
			)
		)
		(pad "3" smd roundrect
			(at -1.938 -0.25)
			(size 0.825 0.25)
			(layers "F.Cu" "F.Mask" "F.Paste")
			(roundrect_rratio 0.25)
			(net 564 "/2xSFP+/~{LED0_2}")
			(pinfunction "IO0_2")
			(pintype "bidirectional")
			(teardrops
				(best_length_ratio 0.2)
				(max_length 1)
				(best_width_ratio 0.9)
				(max_width 2)
				(curved_edges yes)
				(filter_ratio 0.9)
				(enabled yes)
				(allow_two_segments yes)
				(prefer_zone_connections yes)
			)
		)
		(pad "4" smd roundrect
			(at -1.938 0.248)
			(size 0.825 0.25)
			(layers "F.Cu" "F.Mask" "F.Paste")
			(roundrect_rratio 0.25)
			(net 565 "/2xSFP+/~{LED1_0}")
			(pinfunction "IO0_3")
			(pintype "bidirectional")
			(teardrops
				(best_length_ratio 0.2)
				(max_length 1)
				(best_width_ratio 0.9)
				(max_width 2)
				(curved_edges yes)
				(filter_ratio 0.9)
				(enabled yes)
				(allow_two_segments yes)
				(prefer_zone_connections yes)
			)
		)
		(pad "5" smd roundrect
			(at -1.938 0.748)
			(size 0.825 0.25)
			(layers "F.Cu" "F.Mask" "F.Paste")
			(roundrect_rratio 0.25)
			(net 566 "/2xSFP+/~{LED1_1}")
			(pinfunction "IO0_4")
			(pintype "bidirectional")
			(teardrops
				(best_length_ratio 0.2)
				(max_length 1)
				(best_width_ratio 0.9)
				(max_width 2)
				(curved_edges yes)
				(filter_ratio 0.9)
				(enabled yes)
				(allow_two_segments yes)
				(prefer_zone_connections yes)
			)
		)
		(pad "6" smd roundrect
			(at -1.938 1.249)
			(size 0.825 0.25)
			(layers "F.Cu" "F.Mask" "F.Paste")
			(roundrect_rratio 0.25)
			(net 567 "/2xSFP+/~{LED1_2}")
			(pinfunction "IO0_5")
			(pintype "bidirectional")
			(teardrops
				(best_length_ratio 0.2)
				(max_length 1)
				(best_width_ratio 0.9)
				(max_width 2)
				(curved_edges yes)
				(filter_ratio 0.9)
				(enabled yes)
				(allow_two_segments yes)
				(prefer_zone_connections yes)
			)
		)
		(pad "7" smd roundrect
			(at -1.25 1.937)
			(size 0.25 0.825)
			(layers "F.Cu" "F.Mask" "F.Paste")
			(roundrect_rratio 0.25)
			(net 697 "Net-(U5-IO0_6)")
			(pinfunction "IO0_6")
			(pintype "bidirectional")
			(teardrops
				(best_length_ratio 0.2)
				(max_length 1)
				(best_width_ratio 0.9)
				(max_width 2)
				(curved_edges yes)
				(filter_ratio 0.9)
				(enabled yes)
				(allow_two_segments yes)
				(prefer_zone_connections yes)
			)
		)
		(pad "8" smd roundrect
			(at -0.75 1.937)
			(size 0.25 0.825)
			(layers "F.Cu" "F.Mask" "F.Paste")
			(roundrect_rratio 0.25)
			(net 698 "Net-(U5-IO0_7)")
			(pinfunction "IO0_7")
			(pintype "bidirectional")
			(teardrops
				(best_length_ratio 0.2)
				(max_length 1)
				(best_width_ratio 0.9)
				(max_width 2)
				(curved_edges yes)
				(filter_ratio 0.9)
				(enabled yes)
				(allow_two_segments yes)
				(prefer_zone_connections yes)
			)
		)
		(pad "9" smd roundrect
			(at -0.25 1.937)
			(size 0.25 0.825)
			(layers "F.Cu" "F.Mask" "F.Paste")
			(roundrect_rratio 0.25)
			(net 1 "GND")
			(pinfunction "GND")
			(pintype "power_in")
			(teardrops
				(best_length_ratio 0.2)
				(max_length 1)
				(best_width_ratio 0.9)
				(max_width 2)
				(curved_edges yes)
				(filter_ratio 0.9)
				(enabled no)
				(allow_two_segments yes)
				(prefer_zone_connections yes)
			)
		)
		(pad "10" smd roundrect
			(at 0.248 1.937)
			(size 0.25 0.825)
			(layers "F.Cu" "F.Mask" "F.Paste")
			(roundrect_rratio 0.25)
			(net 760 "unconnected-(U5-IO1_0-Pad10)")
			(pinfunction "IO1_0")
			(pintype "bidirectional+no_connect")
			(teardrops
				(best_length_ratio 0.2)
				(max_length 1)
				(best_width_ratio 0.9)
				(max_width 2)
				(curved_edges yes)
				(filter_ratio 0.9)
				(enabled yes)
				(allow_two_segments yes)
				(prefer_zone_connections yes)
			)
		)
		(pad "11" smd roundrect
			(at 0.748 1.937)
			(size 0.25 0.825)
			(layers "F.Cu" "F.Mask" "F.Paste")
			(roundrect_rratio 0.25)
			(net 761 "unconnected-(U5-IO1_1-Pad11)")
			(pinfunction "IO1_1")
			(pintype "bidirectional+no_connect")
			(teardrops
				(best_length_ratio 0.2)
				(max_length 1)
				(best_width_ratio 0.9)
				(max_width 2)
				(curved_edges yes)
				(filter_ratio 0.9)
				(enabled yes)
				(allow_two_segments yes)
				(prefer_zone_connections yes)
			)
		)
		(pad "12" smd roundrect
			(at 1.249 1.937)
			(size 0.25 0.825)
			(layers "F.Cu" "F.Mask" "F.Paste")
			(roundrect_rratio 0.25)
			(net 762 "unconnected-(U5-IO1_2-Pad12)")
			(pinfunction "IO1_2")
			(pintype "bidirectional+no_connect")
			(teardrops
				(best_length_ratio 0.2)
				(max_length 1)
				(best_width_ratio 0.9)
				(max_width 2)
				(curved_edges yes)
				(filter_ratio 0.9)
				(enabled yes)
				(allow_two_segments yes)
				(prefer_zone_connections yes)
			)
		)
		(pad "13" smd roundrect
			(at 1.937 1.249)
			(size 0.825 0.25)
			(layers "F.Cu" "F.Mask" "F.Paste")
			(roundrect_rratio 0.25)
			(net 763 "unconnected-(U5-IO1_3-Pad13)")
			(pinfunction "IO1_3")
			(pintype "bidirectional+no_connect")
			(teardrops
				(best_length_ratio 0.2)
				(max_length 1)
				(best_width_ratio 0.9)
				(max_width 2)
				(curved_edges yes)
				(filter_ratio 0.9)
				(enabled yes)
				(allow_two_segments yes)
				(prefer_zone_connections yes)
			)
		)
		(pad "14" smd roundrect
			(at 1.937 0.748)
			(size 0.825 0.25)
			(layers "F.Cu" "F.Mask" "F.Paste")
			(roundrect_rratio 0.25)
			(net 764 "unconnected-(U5-IO1_4-Pad14)")
			(pinfunction "IO1_4")
			(pintype "bidirectional+no_connect")
			(teardrops
				(best_length_ratio 0.2)
				(max_length 1)
				(best_width_ratio 0.9)
				(max_width 2)
				(curved_edges yes)
				(filter_ratio 0.9)
				(enabled yes)
				(allow_two_segments yes)
				(prefer_zone_connections yes)
			)
		)
		(pad "15" smd roundrect
			(at 1.937 0.248)
			(size 0.825 0.25)
			(layers "F.Cu" "F.Mask" "F.Paste")
			(roundrect_rratio 0.25)
			(net 765 "unconnected-(U5-IO1_5-Pad15)")
			(pinfunction "IO1_5")
			(pintype "bidirectional+no_connect")
			(teardrops
				(best_length_ratio 0.2)
				(max_length 1)
				(best_width_ratio 0.9)
				(max_width 2)
				(curved_edges yes)
				(filter_ratio 0.9)
				(enabled yes)
				(allow_two_segments yes)
				(prefer_zone_connections yes)
			)
		)
		(pad "16" smd roundrect
			(at 1.937 -0.25)
			(size 0.825 0.25)
			(layers "F.Cu" "F.Mask" "F.Paste")
			(roundrect_rratio 0.25)
			(net 766 "unconnected-(U5-IO1_6-Pad16)")
			(pinfunction "IO1_6")
			(pintype "bidirectional+no_connect")
			(teardrops
				(best_length_ratio 0.2)
				(max_length 1)
				(best_width_ratio 0.9)
				(max_width 2)
				(curved_edges yes)
				(filter_ratio 0.9)
				(enabled yes)
				(allow_two_segments yes)
				(prefer_zone_connections yes)
			)
		)
		(pad "17" smd roundrect
			(at 1.937 -0.75)
			(size 0.825 0.25)
			(layers "F.Cu" "F.Mask" "F.Paste")
			(roundrect_rratio 0.25)
			(net 767 "unconnected-(U5-IO1_7-Pad17)")
			(pinfunction "IO1_7")
			(pintype "bidirectional+no_connect")
			(teardrops
				(best_length_ratio 0.2)
				(max_length 1)
				(best_width_ratio 0.9)
				(max_width 2)
				(curved_edges yes)
				(filter_ratio 0.9)
				(enabled yes)
				(allow_two_segments yes)
				(prefer_zone_connections yes)
			)
		)
		(pad "18" smd roundrect
			(at 1.937 -1.25)
			(size 0.825 0.25)
			(layers "F.Cu" "F.Mask" "F.Paste")
			(roundrect_rratio 0.25)
			(net 557 "Net-(U5-A0)")
			(pinfunction "A0")
			(pintype "input")
			(teardrops
				(best_length_ratio 0.2)
				(max_length 1)
				(best_width_ratio 0.9)
				(max_width 2)
				(curved_edges yes)
				(filter_ratio 0.9)
				(enabled yes)
				(allow_two_segments yes)
				(prefer_zone_connections yes)
			)
		)
		(pad "19" smd roundrect
			(at 1.249 -1.938)
			(size 0.25 0.825)
			(layers "F.Cu" "F.Mask" "F.Paste")
			(roundrect_rratio 0.25)
			(net 559 "Net-(U5-SCL)")
			(pinfunction "SCL")
			(pintype "input")
			(teardrops
				(best_length_ratio 0.2)
				(max_length 1)
				(best_width_ratio 0.9)
				(max_width 2)
				(curved_edges yes)
				(filter_ratio 0.9)
				(enabled yes)
				(allow_two_segments yes)
				(prefer_zone_connections yes)
			)
		)
		(pad "20" smd roundrect
			(at 0.748 -1.938)
			(size 0.25 0.825)
			(layers "F.Cu" "F.Mask" "F.Paste")
			(roundrect_rratio 0.25)
			(net 558 "Net-(U5-SDA)")
			(pinfunction "SDA")
			(pintype "bidirectional")
			(teardrops
				(best_length_ratio 0.2)
				(max_length 1)
				(best_width_ratio 0.9)
				(max_width 2)
				(curved_edges yes)
				(filter_ratio 0.9)
				(enabled yes)
				(allow_two_segments yes)
				(prefer_zone_connections yes)
			)
		)
		(pad "21" smd roundrect
			(at 0.248 -1.938)
			(size 0.25 0.825)
			(layers "F.Cu" "F.Mask" "F.Paste")
			(roundrect_rratio 0.25)
			(net 2 "+3V3")
			(pinfunction "VDD")
			(pintype "power_in")
			(teardrops
				(best_length_ratio 0.2)
				(max_length 1)
				(best_width_ratio 0.9)
				(max_width 2)
				(curved_edges yes)
				(filter_ratio 0.9)
				(enabled yes)
				(allow_two_segments yes)
				(prefer_zone_connections yes)
			)
		)
		(pad "22" smd roundrect
			(at -0.25 -1.938)
			(size 0.25 0.825)
			(layers "F.Cu" "F.Mask" "F.Paste")
			(roundrect_rratio 0.25)
			(net 768 "unconnected-(U5-~{INT}-Pad22)")
			(pinfunction "~{INT}")
			(pintype "output+no_connect")
			(teardrops
				(best_length_ratio 0.2)
				(max_length 1)
				(best_width_ratio 0.9)
				(max_width 2)
				(curved_edges yes)
				(filter_ratio 0.9)
				(enabled yes)
				(allow_two_segments yes)
				(prefer_zone_connections yes)
			)
		)
		(pad "23" smd roundrect
			(at -0.75 -1.938)
			(size 0.25 0.825)
			(layers "F.Cu" "F.Mask" "F.Paste")
			(roundrect_rratio 0.25)
			(net 561 "Net-(U5-A1)")
			(pinfunction "A1")
			(pintype "input")
			(teardrops
				(best_length_ratio 0.2)
				(max_length 1)
				(best_width_ratio 0.9)
				(max_width 2)
				(curved_edges yes)
				(filter_ratio 0.9)
				(enabled yes)
				(allow_two_segments yes)
				(prefer_zone_connections yes)
			)
		)
		(pad "24" smd roundrect
			(at -1.25 -1.938)
			(size 0.25 0.825)
			(layers "F.Cu" "F.Mask" "F.Paste")
			(roundrect_rratio 0.25)
			(net 560 "Net-(U5-~{RESET})")
			(pinfunction "~{RESET}")
			(pintype "input")
			(teardrops
				(best_length_ratio 0.2)
				(max_length 1)
				(best_width_ratio 0.9)
				(max_width 2)
				(curved_edges yes)
				(filter_ratio 0.9)
				(enabled yes)
				(allow_two_segments yes)
				(prefer_zone_connections yes)
			)
		)
		(pad "25" smd rect
			(at 0 0)
			(size 2.1 2.1)
			(layers "F.Cu" "F.Mask")
			(net 1 "GND")
			(pinfunction "GND")
			(pintype "passive")
			(teardrops
				(best_length_ratio 0.2)
				(max_length 1)
				(best_width_ratio 0.9)
				(max_width 2)
				(curved_edges yes)
				(filter_ratio 0.9)
				(enabled no)
				(allow_two_segments yes)
				(prefer_zone_connections yes)
			)
		)
	)
	(footprint "antmicro-footprints:QFN-16-1EP_4x4mm_P0.65mm"
		(layer "F.Cu")
		(at 115.159999 75.825 -90)
		(property "Reference" "U6"
			(at -2.365 0.709999 180)
			(layer "F.SilkS")
			(effects
				(font
					(size 0.7 0.7)
					(thickness 0.15)
				)
				(justify right bottom)
			)
		)
		(property "Value" "FT230X_QFN"
			(at 0 3.3 90)
			(layer "F.Fab")
			(effects
				(font
					(size 0.7 0.7)
					(thickness 0.15)
				)
				(justify right bottom)
			)
		)
		(property "Datasheet" "https://ftdichip.com/wp-content/uploads/2021/10/DS_FT230X.pdf"
			(at 0 0 270)
			(layer "F.Fab")
			(hide yes)
			(effects
				(font
					(size 1.27 1.27)
					(thickness 0.15)
				)
			)
		)
		(property "Author" "Antmicro"
			(at 39.334999 190.984999 0)
			(layer "F.Fab")
			(hide yes)
			(effects
				(font
					(size 1 1)
					(thickness 0.15)
				)
			)
		)
		(property "License" "Apache-2.0"
			(at 39.334999 190.984999 0)
			(layer "F.Fab")
			(hide yes)
			(effects
				(font
					(size 1 1)
					(thickness 0.15)
				)
			)
		)
		(property "MPN" "FT230XQ-R"
			(at 39.334999 190.984999 0)
			(layer "F.Fab")
			(hide yes)
			(effects
				(font
					(size 1 1)
					(thickness 0.15)
				)
			)
		)
		(property "Manufacturer" "FTDI Chip"
			(at 39.334999 190.984999 0)
			(layer "F.Fab")
			(hide yes)
			(effects
				(font
					(size 1 1)
					(thickness 0.15)
				)
			)
		)
		(sheetname "USB-C console")
		(sheetfile "usb-c_console.kicad_sch")
		(attr smd)
		(fp_line
			(start -2.101 2.1)
			(end -1.5 2.1)
			(stroke
				(width 0.15)
				(type solid)
			)
			(layer "F.SilkS")
		)
		(fp_line
			(start 1.499 2.1)
			(end 2.1 2.1)
			(stroke
				(width 0.15)
				(type solid)
			)
			(layer "F.SilkS")
		)
		(fp_line
			(start 2.1 2.1)
			(end 2.1 1.398)
			(stroke
				(width 0.15)
				(type solid)
			)
			(layer "F.SilkS")
		)
		(fp_line
			(start -2.101 1.398)
			(end -2.101 2.1)
			(stroke
				(width 0.15)
				(type solid)
			)
			(layer "F.SilkS")
		)
		(fp_line
			(start -2.1 -2.1)
			(end -2.101 -1.4)
			(stroke
				(width 0.15)
				(type solid)
			)
			(layer "F.SilkS")
		)
		(fp_line
			(start -1.4 -2.1)
			(end -2.1 -2.1)
			(stroke
				(width 0.15)
				(type solid)
			)
			(layer "F.SilkS")
		)
		(fp_line
			(start 1.499 -2.101)
			(end 2.1 -2.101)
			(stroke
				(width 0.15)
				(type solid)
			)
			(layer "F.SilkS")
		)
		(fp_line
			(start 2.1 -2.101)
			(end 2.1 -1.401)
			(stroke
				(width 0.15)
				(type solid)
			)
			(layer "F.SilkS")
		)
		(fp_circle
			(center -2.35 -1.4)
			(end -2.3 -1.4)
			(stroke
				(width 0.15)
				(type solid)
			)
			(fill yes)
			(layer "F.SilkS")
		)
		(fp_rect
			(start -2.35 -2.35)
			(end 2.35 2.35)
			(stroke
				(width 0.05)
				(type solid)
			)
			(fill no)
			(layer "F.CrtYd")
		)
		(fp_line
			(start -1.5 -2)
			(end -2 -1.5)
			(stroke
				(width 0.15)
				(type solid)
			)
			(layer "F.Fab")
		)
		(fp_rect
			(start 2 2)
			(end -2 -2)
			(stroke
				(width 0.15)
				(type solid)
			)
			(fill no)
			(layer "F.Fab")
		)
		(pad "1" smd rect
			(at -1.9 -0.975 270)
			(size 0.8 0.4)
			(layers "F.Cu" "F.Mask" "F.Paste")
			(net 57 "/USB-C console/FTDI_VCCIO")
			(pinfunction "V_{CCIO}")
			(pintype "power_in")
			(teardrops
				(best_length_ratio 0.2)
				(max_length 1)
				(best_width_ratio 0.9)
				(max_width 2)
				(curved_edges yes)
				(filter_ratio 0.9)
				(enabled yes)
				(allow_two_segments yes)
				(prefer_zone_connections yes)
			)
		)
		(pad "2" smd rect
			(at -1.9 -0.325 270)
			(size 0.8 0.4)
			(layers "F.Cu" "F.Mask" "F.Paste")
			(net 699 "/USB-C console/FTDI_RX")
			(pinfunction "RXD")
			(pintype "input")
			(teardrops
				(best_length_ratio 0.2)
				(max_length 1)
				(best_width_ratio 0.9)
				(max_width 2)
				(curved_edges yes)
				(filter_ratio 0.9)
				(enabled yes)
				(allow_two_segments yes)
				(prefer_zone_connections yes)
			)
		)
		(pad "3" smd rect
			(at -1.9 0.325 270)
			(size 0.8 0.4)
			(layers "F.Cu" "F.Mask" "F.Paste")
			(net 1 "GND")
			(pinfunction "GND")
			(pintype "passive")
			(teardrops
				(best_length_ratio 0.2)
				(max_length 1)
				(best_width_ratio 0.9)
				(max_width 2)
				(curved_edges yes)
				(filter_ratio 0.9)
				(enabled yes)
				(allow_two_segments yes)
				(prefer_zone_connections yes)
			)
		)
		(pad "4" smd rect
			(at -1.9 0.975 270)
			(size 0.8 0.4)
			(layers "F.Cu" "F.Mask" "F.Paste")
			(net 769 "unconnected-(U6-~{CTS}-Pad4)")
			(pinfunction "~{CTS}")
			(pintype "input+no_connect")
			(teardrops
				(best_length_ratio 0.2)
				(max_length 1)
				(best_width_ratio 0.9)
				(max_width 2)
				(curved_edges yes)
				(filter_ratio 0.9)
				(enabled yes)
				(allow_two_segments yes)
				(prefer_zone_connections yes)
			)
		)
		(pad "5" smd rect
			(at -0.975 1.9 270)
			(size 0.4 0.8)
			(layers "F.Cu" "F.Mask" "F.Paste")
			(net 128 "/USB-C console/FTDI_LED_TX")
			(pinfunction "CBUS2")
			(pintype "bidirectional")
			(teardrops
				(best_length_ratio 0.2)
				(max_length 1)
				(best_width_ratio 0.9)
				(max_width 2)
				(curved_edges yes)
				(filter_ratio 0.9)
				(enabled yes)
				(allow_two_segments yes)
				(prefer_zone_connections yes)
			)
		)
		(pad "6" smd rect
			(at -0.325 1.9 270)
			(size 0.4 0.8)
			(layers "F.Cu" "F.Mask" "F.Paste")
			(net 568 "/USB-C console/FTDI_D+")
			(pinfunction "D+")
			(pintype "input")
			(teardrops
				(best_length_ratio 0.2)
				(max_length 1)
				(best_width_ratio 0.9)
				(max_width 2)
				(curved_edges yes)
				(filter_ratio 0.9)
				(enabled yes)
				(allow_two_segments yes)
				(prefer_zone_connections yes)
			)
		)
		(pad "7" smd rect
			(at 0.325 1.9 270)
			(size 0.4 0.8)
			(layers "F.Cu" "F.Mask" "F.Paste")
			(net 569 "/USB-C console/FTDI_D-")
			(pinfunction "D-")
			(pintype "input")
			(teardrops
				(best_length_ratio 0.2)
				(max_length 1)
				(best_width_ratio 0.9)
				(max_width 2)
				(curved_edges yes)
				(filter_ratio 0.9)
				(enabled yes)
				(allow_two_segments yes)
				(prefer_zone_connections yes)
			)
		)
		(pad "8" smd rect
			(at 0.975 1.9 270)
			(size 0.4 0.8)
			(layers "F.Cu" "F.Mask" "F.Paste")
			(net 57 "/USB-C console/FTDI_VCCIO")
			(pinfunction "3V3_{OUT}")
			(pintype "passive")
			(teardrops
				(best_length_ratio 0.2)
				(max_length 1)
				(best_width_ratio 0.9)
				(max_width 2)
				(curved_edges yes)
				(filter_ratio 0.9)
				(enabled yes)
				(allow_two_segments yes)
				(prefer_zone_connections yes)
			)
		)
		(pad "9" smd rect
			(at 1.9 0.975 270)
			(size 0.8 0.4)
			(layers "F.Cu" "F.Mask" "F.Paste")
			(net 570 "Net-(U6-~{RESET})")
			(pinfunction "~{RESET}")
			(pintype "input")
			(teardrops
				(best_length_ratio 0.2)
				(max_length 1)
				(best_width_ratio 0.9)
				(max_width 2)
				(curved_edges yes)
				(filter_ratio 0.9)
				(enabled yes)
				(allow_two_segments yes)
				(prefer_zone_connections yes)
			)
		)
		(pad "10" smd rect
			(at 1.9 0.325 270)
			(size 0.8 0.4)
			(layers "F.Cu" "F.Mask" "F.Paste")
			(net 58 "/USB-C console/VBUS_FTDI")
			(pinfunction "V_{CC}")
			(pintype "power_in")
			(teardrops
				(best_length_ratio 0.2)
				(max_length 1)
				(best_width_ratio 0.9)
				(max_width 2)
				(curved_edges yes)
				(filter_ratio 0.9)
				(enabled yes)
				(allow_two_segments yes)
				(prefer_zone_connections yes)
			)
		)
		(pad "11" smd rect
			(at 1.9 -0.325 270)
			(size 0.8 0.4)
			(layers "F.Cu" "F.Mask" "F.Paste")
			(net 127 "/USB-C console/FTDI_LED_RX")
			(pinfunction "CBUS1")
			(pintype "bidirectional")
			(teardrops
				(best_length_ratio 0.2)
				(max_length 1)
				(best_width_ratio 0.9)
				(max_width 2)
				(curved_edges yes)
				(filter_ratio 0.9)
				(enabled yes)
				(allow_two_segments yes)
				(prefer_zone_connections yes)
			)
		)
		(pad "12" smd rect
			(at 1.9 -0.975 270)
			(size 0.8 0.4)
			(layers "F.Cu" "F.Mask" "F.Paste")
			(net 701 "/USB-C console/FTDI_CBUS0")
			(pinfunction "CBUS0")
			(pintype "bidirectional")
			(teardrops
				(best_length_ratio 0.2)
				(max_length 1)
				(best_width_ratio 0.9)
				(max_width 2)
				(curved_edges yes)
				(filter_ratio 0.9)
				(enabled yes)
				(allow_two_segments yes)
				(prefer_zone_connections yes)
			)
		)
		(pad "13" smd rect
			(at 0.975 -1.9 270)
			(size 0.4 0.8)
			(layers "F.Cu" "F.Mask" "F.Paste")
			(net 1 "GND")
			(pinfunction "GND")
			(pintype "power_in")
			(teardrops
				(best_length_ratio 0.2)
				(max_length 1)
				(best_width_ratio 0.9)
				(max_width 2)
				(curved_edges yes)
				(filter_ratio 0.9)
				(enabled no)
				(allow_two_segments yes)
				(prefer_zone_connections yes)
			)
		)
		(pad "14" smd rect
			(at 0.325 -1.9 270)
			(size 0.4 0.8)
			(layers "F.Cu" "F.Mask" "F.Paste")
			(net 702 "/USB-C console/FTDI_CBUS3")
			(pinfunction "CBUS3")
			(pintype "bidirectional")
			(teardrops
				(best_length_ratio 0.2)
				(max_length 1)
				(best_width_ratio 0.9)
				(max_width 2)
				(curved_edges yes)
				(filter_ratio 0.9)
				(enabled yes)
				(allow_two_segments yes)
				(prefer_zone_connections yes)
			)
		)
		(pad "15" smd rect
			(at -0.325 -1.9 270)
			(size 0.4 0.8)
			(layers "F.Cu" "F.Mask" "F.Paste")
			(net 700 "/USB-C console/FTDI_TX")
			(pinfunction "TXD")
			(pintype "output")
			(teardrops
				(best_length_ratio 0.2)
				(max_length 1)
				(best_width_ratio 0.9)
				(max_width 2)
				(curved_edges yes)
				(filter_ratio 0.9)
				(enabled yes)
				(allow_two_segments yes)
				(prefer_zone_connections yes)
			)
		)
		(pad "16" smd rect
			(at -0.975 -1.9 270)
			(size 0.4 0.8)
			(layers "F.Cu" "F.Mask" "F.Paste")
			(net 770 "unconnected-(U6-~{RTS}-Pad16)")
			(pinfunction "~{RTS}")
			(pintype "output+no_connect")
			(teardrops
				(best_length_ratio 0.2)
				(max_length 1)
				(best_width_ratio 0.9)
				(max_width 2)
				(curved_edges yes)
				(filter_ratio 0.9)
				(enabled yes)
				(allow_two_segments yes)
				(prefer_zone_connections yes)
			)
		)
		(pad "17" smd rect
			(at 0 0 270)
			(size 2.3 2.3)
			(layers "F.Cu" "F.Mask" "F.Paste")
			(net 1 "GND")
			(pinfunction "GND")
			(pintype "passive")
			(teardrops
				(best_length_ratio 0.2)
				(max_length 1)
				(best_width_ratio 0.9)
				(max_width 2)
				(curved_edges yes)
				(filter_ratio 0.9)
				(enabled no)
				(allow_two_segments yes)
				(prefer_zone_connections yes)
			)
		)
	)
	(footprint "antmicro-footprints:R_0201"
		(layer "F.Cu")
		(at 153.33 147.935 -90)
		(descr "Resistor SMD 0201")
		(tags "resistor SMD 0201")
		(property "Reference" "R249"
			(at 6.495 -0.57 270)
			(layer "F.SilkS")
			(effects
				(font
					(size 0.7 0.7)
					(thickness 0.15)
				)
				(justify left bottom)
			)
		)
		(property "Value" "R_0R_0201"
			(at 0 1.25 270)
			(layer "F.Fab")
			(effects
				(font
					(size 0.7 0.7)
					(thickness 0.15)
				)
				(justify left bottom)
			)
		)
		(property "Datasheet" "https://www.bourns.com/docs/product-datasheets/cr.pdf"
			(at 0 0 270)
			(layer "F.Fab")
			(hide yes)
			(effects
				(font
					(size 1.27 1.27)
					(thickness 0.15)
				)
			)
		)
		(property "Author" "Antmicro"
			(at 5.395 301.265 0)
			(layer "F.Fab")
			(hide yes)
			(effects
				(font
					(size 1 1)
					(thickness 0.15)
				)
			)
		)
		(property "License" "Apache-2.0"
			(at 5.395 301.265 0)
			(layer "F.Fab")
			(hide yes)
			(effects
				(font
					(size 1 1)
					(thickness 0.15)
				)
			)
		)
		(property "MPN" "CR0201-FX-0R00GLF"
			(at 5.395 301.265 0)
			(layer "F.Fab")
			(hide yes)
			(effects
				(font
					(size 1 1)
					(thickness 0.15)
				)
			)
		)
		(property "Manufacturer" "Bourns"
			(at 5.395 301.265 0)
			(layer "F.Fab")
			(hide yes)
			(effects
				(font
					(size 1 1)
					(thickness 0.15)
				)
			)
		)
		(property "Tolerance" "1%"
			(at 5.395 301.265 0)
			(layer "F.Fab")
			(hide yes)
			(effects
				(font
					(size 1 1)
					(thickness 0.15)
				)
			)
		)
		(property "Val" "0R"
			(at 5.395 301.265 0)
			(layer "F.Fab")
			(hide yes)
			(effects
				(font
					(size 1 1)
					(thickness 0.15)
				)
			)
		)
		(sheetname "KR to SFI #1")
		(sheetfile "kr_sfi.kicad_sch")
		(attr smd dnp)
		(fp_rect
			(start -0.7 -0.35)
			(end 0.7 0.35)
			(stroke
				(width 0.05)
				(type default)
			)
			(fill no)
			(layer "F.CrtYd")
		)
		(fp_rect
			(start -0.3 -0.15)
			(end 0.298 0.148)
			(stroke
				(width 0.15)
				(type solid)
			)
			(fill no)
			(layer "F.Fab")
		)
		(pad "" smd roundrect
			(at -0.346 0 270)
			(size 0.318 0.36)
			(layers "F.Paste")
			(roundrect_rratio 0.25)
			(teardrops
				(best_length_ratio 0.2)
				(max_length 1)
				(best_width_ratio 0.9)
				(max_width 2)
				(curved_edges yes)
				(filter_ratio 0.9)
				(enabled yes)
				(allow_two_segments yes)
				(prefer_zone_connections yes)
			)
		)
		(pad "" smd roundrect
			(at 0.344 0 270)
			(size 0.318 0.36)
			(layers "F.Paste")
			(roundrect_rratio 0.25)
			(teardrops
				(best_length_ratio 0.2)
				(max_length 1)
				(best_width_ratio 0.9)
				(max_width 2)
				(curved_edges yes)
				(filter_ratio 0.9)
				(enabled yes)
				(allow_two_segments yes)
				(prefer_zone_connections yes)
			)
		)
		(pad "1" smd roundrect
			(at -0.32 0 270)
			(size 0.46 0.4)
			(layers "F.Cu" "F.Mask")
			(roundrect_rratio 0.25)
			(net 432 "/2xSFP+/10GKR_SFP0.RX+")
			(pintype "passive")
			(teardrops
				(best_length_ratio 0.2)
				(max_length 1)
				(best_width_ratio 0.9)
				(max_width 2)
				(curved_edges yes)
				(filter_ratio 0.9)
				(enabled yes)
				(allow_two_segments yes)
				(prefer_zone_connections yes)
			)
		)
		(pad "2" smd roundrect
			(at 0.32 0 270)
			(size 0.46 0.4)
			(layers "F.Cu" "F.Mask")
			(roundrect_rratio 0.25)
			(net 946 "/2xSFP+/KR to SFI #1/BYP_RX+")
			(pintype "passive")
			(teardrops
				(best_length_ratio 0.2)
				(max_length 1)
				(best_width_ratio 0.9)
				(max_width 2)
				(curved_edges yes)
				(filter_ratio 0.9)
				(enabled yes)
				(allow_two_segments yes)
				(prefer_zone_connections yes)
			)
		)
	)
	(footprint "antmicro-footprints:R_0402_1005Metric"
		(layer "F.Cu")
		(at 156.475 72.31 180)
		(descr "Resistor SMD 0402")
		(tags "resistor SMD 0402")
		(property "Reference" "R134"
			(at -3.65 -0.45 0)
			(layer "F.SilkS")
			(effects
				(font
					(size 0.7 0.7)
					(thickness 0.15)
				)
				(justify right bottom)
			)
		)
		(property "Value" "R_0R_0402"
			(at -1.011843 1.772047 0)
			(layer "F.Fab")
			(effects
				(font
					(size 0.7 0.7)
					(thickness 0.15)
				)
				(justify right bottom)
			)
		)
		(property "Datasheet" "https://industrial.panasonic.com/cdbs/www-data/pdf/RDA0000/AOA0000C301.pdf"
			(at 0 0 180)
			(layer "F.Fab")
			(hide yes)
			(effects
				(font
					(size 1.27 1.27)
					(thickness 0.15)
				)
			)
		)
		(property "Author" "Antmicro"
			(at 312.95 144.62 0)
			(layer "F.Fab")
			(hide yes)
			(effects
				(font
					(size 1 1)
					(thickness 0.15)
				)
			)
		)
		(property "Current" "1A"
			(at 312.95 144.62 0)
			(layer "F.Fab")
			(hide yes)
			(effects
				(font
					(size 1 1)
					(thickness 0.15)
				)
			)
		)
		(property "License" "Apache-2.0"
			(at 312.95 144.62 0)
			(layer "F.Fab")
			(hide yes)
			(effects
				(font
					(size 1 1)
					(thickness 0.15)
				)
			)
		)
		(property "MPN" "ERJ2GE0R00X"
			(at 312.95 144.62 0)
			(layer "F.Fab")
			(hide yes)
			(effects
				(font
					(size 1 1)
					(thickness 0.15)
				)
			)
		)
		(property "Manufacturer" "Panasonic"
			(at 312.95 144.62 0)
			(layer "F.Fab")
			(hide yes)
			(effects
				(font
					(size 1 1)
					(thickness 0.15)
				)
			)
		)
		(property "Public" "False"
			(at 312.95 144.62 0)
			(layer "F.Fab")
			(hide yes)
			(effects
				(font
					(size 1 1)
					(thickness 0.15)
				)
			)
		)
		(property "Tolerance" ""
			(at 312.95 144.62 0)
			(layer "F.Fab")
			(hide yes)
			(effects
				(font
					(size 1 1)
					(thickness 0.15)
				)
			)
		)
		(property "Val" "0R"
			(at 312.95 144.62 0)
			(layer "F.Fab")
			(hide yes)
			(effects
				(font
					(size 1 1)
					(thickness 0.15)
				)
			)
		)
		(sheetname "M.2 key E")
		(sheetfile "m2keye.kicad_sch")
		(attr smd)
		(fp_rect
			(start -0.925 -0.47)
			(end 0.925 0.47)
			(stroke
				(width 0.05)
				(type default)
			)
			(fill no)
			(layer "F.CrtYd")
		)
		(fp_rect
			(start -0.5 -0.25)
			(end 0.5 0.25)
			(stroke
				(width 0.15)
				(type solid)
			)
			(fill no)
			(layer "F.Fab")
		)
		(pad "1" smd roundrect
			(at -0.48 0 180)
			(size 0.59 0.64)
			(layers "F.Cu" "F.Mask" "F.Paste")
			(roundrect_rratio 0.25)
			(net 377 "/Com Express 7 Interfaces/USB1.D-")
			(pintype "passive")
			(teardrops
				(best_length_ratio 0.2)
				(max_length 1)
				(best_width_ratio 0.9)
				(max_width 2)
				(curved_edges yes)
				(filter_ratio 0.9)
				(enabled yes)
				(allow_two_segments yes)
				(prefer_zone_connections yes)
			)
		)
		(pad "2" smd roundrect
			(at 0.48 0 180)
			(size 0.59 0.64)
			(layers "F.Cu" "F.Mask" "F.Paste")
			(roundrect_rratio 0.25)
			(net 4 "/M.2 key E/WIFI_BT_USB_D_N")
			(pintype "passive")
			(teardrops
				(best_length_ratio 0.2)
				(max_length 1)
				(best_width_ratio 0.9)
				(max_width 2)
				(curved_edges yes)
				(filter_ratio 0.9)
				(enabled yes)
				(allow_two_segments yes)
				(prefer_zone_connections yes)
			)
		)
	)
	(footprint "antmicro-footprints:TP_SMD_0.75mm"
		(layer "F.Cu")
		(at 118.25 74.71 90)
		(property "Reference" "TP8"
			(at 4.15 6.55 0)
			(layer "F.SilkS")
			(effects
				(font
					(size 0.7 0.7)
					(thickness 0.15)
				)
				(justify left bottom)
			)
		)
		(property "Value" "TP_0.75mm_SMD"
			(at 0 1.2 90)
			(layer "F.Fab")
			(effects
				(font
					(size 0.7 0.7)
					(thickness 0.15)
				)
				(justify left bottom)
			)
		)
		(property "Author" "Antmicro"
			(at 192.96 -43.54 0)
			(layer "F.Fab")
			(hide yes)
			(effects
				(font
					(size 1 1)
					(thickness 0.15)
				)
			)
		)
		(property "License" "Apache-2.0"
			(at 192.96 -43.54 0)
			(layer "F.Fab")
			(hide yes)
			(effects
				(font
					(size 1 1)
					(thickness 0.15)
				)
			)
		)
		(property "MPN" ""
			(at 192.96 -43.54 0)
			(layer "F.Fab")
			(hide yes)
			(effects
				(font
					(size 1 1)
					(thickness 0.15)
				)
			)
		)
		(property "Manufacturer" ""
			(at 192.96 -43.54 0)
			(layer "F.Fab")
			(hide yes)
			(effects
				(font
					(size 1 1)
					(thickness 0.15)
				)
			)
		)
		(property "Public" "False"
			(at 192.96 -43.54 0)
			(layer "F.Fab")
			(hide yes)
			(effects
				(font
					(size 1 1)
					(thickness 0.15)
				)
			)
		)
		(sheetname "USB-C console")
		(sheetfile "usb-c_console.kicad_sch")
		(attr exclude_from_pos_files exclude_from_bom)
		(fp_circle
			(center 0 0)
			(end 0.475 0)
			(stroke
				(width 0.05)
				(type default)
			)
			(fill no)
			(layer "F.CrtYd")
		)
		(pad "1" smd circle
			(at 0 0 90)
			(size 0.75 0.75)
			(layers "F.Cu" "F.Mask")
			(net 700 "/USB-C console/FTDI_TX")
			(pinfunction "1")
			(pintype "passive")
			(teardrops
				(best_length_ratio 0.4)
				(max_length 1)
				(best_width_ratio 0.9)
				(max_width 2)
				(curved_edges yes)
				(filter_ratio 0.9)
				(enabled yes)
				(allow_two_segments yes)
				(prefer_zone_connections yes)
			)
		)
	)
	(footprint "antmicro-footprints:LED_0603_1608Metric_G"
		(layer "F.Cu")
		(at 193.70861 74.802163 90)
		(descr "LED SMD 0603 Green")
		(tags "LED SMD 0603 Green")
		(property "Reference" "D32"
			(at -1.1 -0.55 90)
			(layer "F.SilkS")
			(effects
				(font
					(size 0.7 0.7)
					(thickness 0.15)
				)
				(justify left bottom)
			)
		)
		(property "Value" "LED_G_0603_LTST-C190GKT"
			(at -0.001 1.599 90)
			(layer "F.Fab")
			(effects
				(font
					(size 0.7 0.7)
					(thickness 0.15)
				)
				(justify left bottom)
			)
		)
		(property "Datasheet" "https://media.digikey.com/pdf/Data%20Sheets/Lite-On%20PDFs/LTST-C190GKT.pdf"
			(at 0 0 90)
			(layer "F.Fab")
			(hide yes)
			(effects
				(font
					(size 1.27 1.27)
					(thickness 0.15)
				)
			)
		)
		(property "Author" "Antmicro"
			(at 268.510773 -118.906447 0)
			(layer "F.Fab")
			(hide yes)
			(effects
				(font
					(size 1 1)
					(thickness 0.15)
				)
			)
		)
		(property "Color" "Green"
			(at 268.510773 -118.906447 0)
			(layer "F.Fab")
			(hide yes)
			(effects
				(font
					(size 1 1)
					(thickness 0.15)
				)
			)
		)
		(property "License" "Apache-2.0"
			(at 268.510773 -118.906447 0)
			(layer "F.Fab")
			(hide yes)
			(effects
				(font
					(size 1 1)
					(thickness 0.15)
				)
			)
		)
		(property "MPN" "LTST-C190GKT"
			(at 268.510773 -118.906447 0)
			(layer "F.Fab")
			(hide yes)
			(effects
				(font
					(size 1 1)
					(thickness 0.15)
				)
			)
		)
		(property "Manufacturer" "Lite-On"
			(at 268.510773 -118.906447 0)
			(layer "F.Fab")
			(hide yes)
			(effects
				(font
					(size 1 1)
					(thickness 0.15)
				)
			)
		)
		(property "Public" "False"
			(at 268.510773 -118.906447 0)
			(layer "F.Fab")
			(hide yes)
			(effects
				(font
					(size 1 1)
					(thickness 0.15)
				)
			)
		)
		(sheetname "Power")
		(sheetfile "power.kicad_sch")
		(attr smd)
		(fp_line
			(start 0.22 -0.35)
			(end -0.22 -0.35)
			(stroke
				(width 0.15)
				(type solid)
			)
			(layer "F.SilkS")
		)
		(fp_line
			(start -1.18 -0.319)
			(end -1.18 0.321)
			(stroke
				(width 0.15)
				(type solid)
			)
			(layer "F.SilkS")
		)
		(fp_line
			(start 0.105328 0.001008)
			(end 0.24 0.001)
			(stroke
				(width 0.1)
				(type solid)
			)
			(layer "F.SilkS")
		)
		(fp_line
			(start -0.094672 0.001008)
			(end 0.105328 -0.198992)
			(stroke
				(width 0.1)
				(type solid)
			)
			(layer "F.SilkS")
		)
		(fp_line
			(start -0.094672 0.001008)
			(end -0.24 0.001008)
			(stroke
				(width 0.1)
				(type solid)
			)
			(layer "F.SilkS")
		)
		(fp_line
			(start 0.105328 0.201008)
			(end 0.105328 -0.198992)
			(stroke
				(width 0.1)
				(type solid)
			)
			(layer "F.SilkS")
		)
		(fp_line
			(start 0.105328 0.201008)
			(end -0.094672 0.001008)
			(stroke
				(width 0.1)
				(type solid)
			)
			(layer "F.SilkS")
		)
		(fp_line
			(start -0.094672 0.201008)
			(end -0.094672 -0.198992)
			(stroke
				(width 0.1)
				(type solid)
			)
			(layer "F.SilkS")
		)
		(fp_line
			(start 0.22 0.35)
			(end -0.22 0.35)
			(stroke
				(width 0.15)
				(type solid)
			)
			(layer "F.SilkS")
		)
		(fp_rect
			(start 1.25 0.65)
			(end -1.25 -0.65)
			(stroke
				(width 0.05)
				(type solid)
			)
			(fill no)
			(layer "F.CrtYd")
		)
		(fp_line
			(start 0.201 -0.202)
			(end -0.101 0)
			(stroke
				(width 0.15)
				(type solid)
			)
			(layer "F.Fab")
		)
		(fp_line
			(start -0.199 -0.202)
			(end -0.199 0.1)
			(stroke
				(width 0.15)
				(type solid)
			)
			(layer "F.Fab")
		)
		(fp_line
			(start 0.599 0)
			(end 0.201 0)
			(stroke
				(width 0.15)
				(type solid)
			)
			(layer "F.Fab")
		)
		(fp_line
			(start 0.201 0)
			(end 0.201 -0.202)
			(stroke
				(width 0.15)
				(type solid)
			)
			(layer "F.Fab")
		)
		(fp_line
			(start -0.101 0)
			(end 0.201 0.2)
			(stroke
				(width 0.15)
				(type solid)
			)
			(layer "F.Fab")
		)
		(fp_line
			(start -0.199 0)
			(end -0.597 0)
			(stroke
				(width 0.15)
				(type solid)
			)
			(layer "F.Fab")
		)
		(fp_line
			(start 0.201 0.2)
			(end 0.201 0)
			(stroke
				(width 0.15)
				(type solid)
			)
			(layer "F.Fab")
		)
		(fp_line
			(start -0.199 0.2)
			(end -0.199 0.1)
			(stroke
				(width 0.15)
				(type solid)
			)
			(layer "F.Fab")
		)
		(fp_rect
			(start 0.848 0.4)
			(end -0.85 -0.402)
			(stroke
				(width 0.15)
				(type solid)
			)
			(fill no)
			(layer "F.Fab")
		)
		(pad "1" smd roundrect
			(at -0.7 0 270)
			(size 0.8 1)
			(layers "F.Cu" "F.Mask" "F.Paste")
			(roundrect_rratio 0.2)
			(net 984 "Net-(D32-C)")
			(pinfunction "C")
			(pintype "passive")
			(teardrops
				(best_length_ratio 0.2)
				(max_length 1)
				(best_width_ratio 0.9)
				(max_width 2)
				(curved_edges yes)
				(filter_ratio 0.9)
				(enabled yes)
				(allow_two_segments yes)
				(prefer_zone_connections yes)
			)
		)
		(pad "2" smd roundrect
			(at 0.7 0 270)
			(size 0.8 1)
			(layers "F.Cu" "F.Mask" "F.Paste")
			(roundrect_rratio 0.2)
			(net 65 "+12V")
			(pinfunction "A")
			(pintype "passive")
			(teardrops
				(best_length_ratio 0.2)
				(max_length 1)
				(best_width_ratio 0.9)
				(max_width 2)
				(curved_edges yes)
				(filter_ratio 0.9)
				(enabled yes)
				(allow_two_segments yes)
				(prefer_zone_connections yes)
			)
		)
	)
	(footprint "antmicro-footprints:TP_SMD_0.75mm"
		(layer "F.Cu")
		(at 157 128.71)
		(property "Reference" "TP70"
			(at 0.4 -3.3 90)
			(layer "F.SilkS")
			(effects
				(font
					(size 0.7 0.7)
					(thickness 0.15)
				)
				(justify left bottom)
			)
		)
		(property "Value" "TP_0.75mm_SMD"
			(at 0 1.2 0)
			(layer "F.Fab")
			(effects
				(font
					(size 0.7 0.7)
					(thickness 0.15)
				)
				(justify left bottom)
			)
		)
		(property "Author" "Antmicro"
			(at 0 0 0)
			(layer "F.Fab")
			(hide yes)
			(effects
				(font
					(size 1 1)
					(thickness 0.15)
				)
			)
		)
		(property "License" "Apache-2.0"
			(at 0 0 0)
			(layer "F.Fab")
			(hide yes)
			(effects
				(font
					(size 1 1)
					(thickness 0.15)
				)
			)
		)
		(property "MPN" ""
			(at 0 0 0)
			(layer "F.Fab")
			(hide yes)
			(effects
				(font
					(size 1 1)
					(thickness 0.15)
				)
			)
		)
		(property "Manufacturer" ""
			(at 0 0 0)
			(layer "F.Fab")
			(hide yes)
			(effects
				(font
					(size 1 1)
					(thickness 0.15)
				)
			)
		)
		(property "Public" "False"
			(at 0 0 0)
			(layer "F.Fab")
			(hide yes)
			(effects
				(font
					(size 1 1)
					(thickness 0.15)
				)
			)
		)
		(sheetname "KR to SFI #1")
		(sheetfile "kr_sfi.kicad_sch")
		(attr exclude_from_pos_files exclude_from_bom)
		(fp_circle
			(center 0 0)
			(end 0.475 0)
			(stroke
				(width 0.05)
				(type default)
			)
			(fill no)
			(layer "F.CrtYd")
		)
		(pad "1" smd circle
			(at 0 0)
			(size 0.75 0.75)
			(layers "F.Cu" "F.Mask")
			(net 733 "Net-(U43C-CLKOUTB-)")
			(pinfunction "1")
			(pintype "passive")
			(teardrops
				(best_length_ratio 0.4)
				(max_length 1)
				(best_width_ratio 0.9)
				(max_width 2)
				(curved_edges yes)
				(filter_ratio 0.9)
				(enabled yes)
				(allow_two_segments yes)
				(prefer_zone_connections yes)
			)
		)
	)
	(footprint "antmicro-footprints:R_0402_1005Metric"
		(layer "F.Cu")
		(at 252.615 82.174999)
		(descr "Resistor SMD 0402")
		(tags "resistor SMD 0402")
		(property "Reference" "R146"
			(at -0.825 0.435001 0)
			(layer "F.SilkS")
			(effects
				(font
					(size 0.7 0.7)
					(thickness 0.15)
				)
				(justify right bottom)
			)
		)
		(property "Value" "R_10k_0402"
			(at -1.011843 1.772047 0)
			(layer "F.Fab")
			(effects
				(font
					(size 0.7 0.7)
					(thickness 0.15)
				)
				(justify left bottom)
			)
		)
		(property "Datasheet" "https://www.bourns.com/docs/product-datasheets/cr.pdf"
			(at 0 0 0)
			(layer "F.Fab")
			(hide yes)
			(effects
				(font
					(size 1.27 1.27)
					(thickness 0.15)
				)
			)
		)
		(property "Author" "Antmicro"
			(at 0 0 0)
			(layer "F.Fab")
			(hide yes)
			(effects
				(font
					(size 1 1)
					(thickness 0.15)
				)
			)
		)
		(property "License" "Apache-2.0"
			(at 0 0 0)
			(layer "F.Fab")
			(hide yes)
			(effects
				(font
					(size 1 1)
					(thickness 0.15)
				)
			)
		)
		(property "MPN" "CR0402-FX-1002GLF"
			(at 0 0 0)
			(layer "F.Fab")
			(hide yes)
			(effects
				(font
					(size 1 1)
					(thickness 0.15)
				)
			)
		)
		(property "Manufacturer" "Bourns"
			(at 0 0 0)
			(layer "F.Fab")
			(hide yes)
			(effects
				(font
					(size 1 1)
					(thickness 0.15)
				)
			)
		)
		(property "Public" "False"
			(at 0 0 0)
			(layer "F.Fab")
			(hide yes)
			(effects
				(font
					(size 1 1)
					(thickness 0.15)
				)
			)
		)
		(property "Tolerance" "1%"
			(at 0 0 0)
			(layer "F.Fab")
			(hide yes)
			(effects
				(font
					(size 1 1)
					(thickness 0.15)
				)
			)
		)
		(property "Val" "10k"
			(at 0 0 0)
			(layer "F.Fab")
			(hide yes)
			(effects
				(font
					(size 1 1)
					(thickness 0.15)
				)
			)
		)
		(sheetname "Misc")
		(sheetfile "misc.kicad_sch")
		(attr smd dnp)
		(fp_rect
			(start -0.925 -0.47)
			(end 0.925 0.47)
			(stroke
				(width 0.05)
				(type default)
			)
			(fill no)
			(layer "F.CrtYd")
		)
		(fp_rect
			(start -0.5 -0.25)
			(end 0.5 0.25)
			(stroke
				(width 0.15)
				(type solid)
			)
			(fill no)
			(layer "F.Fab")
		)
		(pad "1" smd roundrect
			(at -0.48 0)
			(size 0.59 0.64)
			(layers "F.Cu" "F.Mask" "F.Paste")
			(roundrect_rratio 0.25)
			(net 1 "GND")
			(pintype "passive")
			(teardrops
				(best_length_ratio 0.2)
				(max_length 1)
				(best_width_ratio 0.9)
				(max_width 2)
				(curved_edges yes)
				(filter_ratio 0.9)
				(enabled yes)
				(allow_two_segments yes)
				(prefer_zone_connections yes)
			)
		)
		(pad "2" smd roundrect
			(at 0.48 0)
			(size 0.59 0.64)
			(layers "F.Cu" "F.Mask" "F.Paste")
			(roundrect_rratio 0.25)
			(net 589 "/Misc/~{ADDRSEL}")
			(pintype "passive")
			(teardrops
				(best_length_ratio 0.2)
				(max_length 1)
				(best_width_ratio 0.9)
				(max_width 2)
				(curved_edges yes)
				(filter_ratio 0.9)
				(enabled yes)
				(allow_two_segments yes)
				(prefer_zone_connections yes)
			)
		)
	)
	(footprint "antmicro-footprints:TP_SMD_0.75mm"
		(layer "F.Cu")
		(at 132.34 128.71)
		(property "Reference" "TP93"
			(at 0.51 -3.3 90)
			(layer "F.SilkS")
			(effects
				(font
					(size 0.7 0.7)
					(thickness 0.15)
				)
				(justify left bottom)
			)
		)
		(property "Value" "TP_0.75mm_SMD"
			(at 0 1.2 0)
			(layer "F.Fab")
			(effects
				(font
					(size 0.7 0.7)
					(thickness 0.15)
				)
				(justify left bottom)
			)
		)
		(property "Author" "Antmicro"
			(at 0 0 0)
			(layer "F.Fab")
			(hide yes)
			(effects
				(font
					(size 1 1)
					(thickness 0.15)
				)
			)
		)
		(property "License" "Apache-2.0"
			(at 0 0 0)
			(layer "F.Fab")
			(hide yes)
			(effects
				(font
					(size 1 1)
					(thickness 0.15)
				)
			)
		)
		(property "MPN" ""
			(at 0 0 0)
			(layer "F.Fab")
			(hide yes)
			(effects
				(font
					(size 1 1)
					(thickness 0.15)
				)
			)
		)
		(property "Manufacturer" ""
			(at 0 0 0)
			(layer "F.Fab")
			(hide yes)
			(effects
				(font
					(size 1 1)
					(thickness 0.15)
				)
			)
		)
		(property "Public" "False"
			(at 0 0 0)
			(layer "F.Fab")
			(hide yes)
			(effects
				(font
					(size 1 1)
					(thickness 0.15)
				)
			)
		)
		(sheetname "KR to SFI #2")
		(sheetfile "kr_sfi.kicad_sch")
		(attr exclude_from_pos_files exclude_from_bom)
		(fp_circle
			(center 0 0)
			(end 0.475 0)
			(stroke
				(width 0.05)
				(type default)
			)
			(fill no)
			(layer "F.CrtYd")
		)
		(pad "1" smd circle
			(at 0 0)
			(size 0.75 0.75)
			(layers "F.Cu" "F.Mask")
			(net 756 "Net-(U45A-LS_OK_{OUT_A})")
			(pinfunction "1")
			(pintype "passive")
			(teardrops
				(best_length_ratio 0.4)
				(max_length 1)
				(best_width_ratio 0.9)
				(max_width 2)
				(curved_edges yes)
				(filter_ratio 0.9)
				(enabled yes)
				(allow_two_segments yes)
				(prefer_zone_connections yes)
			)
		)
	)
	(footprint "antmicro-footprints:C_0603_1608Metric"
		(layer "F.Cu")
		(at 177.52 95.69)
		(descr "Capacitor SMD 0603")
		(tags "capacitor 0603")
		(property "Reference" "C72"
			(at -3.32 0.47 0)
			(layer "F.SilkS")
			(effects
				(font
					(size 0.7 0.7)
					(thickness 0.15)
				)
				(justify left bottom)
			)
		)
		(property "Value" "C_22u_16V_0603"
			(at -1.42757 1.770288 0)
			(layer "F.Fab")
			(effects
				(font
					(size 0.7 0.7)
					(thickness 0.15)
				)
				(justify left bottom)
			)
		)
		(property "Datasheet" "https://product.samsungsem.com/mlcc/CL10A226MO7JZN.do"
			(at 0 0 0)
			(layer "F.Fab")
			(hide yes)
			(effects
				(font
					(size 1.27 1.27)
					(thickness 0.15)
				)
			)
		)
		(property "Author" "Antmicro"
			(at 0 0 0)
			(layer "F.Fab")
			(hide yes)
			(effects
				(font
					(size 1 1)
					(thickness 0.15)
				)
			)
		)
		(property "Dielectric" ""
			(at 0 0 0)
			(layer "F.Fab")
			(hide yes)
			(effects
				(font
					(size 1 1)
					(thickness 0.15)
				)
			)
		)
		(property "License" "Apache-2.0"
			(at 0 0 0)
			(layer "F.Fab")
			(hide yes)
			(effects
				(font
					(size 1 1)
					(thickness 0.15)
				)
			)
		)
		(property "MPN" "CL10A226MO7JZNC"
			(at 0 0 0)
			(layer "F.Fab")
			(hide yes)
			(effects
				(font
					(size 1 1)
					(thickness 0.15)
				)
			)
		)
		(property "Manufacturer" "Samsung Electro-Mechanics"
			(at 0 0 0)
			(layer "F.Fab")
			(hide yes)
			(effects
				(font
					(size 1 1)
					(thickness 0.15)
				)
			)
		)
		(property "Public" "False"
			(at 0 0 0)
			(layer "F.Fab")
			(hide yes)
			(effects
				(font
					(size 1 1)
					(thickness 0.15)
				)
			)
		)
		(property "Val" "22u"
			(at 0 0 0)
			(layer "F.Fab")
			(hide yes)
			(effects
				(font
					(size 1 1)
					(thickness 0.15)
				)
			)
		)
		(property "Voltage" "16V"
			(at 0 0 0)
			(layer "F.Fab")
			(hide yes)
			(effects
				(font
					(size 1 1)
					(thickness 0.15)
				)
			)
		)
		(sheetname "M.2 key M #1")
		(sheetfile "m2keym_low.kicad_sch")
		(attr smd)
		(fp_line
			(start -0.15 -0.4)
			(end 0.15 -0.4)
			(stroke
				(width 0.15)
				(type solid)
			)
			(layer "F.SilkS")
		)
		(fp_line
			(start -0.15 0.4)
			(end 0.15 0.4)
			(stroke
				(width 0.15)
				(type solid)
			)
			(layer "F.SilkS")
		)
		(fp_rect
			(start -1.25 -0.65)
			(end 1.25 0.65)
			(stroke
				(width 0.05)
				(type solid)
			)
			(fill no)
			(layer "F.CrtYd")
		)
		(fp_rect
			(start -0.8 -0.4)
			(end 0.8 0.4)
			(stroke
				(width 0.15)
				(type solid)
			)
			(fill no)
			(layer "F.Fab")
		)
		(pad "1" smd roundrect
			(at -0.7 0)
			(size 0.8 1)
			(layers "F.Cu" "F.Mask" "F.Paste")
			(roundrect_rratio 0.2)
			(net 1 "GND")
			(pintype "passive")
			(teardrops
				(best_length_ratio 0.2)
				(max_length 1)
				(best_width_ratio 0.9)
				(max_width 2)
				(curved_edges yes)
				(filter_ratio 0.9)
				(enabled yes)
				(allow_two_segments yes)
				(prefer_zone_connections yes)
			)
		)
		(pad "2" smd roundrect
			(at 0.7 0)
			(size 0.8 1)
			(layers "F.Cu" "F.Mask" "F.Paste")
			(roundrect_rratio 0.2)
			(net 969 "/M.2 key M #1/M2_3V3")
			(pintype "passive")
			(teardrops
				(best_length_ratio 0.2)
				(max_length 1)
				(best_width_ratio 0.9)
				(max_width 2)
				(curved_edges yes)
				(filter_ratio 0.9)
				(enabled yes)
				(allow_two_segments yes)
				(prefer_zone_connections yes)
			)
		)
	)
	(footprint "antmicro-footprints:TP_SMD_0.75mm"
		(layer "F.Cu")
		(at 132.99 129.56)
		(property "Reference" "TP83"
			(at 0.46 -1.25 90)
			(layer "F.SilkS")
			(effects
				(font
					(size 0.7 0.7)
					(thickness 0.15)
				)
				(justify left bottom)
			)
		)
		(property "Value" "TP_0.75mm_SMD"
			(at 0 1.2 0)
			(layer "F.Fab")
			(effects
				(font
					(size 0.7 0.7)
					(thickness 0.15)
				)
				(justify left bottom)
			)
		)
		(property "Author" "Antmicro"
			(at 0 0 0)
			(layer "F.Fab")
			(hide yes)
			(effects
				(font
					(size 1 1)
					(thickness 0.15)
				)
			)
		)
		(property "License" "Apache-2.0"
			(at 0 0 0)
			(layer "F.Fab")
			(hide yes)
			(effects
				(font
					(size 1 1)
					(thickness 0.15)
				)
			)
		)
		(property "MPN" ""
			(at 0 0 0)
			(layer "F.Fab")
			(hide yes)
			(effects
				(font
					(size 1 1)
					(thickness 0.15)
				)
			)
		)
		(property "Manufacturer" ""
			(at 0 0 0)
			(layer "F.Fab")
			(hide yes)
			(effects
				(font
					(size 1 1)
					(thickness 0.15)
				)
			)
		)
		(property "Public" "False"
			(at 0 0 0)
			(layer "F.Fab")
			(hide yes)
			(effects
				(font
					(size 1 1)
					(thickness 0.15)
				)
			)
		)
		(sheetname "KR to SFI #2")
		(sheetfile "kr_sfi.kicad_sch")
		(attr exclude_from_pos_files exclude_from_bom)
		(fp_circle
			(center 0 0)
			(end 0.475 0)
			(stroke
				(width 0.05)
				(type default)
			)
			(fill no)
			(layer "F.CrtYd")
		)
		(pad "1" smd circle
			(at 0 0)
			(size 0.75 0.75)
			(layers "F.Cu" "F.Mask")
			(net 746 "/2xSFP+/KR to SFI #2/~{TRST}")
			(pinfunction "1")
			(pintype "passive")
			(teardrops
				(best_length_ratio 0.4)
				(max_length 1)
				(best_width_ratio 0.9)
				(max_width 2)
				(curved_edges yes)
				(filter_ratio 0.9)
				(enabled yes)
				(allow_two_segments yes)
				(prefer_zone_connections yes)
			)
		)
	)
	(footprint "antmicro-footprints:R_0402_1005Metric"
		(layer "F.Cu")
		(at 122.049999 85.06 180)
		(descr "Resistor SMD 0402")
		(tags "resistor SMD 0402")
		(property "Reference" "R27"
			(at -2.950001 -0.4 0)
			(layer "F.SilkS")
			(effects
				(font
					(size 0.7 0.7)
					(thickness 0.15)
				)
				(justify right bottom)
			)
		)
		(property "Value" "R_0R_0402"
			(at -1.011843 1.772047 0)
			(layer "F.Fab")
			(effects
				(font
					(size 0.7 0.7)
					(thickness 0.15)
				)
				(justify right bottom)
			)
		)
		(property "Datasheet" "https://industrial.panasonic.com/cdbs/www-data/pdf/RDA0000/AOA0000C301.pdf"
			(at 0 0 180)
			(layer "F.Fab")
			(hide yes)
			(effects
				(font
					(size 1.27 1.27)
					(thickness 0.15)
				)
			)
		)
		(property "Author" "Antmicro"
			(at 244.099998 170.12 0)
			(layer "F.Fab")
			(hide yes)
			(effects
				(font
					(size 1 1)
					(thickness 0.15)
				)
			)
		)
		(property "Current" "1A"
			(at 244.099998 170.12 0)
			(layer "F.Fab")
			(hide yes)
			(effects
				(font
					(size 1 1)
					(thickness 0.15)
				)
			)
		)
		(property "License" "Apache-2.0"
			(at 244.099998 170.12 0)
			(layer "F.Fab")
			(hide yes)
			(effects
				(font
					(size 1 1)
					(thickness 0.15)
				)
			)
		)
		(property "MPN" "ERJ2GE0R00X"
			(at 244.099998 170.12 0)
			(layer "F.Fab")
			(hide yes)
			(effects
				(font
					(size 1 1)
					(thickness 0.15)
				)
			)
		)
		(property "Manufacturer" "Panasonic"
			(at 244.099998 170.12 0)
			(layer "F.Fab")
			(hide yes)
			(effects
				(font
					(size 1 1)
					(thickness 0.15)
				)
			)
		)
		(property "Public" "False"
			(at 244.099998 170.12 0)
			(layer "F.Fab")
			(hide yes)
			(effects
				(font
					(size 1 1)
					(thickness 0.15)
				)
			)
		)
		(property "Tolerance" ""
			(at 244.099998 170.12 0)
			(layer "F.Fab")
			(hide yes)
			(effects
				(font
					(size 1 1)
					(thickness 0.15)
				)
			)
		)
		(property "Val" "0R"
			(at 244.099998 170.12 0)
			(layer "F.Fab")
			(hide yes)
			(effects
				(font
					(size 1 1)
					(thickness 0.15)
				)
			)
		)
		(sheetname "2xUSB3.0+RJ45")
		(sheetfile "usb3+rj45.kicad_sch")
		(attr smd)
		(fp_rect
			(start -0.925 -0.47)
			(end 0.925 0.47)
			(stroke
				(width 0.05)
				(type default)
			)
			(fill no)
			(layer "F.CrtYd")
		)
		(fp_rect
			(start -0.5 -0.25)
			(end 0.5 0.25)
			(stroke
				(width 0.15)
				(type solid)
			)
			(fill no)
			(layer "F.Fab")
		)
		(pad "1" smd roundrect
			(at -0.48 0 180)
			(size 0.59 0.64)
			(layers "F.Cu" "F.Mask" "F.Paste")
			(roundrect_rratio 0.25)
			(net 941 "/2xUSB3.0+RJ45/EN_1")
			(pintype "passive")
			(teardrops
				(best_length_ratio 0.2)
				(max_length 1)
				(best_width_ratio 0.9)
				(max_width 2)
				(curved_edges yes)
				(filter_ratio 0.9)
				(enabled yes)
				(allow_two_segments yes)
				(prefer_zone_connections yes)
			)
		)
		(pad "2" smd roundrect
			(at 0.48 0 180)
			(size 0.59 0.64)
			(layers "F.Cu" "F.Mask" "F.Paste")
			(roundrect_rratio 0.25)
			(net 555 "/2xUSB3.0+RJ45/EN_1B")
			(pintype "passive")
			(teardrops
				(best_length_ratio 0.2)
				(max_length 1)
				(best_width_ratio 0.9)
				(max_width 2)
				(curved_edges yes)
				(filter_ratio 0.9)
				(enabled yes)
				(allow_two_segments yes)
				(prefer_zone_connections yes)
			)
		)
	)
	(footprint "antmicro-footprints:C_0402_1005Metric"
		(layer "F.Cu")
		(at 310.075 77.862002 90)
		(descr "Capacitor SMD 0402")
		(tags "capacitor SMD 0402")
		(property "Reference" "C109"
			(at -1.797998 1.375 90)
			(layer "F.SilkS")
			(effects
				(font
					(size 0.7 0.7)
					(thickness 0.15)
				)
				(justify left bottom)
			)
		)
		(property "Value" "C_100n_0402"
			(at -1.022927 2.155213 90)
			(layer "F.Fab")
			(effects
				(font
					(size 0.7 0.7)
					(thickness 0.15)
				)
				(justify left bottom)
			)
		)
		(property "Datasheet" "https://www.murata.com/products/productdetail?partno=GRM155R61H104KE14%23"
			(at 0 0 90)
			(layer "F.Fab")
			(hide yes)
			(effects
				(font
					(size 1.27 1.27)
					(thickness 0.15)
				)
			)
		)
		(property "Author" "Antmicro"
			(at 387.937002 -232.212998 0)
			(layer "F.Fab")
			(hide yes)
			(effects
				(font
					(size 1 1)
					(thickness 0.15)
				)
			)
		)
		(property "Dielectric" "X5R"
			(at 387.937002 -232.212998 0)
			(layer "F.Fab")
			(hide yes)
			(effects
				(font
					(size 1 1)
					(thickness 0.15)
				)
			)
		)
		(property "License" "Apache-2.0"
			(at 387.937002 -232.212998 0)
			(layer "F.Fab")
			(hide yes)
			(effects
				(font
					(size 1 1)
					(thickness 0.15)
				)
			)
		)
		(property "MPN" "GRM155R61H104KE14D"
			(at 387.937002 -232.212998 0)
			(layer "F.Fab")
			(hide yes)
			(effects
				(font
					(size 1 1)
					(thickness 0.15)
				)
			)
		)
		(property "Manufacturer" "Murata"
			(at 387.937002 -232.212998 0)
			(layer "F.Fab")
			(hide yes)
			(effects
				(font
					(size 1 1)
					(thickness 0.15)
				)
			)
		)
		(property "Public" "False"
			(at 387.937002 -232.212998 0)
			(layer "F.Fab")
			(hide yes)
			(effects
				(font
					(size 1 1)
					(thickness 0.15)
				)
			)
		)
		(property "Val" "100n"
			(at 387.937002 -232.212998 0)
			(layer "F.Fab")
			(hide yes)
			(effects
				(font
					(size 1 1)
					(thickness 0.15)
				)
			)
		)
		(property "Voltage" "50V"
			(at 387.937002 -232.212998 0)
			(layer "F.Fab")
			(hide yes)
			(effects
				(font
					(size 1 1)
					(thickness 0.15)
				)
			)
		)
		(sheetname "PCIe misc")
		(sheetfile "pcie_misc.kicad_sch")
		(attr smd)
		(fp_rect
			(start -0.925 -0.47)
			(end 0.925 0.47)
			(stroke
				(width 0.05)
				(type default)
			)
			(fill no)
			(layer "F.CrtYd")
		)
		(fp_line
			(start 0.504 -0.25)
			(end 0.504 0.248)
			(stroke
				(width 0.15)
				(type solid)
			)
			(layer "F.Fab")
		)
		(fp_line
			(start -0.494 -0.25)
			(end 0.504 -0.25)
			(stroke
				(width 0.15)
				(type solid)
			)
			(layer "F.Fab")
		)
		(fp_line
			(start 0.504 0.248)
			(end -0.494 0.248)
			(stroke
				(width 0.15)
				(type solid)
			)
			(layer "F.Fab")
		)
		(fp_line
			(start -0.494 0.248)
			(end -0.494 -0.25)
			(stroke
				(width 0.15)
				(type solid)
			)
			(layer "F.Fab")
		)
		(pad "1" smd roundrect
			(at -0.48 0 90)
			(size 0.59 0.64)
			(layers "F.Cu" "F.Mask" "F.Paste")
			(roundrect_rratio 0.25)
			(net 1 "GND")
			(pintype "passive")
			(teardrops
				(best_length_ratio 0.2)
				(max_length 1)
				(best_width_ratio 0.9)
				(max_width 2)
				(curved_edges yes)
				(filter_ratio 0.9)
				(enabled yes)
				(allow_two_segments yes)
				(prefer_zone_connections yes)
			)
		)
		(pad "2" smd roundrect
			(at 0.48 0 90)
			(size 0.59 0.64)
			(layers "F.Cu" "F.Mask" "F.Paste")
			(roundrect_rratio 0.25)
			(net 2 "+3V3")
			(pintype "passive")
			(teardrops
				(best_length_ratio 0.2)
				(max_length 1)
				(best_width_ratio 0.9)
				(max_width 2)
				(curved_edges yes)
				(filter_ratio 0.9)
				(enabled yes)
				(allow_two_segments yes)
				(prefer_zone_connections yes)
			)
		)
	)
	(footprint "antmicro-footprints:C_0402_1005Metric"
		(layer "F.Cu")
		(at 114.35 91.31 90)
		(descr "Capacitor SMD 0402")
		(tags "capacitor SMD 0402")
		(property "Reference" "C9"
			(at 0.85 0.45 90)
			(layer "F.SilkS")
			(effects
				(font
					(size 0.7 0.7)
					(thickness 0.15)
				)
				(justify left bottom)
			)
		)
		(property "Value" "C_1u_0402"
			(at -1.022927 2.155213 90)
			(layer "F.Fab")
			(effects
				(font
					(size 0.7 0.7)
					(thickness 0.15)
				)
				(justify left bottom)
			)
		)
		(property "Datasheet" "https://product.tdk.com/en/search/capacitor/ceramic/mlcc/info?part_no=C1005X6S1A105K050BC"
			(at 0 0 90)
			(layer "F.Fab")
			(hide yes)
			(effects
				(font
					(size 1.27 1.27)
					(thickness 0.15)
				)
			)
		)
		(property "Author" "Antmicro"
			(at 205.66 -23.04 0)
			(layer "F.Fab")
			(hide yes)
			(effects
				(font
					(size 1 1)
					(thickness 0.15)
				)
			)
		)
		(property "Dielectric" ""
			(at 205.66 -23.04 0)
			(layer "F.Fab")
			(hide yes)
			(effects
				(font
					(size 1 1)
					(thickness 0.15)
				)
			)
		)
		(property "License" "Apache-2.0"
			(at 205.66 -23.04 0)
			(layer "F.Fab")
			(hide yes)
			(effects
				(font
					(size 1 1)
					(thickness 0.15)
				)
			)
		)
		(property "MPN" "C1005X6S1A105K050BC"
			(at 205.66 -23.04 0)
			(layer "F.Fab")
			(hide yes)
			(effects
				(font
					(size 1 1)
					(thickness 0.15)
				)
			)
		)
		(property "Manufacturer" "TDK"
			(at 205.66 -23.04 0)
			(layer "F.Fab")
			(hide yes)
			(effects
				(font
					(size 1 1)
					(thickness 0.15)
				)
			)
		)
		(property "Public" "False"
			(at 205.66 -23.04 0)
			(layer "F.Fab")
			(hide yes)
			(effects
				(font
					(size 1 1)
					(thickness 0.15)
				)
			)
		)
		(property "Val" "1u"
			(at 205.66 -23.04 0)
			(layer "F.Fab")
			(hide yes)
			(effects
				(font
					(size 1 1)
					(thickness 0.15)
				)
			)
		)
		(property "Voltage" ""
			(at 205.66 -23.04 0)
			(layer "F.Fab")
			(hide yes)
			(effects
				(font
					(size 1 1)
					(thickness 0.15)
				)
			)
		)
		(sheetname "2xUSB3.0+RJ45")
		(sheetfile "usb3+rj45.kicad_sch")
		(attr smd)
		(fp_rect
			(start -0.925 -0.47)
			(end 0.925 0.47)
			(stroke
				(width 0.05)
				(type default)
			)
			(fill no)
			(layer "F.CrtYd")
		)
		(fp_line
			(start 0.504 -0.25)
			(end 0.504 0.248)
			(stroke
				(width 0.15)
				(type solid)
			)
			(layer "F.Fab")
		)
		(fp_line
			(start -0.494 -0.25)
			(end 0.504 -0.25)
			(stroke
				(width 0.15)
				(type solid)
			)
			(layer "F.Fab")
		)
		(fp_line
			(start 0.504 0.248)
			(end -0.494 0.248)
			(stroke
				(width 0.15)
				(type solid)
			)
			(layer "F.Fab")
		)
		(fp_line
			(start -0.494 0.248)
			(end -0.494 -0.25)
			(stroke
				(width 0.15)
				(type solid)
			)
			(layer "F.Fab")
		)
		(pad "1" smd roundrect
			(at -0.48 0 90)
			(size 0.59 0.64)
			(layers "F.Cu" "F.Mask" "F.Paste")
			(roundrect_rratio 0.25)
			(net 1 "GND")
			(pintype "passive")
			(teardrops
				(best_length_ratio 0.2)
				(max_length 1)
				(best_width_ratio 0.9)
				(max_width 2)
				(curved_edges yes)
				(filter_ratio 0.9)
				(enabled yes)
				(allow_two_segments yes)
				(prefer_zone_connections yes)
			)
		)
		(pad "2" smd roundrect
			(at 0.48 0 90)
			(size 0.59 0.64)
			(layers "F.Cu" "F.Mask" "F.Paste")
			(roundrect_rratio 0.25)
			(net 43 "/2xUSB3.0+RJ45/P2_VBUS")
			(pintype "passive")
			(teardrops
				(best_length_ratio 0.2)
				(max_length 1)
				(best_width_ratio 0.9)
				(max_width 2)
				(curved_edges yes)
				(filter_ratio 0.9)
				(enabled yes)
				(allow_two_segments yes)
				(prefer_zone_connections yes)
			)
		)
	)
	(footprint "antmicro-footprints:R_0402_1005Metric"
		(layer "F.Cu")
		(at 143 134.88 180)
		(descr "Resistor SMD 0402")
		(tags "resistor SMD 0402")
		(property "Reference" "R270"
			(at 0.75 -0.43 0)
			(layer "F.SilkS")
			(effects
				(font
					(size 0.7 0.7)
					(thickness 0.15)
				)
				(justify right bottom)
			)
		)
		(property "Value" "R_10k_0402"
			(at -1.011843 1.772047 0)
			(layer "F.Fab")
			(effects
				(font
					(size 0.7 0.7)
					(thickness 0.15)
				)
				(justify right bottom)
			)
		)
		(property "Datasheet" "https://www.bourns.com/docs/product-datasheets/cr.pdf"
			(at 0 0 180)
			(layer "F.Fab")
			(hide yes)
			(effects
				(font
					(size 1.27 1.27)
					(thickness 0.15)
				)
			)
		)
		(property "Author" "Antmicro"
			(at 286 269.76 0)
			(layer "F.Fab")
			(hide yes)
			(effects
				(font
					(size 1 1)
					(thickness 0.15)
				)
			)
		)
		(property "License" "Apache-2.0"
			(at 286 269.76 0)
			(layer "F.Fab")
			(hide yes)
			(effects
				(font
					(size 1 1)
					(thickness 0.15)
				)
			)
		)
		(property "MPN" "CR0402-FX-1002GLF"
			(at 286 269.76 0)
			(layer "F.Fab")
			(hide yes)
			(effects
				(font
					(size 1 1)
					(thickness 0.15)
				)
			)
		)
		(property "Manufacturer" "Bourns"
			(at 286 269.76 0)
			(layer "F.Fab")
			(hide yes)
			(effects
				(font
					(size 1 1)
					(thickness 0.15)
				)
			)
		)
		(property "Public" "False"
			(at 286 269.76 0)
			(layer "F.Fab")
			(hide yes)
			(effects
				(font
					(size 1 1)
					(thickness 0.15)
				)
			)
		)
		(property "Tolerance" "1%"
			(at 286 269.76 0)
			(layer "F.Fab")
			(hide yes)
			(effects
				(font
					(size 1 1)
					(thickness 0.15)
				)
			)
		)
		(property "Val" "10k"
			(at 286 269.76 0)
			(layer "F.Fab")
			(hide yes)
			(effects
				(font
					(size 1 1)
					(thickness 0.15)
				)
			)
		)
		(sheetname "KR to SFI #1")
		(sheetfile "kr_sfi.kicad_sch")
		(attr smd dnp)
		(fp_rect
			(start -0.925 -0.47)
			(end 0.925 0.47)
			(stroke
				(width 0.05)
				(type default)
			)
			(fill no)
			(layer "F.CrtYd")
		)
		(fp_rect
			(start -0.5 -0.25)
			(end 0.5 0.25)
			(stroke
				(width 0.15)
				(type solid)
			)
			(fill no)
			(layer "F.Fab")
		)
		(pad "1" smd roundrect
			(at -0.48 0 180)
			(size 0.59 0.64)
			(layers "F.Cu" "F.Mask" "F.Paste")
			(roundrect_rratio 0.25)
			(net 663 "Net-(U43C-ST)")
			(pintype "passive")
			(teardrops
				(best_length_ratio 0.2)
				(max_length 1)
				(best_width_ratio 0.9)
				(max_width 2)
				(curved_edges yes)
				(filter_ratio 0.9)
				(enabled yes)
				(allow_two_segments yes)
				(prefer_zone_connections yes)
			)
		)
		(pad "2" smd roundrect
			(at 0.48 0 180)
			(size 0.59 0.64)
			(layers "F.Cu" "F.Mask" "F.Paste")
			(roundrect_rratio 0.25)
			(net 78 "+1V8")
			(pintype "passive")
			(teardrops
				(best_length_ratio 0.2)
				(max_length 1)
				(best_width_ratio 0.9)
				(max_width 2)
				(curved_edges yes)
				(filter_ratio 0.9)
				(enabled yes)
				(allow_two_segments yes)
				(prefer_zone_connections yes)
			)
		)
	)
	(footprint "antmicro-footprints:C_0402_1005Metric"
		(layer "F.Cu")
		(at 109.757 76.776 90)
		(descr "Capacitor SMD 0402")
		(tags "capacitor SMD 0402")
		(property "Reference" "C31"
			(at -1.034 -0.507 90)
			(layer "F.SilkS")
			(effects
				(font
					(size 0.7 0.7)
					(thickness 0.15)
				)
				(justify left bottom)
			)
		)
		(property "Value" "C_47p_0402"
			(at -1.022927 2.155213 90)
			(layer "F.Fab")
			(effects
				(font
					(size 0.7 0.7)
					(thickness 0.15)
				)
				(justify left bottom)
			)
		)
		(property "Datasheet" "https://www.kemet.com/en/us/capacitors/product/C0402C470J5GACTU.html"
			(at 0 0 90)
			(layer "F.Fab")
			(hide yes)
			(effects
				(font
					(size 1.27 1.27)
					(thickness 0.15)
				)
			)
		)
		(property "Author" "Antmicro"
			(at 186.533 -32.981 0)
			(layer "F.Fab")
			(hide yes)
			(effects
				(font
					(size 1 1)
					(thickness 0.15)
				)
			)
		)
		(property "Dielectric" "C0G"
			(at 186.533 -32.981 0)
			(layer "F.Fab")
			(hide yes)
			(effects
				(font
					(size 1 1)
					(thickness 0.15)
				)
			)
		)
		(property "License" "Apache-2.0"
			(at 186.533 -32.981 0)
			(layer "F.Fab")
			(hide yes)
			(effects
				(font
					(size 1 1)
					(thickness 0.15)
				)
			)
		)
		(property "MPN" "C0402C470J5GACTU"
			(at 186.533 -32.981 0)
			(layer "F.Fab")
			(hide yes)
			(effects
				(font
					(size 1 1)
					(thickness 0.15)
				)
			)
		)
		(property "Manufacturer" "KEMET"
			(at 186.533 -32.981 0)
			(layer "F.Fab")
			(hide yes)
			(effects
				(font
					(size 1 1)
					(thickness 0.15)
				)
			)
		)
		(property "Public" "False"
			(at 186.533 -32.981 0)
			(layer "F.Fab")
			(hide yes)
			(effects
				(font
					(size 1 1)
					(thickness 0.15)
				)
			)
		)
		(property "Val" "47p"
			(at 186.533 -32.981 0)
			(layer "F.Fab")
			(hide yes)
			(effects
				(font
					(size 1 1)
					(thickness 0.15)
				)
			)
		)
		(property "Voltage" ""
			(at 186.533 -32.981 0)
			(layer "F.Fab")
			(hide yes)
			(effects
				(font
					(size 1 1)
					(thickness 0.15)
				)
			)
		)
		(sheetname "USB-C console")
		(sheetfile "usb-c_console.kicad_sch")
		(attr smd)
		(fp_rect
			(start -0.925 -0.47)
			(end 0.925 0.47)
			(stroke
				(width 0.05)
				(type default)
			)
			(fill no)
			(layer "F.CrtYd")
		)
		(fp_line
			(start 0.504 -0.25)
			(end 0.504 0.248)
			(stroke
				(width 0.15)
				(type solid)
			)
			(layer "F.Fab")
		)
		(fp_line
			(start -0.494 -0.25)
			(end 0.504 -0.25)
			(stroke
				(width 0.15)
				(type solid)
			)
			(layer "F.Fab")
		)
		(fp_line
			(start 0.504 0.248)
			(end -0.494 0.248)
			(stroke
				(width 0.15)
				(type solid)
			)
			(layer "F.Fab")
		)
		(fp_line
			(start -0.494 0.248)
			(end -0.494 -0.25)
			(stroke
				(width 0.15)
				(type solid)
			)
			(layer "F.Fab")
		)
		(pad "1" smd roundrect
			(at -0.48 0 90)
			(size 0.59 0.64)
			(layers "F.Cu" "F.Mask" "F.Paste")
			(roundrect_rratio 0.25)
			(net 1 "GND")
			(pintype "passive")
			(teardrops
				(best_length_ratio 0.2)
				(max_length 1)
				(best_width_ratio 0.9)
				(max_width 2)
				(curved_edges yes)
				(filter_ratio 0.9)
				(enabled yes)
				(allow_two_segments yes)
				(prefer_zone_connections yes)
			)
		)
		(pad "2" smd roundrect
			(at 0.48 0 90)
			(size 0.59 0.64)
			(layers "F.Cu" "F.Mask" "F.Paste")
			(roundrect_rratio 0.25)
			(net 56 "/USB-C console/USB_D-")
			(pintype "passive")
			(teardrops
				(best_length_ratio 0.2)
				(max_length 1)
				(best_width_ratio 0.9)
				(max_width 2)
				(curved_edges yes)
				(filter_ratio 0.9)
				(enabled yes)
				(allow_two_segments yes)
				(prefer_zone_connections yes)
			)
		)
	)
	(footprint "antmicro-footprints:R_0402_1005Metric"
		(layer "F.Cu")
		(at 219.73 125.9)
		(descr "Resistor SMD 0402")
		(tags "resistor SMD 0402")
		(property "Reference" "R189"
			(at 0.77 0.46 0)
			(layer "F.SilkS")
			(effects
				(font
					(size 0.7 0.7)
					(thickness 0.15)
				)
				(justify left bottom)
			)
		)
		(property "Value" "R_1k_0402"
			(at -1.011843 1.772047 0)
			(layer "F.Fab")
			(effects
				(font
					(size 0.7 0.7)
					(thickness 0.15)
				)
				(justify left bottom)
			)
		)
		(property "Datasheet" "https://www.bourns.com/docs/product-datasheets/cr.pdf"
			(at 0 0 0)
			(layer "F.Fab")
			(hide yes)
			(effects
				(font
					(size 1.27 1.27)
					(thickness 0.15)
				)
			)
		)
		(property "Author" "Antmicro"
			(at 0 0 0)
			(layer "F.Fab")
			(hide yes)
			(effects
				(font
					(size 1 1)
					(thickness 0.15)
				)
			)
		)
		(property "License" "Apache-2.0"
			(at 0 0 0)
			(layer "F.Fab")
			(hide yes)
			(effects
				(font
					(size 1 1)
					(thickness 0.15)
				)
			)
		)
		(property "MPN" "CR0402-FX-1001GLF"
			(at 0 0 0)
			(layer "F.Fab")
			(hide yes)
			(effects
				(font
					(size 1 1)
					(thickness 0.15)
				)
			)
		)
		(property "Manufacturer" "Bourns"
			(at 0 0 0)
			(layer "F.Fab")
			(hide yes)
			(effects
				(font
					(size 1 1)
					(thickness 0.15)
				)
			)
		)
		(property "Public" "False"
			(at 0 0 0)
			(layer "F.Fab")
			(hide yes)
			(effects
				(font
					(size 1 1)
					(thickness 0.15)
				)
			)
		)
		(property "Tolerance" "1%"
			(at 0 0 0)
			(layer "F.Fab")
			(hide yes)
			(effects
				(font
					(size 1 1)
					(thickness 0.15)
				)
			)
		)
		(property "Val" "1k"
			(at 0 0 0)
			(layer "F.Fab")
			(hide yes)
			(effects
				(font
					(size 1 1)
					(thickness 0.15)
				)
			)
		)
		(sheetname "PCIe misc")
		(sheetfile "pcie_misc.kicad_sch")
		(attr smd)
		(fp_rect
			(start -0.925 -0.47)
			(end 0.925 0.47)
			(stroke
				(width 0.05)
				(type default)
			)
			(fill no)
			(layer "F.CrtYd")
		)
		(fp_rect
			(start -0.5 -0.25)
			(end 0.5 0.25)
			(stroke
				(width 0.15)
				(type solid)
			)
			(fill no)
			(layer "F.Fab")
		)
		(pad "1" smd roundrect
			(at -0.48 0)
			(size 0.59 0.64)
			(layers "F.Cu" "F.Mask" "F.Paste")
			(roundrect_rratio 0.25)
			(net 608 "Net-(U37-~{OE5})")
			(pintype "passive")
			(teardrops
				(best_length_ratio 0.2)
				(max_length 1)
				(best_width_ratio 0.9)
				(max_width 2)
				(curved_edges yes)
				(filter_ratio 0.9)
				(enabled yes)
				(allow_two_segments yes)
				(prefer_zone_connections yes)
			)
		)
		(pad "2" smd roundrect
			(at 0.48 0)
			(size 0.59 0.64)
			(layers "F.Cu" "F.Mask" "F.Paste")
			(roundrect_rratio 0.25)
			(net 2 "+3V3")
			(pintype "passive")
			(teardrops
				(best_length_ratio 0.2)
				(max_length 1)
				(best_width_ratio 0.9)
				(max_width 2)
				(curved_edges yes)
				(filter_ratio 0.9)
				(enabled yes)
				(allow_two_segments yes)
				(prefer_zone_connections yes)
			)
		)
	)
	(footprint "antmicro-footprints:TP_SMD_0.75mm"
		(layer "F.Cu")
		(at 118.25 73.41 90)
		(property "Reference" "TP7"
			(at 3.9 6.55 0)
			(layer "F.SilkS")
			(effects
				(font
					(size 0.7 0.7)
					(thickness 0.15)
				)
				(justify left bottom)
			)
		)
		(property "Value" "TP_0.75mm_SMD"
			(at 0 1.2 90)
			(layer "F.Fab")
			(effects
				(font
					(size 0.7 0.7)
					(thickness 0.15)
				)
				(justify left bottom)
			)
		)
		(property "Author" "Antmicro"
			(at 191.66 -44.84 0)
			(layer "F.Fab")
			(hide yes)
			(effects
				(font
					(size 1 1)
					(thickness 0.15)
				)
			)
		)
		(property "License" "Apache-2.0"
			(at 191.66 -44.84 0)
			(layer "F.Fab")
			(hide yes)
			(effects
				(font
					(size 1 1)
					(thickness 0.15)
				)
			)
		)
		(property "MPN" ""
			(at 191.66 -44.84 0)
			(layer "F.Fab")
			(hide yes)
			(effects
				(font
					(size 1 1)
					(thickness 0.15)
				)
			)
		)
		(property "Manufacturer" ""
			(at 191.66 -44.84 0)
			(layer "F.Fab")
			(hide yes)
			(effects
				(font
					(size 1 1)
					(thickness 0.15)
				)
			)
		)
		(property "Public" "False"
			(at 191.66 -44.84 0)
			(layer "F.Fab")
			(hide yes)
			(effects
				(font
					(size 1 1)
					(thickness 0.15)
				)
			)
		)
		(sheetname "USB-C console")
		(sheetfile "usb-c_console.kicad_sch")
		(attr exclude_from_pos_files exclude_from_bom)
		(fp_circle
			(center 0 0)
			(end 0.475 0)
			(stroke
				(width 0.05)
				(type default)
			)
			(fill no)
			(layer "F.CrtYd")
		)
		(pad "1" smd circle
			(at 0 0 90)
			(size 0.75 0.75)
			(layers "F.Cu" "F.Mask")
			(net 699 "/USB-C console/FTDI_RX")
			(pinfunction "1")
			(pintype "passive")
			(teardrops
				(best_length_ratio 0.4)
				(max_length 1)
				(best_width_ratio 0.9)
				(max_width 2)
				(curved_edges yes)
				(filter_ratio 0.9)
				(enabled yes)
				(allow_two_segments yes)
				(prefer_zone_connections yes)
			)
		)
	)
	(footprint "antmicro-footprints:C_Pol_EIA-D"
		(layer "F.Cu")
		(at 238.8 159.9)
		(property "Reference" "C94"
			(at 1.7 -3.35 0)
			(layer "F.SilkS")
			(effects
				(font
					(size 0.7 0.7)
					(thickness 0.15)
				)
				(justify left top)
			)
		)
		(property "Value" "C_Pol_68u_16V_Panasonic-TQC-D"
			(at 0 3.4 0)
			(layer "F.Fab")
			(effects
				(font
					(size 0.7 0.7)
					(thickness 0.15)
				)
				(justify left top)
			)
		)
		(property "Datasheet" "https://industrial.panasonic.com/sa/products/pt/aluminum-cap-smd/models/16TQC68MYF"
			(at 0 0 0)
			(layer "F.Fab")
			(hide yes)
			(effects
				(font
					(size 1.27 1.27)
					(thickness 0.15)
				)
			)
		)
		(property "Author" "Antmicro"
			(at 343.2 319.42 0)
			(layer "F.Fab")
			(hide yes)
			(effects
				(font
					(size 1 1)
					(thickness 0.15)
				)
			)
		)
		(property "Dielectric" "template_dielectric"
			(at 343.2 319.42 0)
			(layer "F.Fab")
			(hide yes)
			(effects
				(font
					(size 1 1)
					(thickness 0.15)
				)
			)
		)
		(property "License" "Apache-2.0"
			(at 343.2 319.42 0)
			(layer "F.Fab")
			(hide yes)
			(effects
				(font
					(size 1 1)
					(thickness 0.15)
				)
			)
		)
		(property "MPN" "16TQC68MYF"
			(at 343.2 319.42 0)
			(layer "F.Fab")
			(hide yes)
			(effects
				(font
					(size 1 1)
					(thickness 0.15)
				)
			)
		)
		(property "Manufacturer" "Panasonic"
			(at 343.2 319.42 0)
			(layer "F.Fab")
			(hide yes)
			(effects
				(font
					(size 1 1)
					(thickness 0.15)
				)
			)
		)
		(property "Public" "False"
			(at 343.2 319.42 0)
			(layer "F.Fab")
			(hide yes)
			(effects
				(font
					(size 1 1)
					(thickness 0.15)
				)
			)
		)
		(property "Val" "68u"
			(at 343.2 319.42 0)
			(layer "F.Fab")
			(hide yes)
			(effects
				(font
					(size 1 1)
					(thickness 0.15)
				)
			)
		)
		(property "Voltage" "16V"
			(at 343.2 319.42 0)
			(layer "F.Fab")
			(hide yes)
			(effects
				(font
					(size 1 1)
					(thickness 0.15)
				)
			)
		)
		(sheetname "Com Express 7 MGMT")
		(sheetfile "com_express_7_mgmt.kicad_sch")
		(attr smd)
		(fp_line
			(start -4.3 -1.825)
			(end -3.9 -1.825)
			(stroke
				(width 0.12)
				(type solid)
			)
			(layer "F.SilkS")
		)
		(fp_line
			(start -4.1 -2.025)
			(end -4.1 -1.625)
			(stroke
				(width 0.12)
				(type solid)
			)
			(layer "F.SilkS")
		)
		(fp_line
			(start -3.58 -2.2)
			(end 3.6 -2.2)
			(stroke
				(width 0.15)
				(type solid)
			)
			(layer "F.SilkS")
		)
		(fp_line
			(start -3.58 -1.6)
			(end -3.58 -2.2)
			(stroke
				(width 0.15)
				(type solid)
			)
			(layer "F.SilkS")
		)
		(fp_line
			(start -3.58 2.2)
			(end -3.58 1.6)
			(stroke
				(width 0.15)
				(type solid)
			)
			(layer "F.SilkS")
		)
		(fp_line
			(start 3.6 -2.2)
			(end 3.6 -1.6)
			(stroke
				(width 0.15)
				(type solid)
			)
			(layer "F.SilkS")
		)
		(fp_line
			(start 3.6 1.6)
			(end 3.6 2.2)
			(stroke
				(width 0.15)
				(type solid)
			)
			(layer "F.SilkS")
		)
		(fp_line
			(start 3.6 2.2)
			(end -3.58 2.2)
			(stroke
				(width 0.15)
				(type solid)
			)
			(layer "F.SilkS")
		)
		(fp_line
			(start -4.505 1.51)
			(end -4.505 -1.5)
			(stroke
				(width 0.05)
				(type solid)
			)
			(layer "F.CrtYd")
		)
		(fp_line
			(start -3.775 -2.4)
			(end -3.775 -1.5)
			(stroke
				(width 0.05)
				(type solid)
			)
			(layer "F.CrtYd")
		)
		(fp_line
			(start -3.775 -2.4)
			(end 3.77 -2.4)
			(stroke
				(width 0.05)
				(type solid)
			)
			(layer "F.CrtYd")
		)
		(fp_line
			(start -3.775 -1.5)
			(end -4.505 -1.5)
			(stroke
				(width 0.05)
				(type solid)
			)
			(layer "F.CrtYd")
		)
		(fp_line
			(start -3.77 1.51)
			(end -4.505 1.51)
			(stroke
				(width 0.05)
				(type solid)
			)
			(layer "F.CrtYd")
		)
		(fp_line
			(start -3.77 2.4)
			(end -3.77 1.51)
			(stroke
				(width 0.05)
				(type solid)
			)
			(layer "F.CrtYd")
		)
		(fp_line
			(start 3.77 -2.4)
			(end 3.77 -1.51)
			(stroke
				(width 0.05)
				(type solid)
			)
			(layer "F.CrtYd")
		)
		(fp_line
			(start 3.77 -1.51)
			(end 4.505 -1.51)
			(stroke
				(width 0.05)
				(type solid)
			)
			(layer "F.CrtYd")
		)
		(fp_line
			(start 3.77 1.51)
			(end 3.77 2.4)
			(stroke
				(width 0.05)
				(type solid)
			)
			(layer "F.CrtYd")
		)
		(fp_line
			(start 3.77 2.4)
			(end -3.77 2.4)
			(stroke
				(width 0.05)
				(type solid)
			)
			(layer "F.CrtYd")
		)
		(fp_line
			(start 4.505 -1.51)
			(end 4.505 1.5)
			(stroke
				(width 0.05)
				(type solid)
			)
			(layer "F.CrtYd")
		)
		(fp_line
			(start 4.505 1.51)
			(end 3.77 1.51)
			(stroke
				(width 0.05)
				(type solid)
			)
			(layer "F.CrtYd")
		)
		(fp_rect
			(start -3.65 -2.15)
			(end 3.65 2.15)
			(stroke
				(width 0.15)
				(type solid)
			)
			(fill no)
			(layer "F.Fab")
		)
		(pad "1" smd roundrect
			(at -3.1 0)
			(size 2.31 2.52)
			(layers "F.Cu" "F.Mask" "F.Paste")
			(roundrect_rratio 0.1)
			(net 65 "+12V")
			(pintype "passive")
			(teardrops
				(best_length_ratio 0.2)
				(max_length 1)
				(best_width_ratio 0.9)
				(max_width 2)
				(curved_edges yes)
				(filter_ratio 0.9)
				(enabled yes)
				(allow_two_segments yes)
				(prefer_zone_connections yes)
			)
		)
		(pad "2" smd roundrect
			(at 3.1 0)
			(size 2.31 2.52)
			(layers "F.Cu" "F.Mask" "F.Paste")
			(roundrect_rratio 0.1)
			(net 1 "GND")
			(pintype "passive")
			(teardrops
				(best_length_ratio 0.2)
				(max_length 1)
				(best_width_ratio 0.9)
				(max_width 2)
				(curved_edges yes)
				(filter_ratio 0.9)
				(enabled yes)
				(allow_two_segments yes)
				(prefer_zone_connections yes)
			)
		)
	)
	(footprint "antmicro-footprints:C_0402_1005Metric"
		(layer "F.Cu")
		(at 129.5 111.19 -90)
		(descr "Capacitor SMD 0402")
		(tags "capacitor SMD 0402")
		(property "Reference" "C14"
			(at -0.98 0.5 90)
			(layer "F.SilkS")
			(effects
				(font
					(size 0.7 0.7)
					(thickness 0.15)
				)
				(justify right bottom)
			)
		)
		(property "Value" "C_100n_0402"
			(at -1.022927 2.155213 90)
			(layer "F.Fab")
			(effects
				(font
					(size 0.7 0.7)
					(thickness 0.15)
				)
				(justify right bottom)
			)
		)
		(property "Datasheet" "https://www.murata.com/products/productdetail?partno=GRM155R61H104KE14%23"
			(at 0 0 270)
			(layer "F.Fab")
			(hide yes)
			(effects
				(font
					(size 1.27 1.27)
					(thickness 0.15)
				)
			)
		)
		(property "Author" "Antmicro"
			(at 18.31 240.69 0)
			(layer "F.Fab")
			(hide yes)
			(effects
				(font
					(size 1 1)
					(thickness 0.15)
				)
			)
		)
		(property "Dielectric" "X5R"
			(at 18.31 240.69 0)
			(layer "F.Fab")
			(hide yes)
			(effects
				(font
					(size 1 1)
					(thickness 0.15)
				)
			)
		)
		(property "License" "Apache-2.0"
			(at 18.31 240.69 0)
			(layer "F.Fab")
			(hide yes)
			(effects
				(font
					(size 1 1)
					(thickness 0.15)
				)
			)
		)
		(property "MPN" "GRM155R61H104KE14D"
			(at 18.31 240.69 0)
			(layer "F.Fab")
			(hide yes)
			(effects
				(font
					(size 1 1)
					(thickness 0.15)
				)
			)
		)
		(property "Manufacturer" "Murata"
			(at 18.31 240.69 0)
			(layer "F.Fab")
			(hide yes)
			(effects
				(font
					(size 1 1)
					(thickness 0.15)
				)
			)
		)
		(property "Public" "False"
			(at 18.31 240.69 0)
			(layer "F.Fab")
			(hide yes)
			(effects
				(font
					(size 1 1)
					(thickness 0.15)
				)
			)
		)
		(property "Val" "100n"
			(at 18.31 240.69 0)
			(layer "F.Fab")
			(hide yes)
			(effects
				(font
					(size 1 1)
					(thickness 0.15)
				)
			)
		)
		(property "Voltage" "50V"
			(at 18.31 240.69 0)
			(layer "F.Fab")
			(hide yes)
			(effects
				(font
					(size 1 1)
					(thickness 0.15)
				)
			)
		)
		(sheetname "2xUSB3.0+RJ45")
		(sheetfile "usb3+rj45.kicad_sch")
		(attr smd)
		(fp_rect
			(start -0.925 -0.47)
			(end 0.925 0.47)
			(stroke
				(width 0.05)
				(type default)
			)
			(fill no)
			(layer "F.CrtYd")
		)
		(fp_line
			(start -0.494 0.248)
			(end -0.494 -0.25)
			(stroke
				(width 0.15)
				(type solid)
			)
			(layer "F.Fab")
		)
		(fp_line
			(start 0.504 0.248)
			(end -0.494 0.248)
			(stroke
				(width 0.15)
				(type solid)
			)
			(layer "F.Fab")
		)
		(fp_line
			(start -0.494 -0.25)
			(end 0.504 -0.25)
			(stroke
				(width 0.15)
				(type solid)
			)
			(layer "F.Fab")
		)
		(fp_line
			(start 0.504 -0.25)
			(end 0.504 0.248)
			(stroke
				(width 0.15)
				(type solid)
			)
			(layer "F.Fab")
		)
		(pad "1" smd roundrect
			(at -0.48 0 270)
			(size 0.59 0.64)
			(layers "F.Cu" "F.Mask" "F.Paste")
			(roundrect_rratio 0.25)
			(net 51 "Net-(C13-Pad1)")
			(pintype "passive")
			(teardrops
				(best_length_ratio 0.2)
				(max_length 1)
				(best_width_ratio 0.9)
				(max_width 2)
				(curved_edges yes)
				(filter_ratio 0.9)
				(enabled yes)
				(allow_two_segments yes)
				(prefer_zone_connections yes)
			)
		)
		(pad "2" smd roundrect
			(at 0.48 0 270)
			(size 0.59 0.64)
			(layers "F.Cu" "F.Mask" "F.Paste")
			(roundrect_rratio 0.25)
			(net 1 "GND")
			(pintype "passive")
			(teardrops
				(best_length_ratio 0.2)
				(max_length 1)
				(best_width_ratio 0.9)
				(max_width 2)
				(curved_edges yes)
				(filter_ratio 0.9)
				(enabled yes)
				(allow_two_segments yes)
				(prefer_zone_connections yes)
			)
		)
	)
	(footprint "antmicro-footprints:C_0402_1005Metric"
		(layer "F.Cu")
		(at 310.314499 133.4245 180)
		(descr "Capacitor SMD 0402")
		(tags "capacitor SMD 0402")
		(property "Reference" "C63"
			(at 0.864499 -0.4355 0)
			(layer "F.SilkS")
			(effects
				(font
					(size 0.7 0.7)
					(thickness 0.15)
				)
				(justify right bottom)
			)
		)
		(property "Value" "C_1u_0402"
			(at -1.022927 2.155213 0)
			(layer "F.Fab")
			(effects
				(font
					(size 0.7 0.7)
					(thickness 0.15)
				)
				(justify right bottom)
			)
		)
		(property "Datasheet" "https://product.tdk.com/en/search/capacitor/ceramic/mlcc/info?part_no=C1005X6S1A105K050BC"
			(at 0 0 180)
			(layer "F.Fab")
			(hide yes)
			(effects
				(font
					(size 1.27 1.27)
					(thickness 0.15)
				)
			)
		)
		(property "Author" "Antmicro"
			(at 620.628998 266.849 0)
			(layer "F.Fab")
			(hide yes)
			(effects
				(font
					(size 1 1)
					(thickness 0.15)
				)
			)
		)
		(property "Dielectric" ""
			(at 620.628998 266.849 0)
			(layer "F.Fab")
			(hide yes)
			(effects
				(font
					(size 1 1)
					(thickness 0.15)
				)
			)
		)
		(property "License" "Apache-2.0"
			(at 620.628998 266.849 0)
			(layer "F.Fab")
			(hide yes)
			(effects
				(font
					(size 1 1)
					(thickness 0.15)
				)
			)
		)
		(property "MPN" "C1005X6S1A105K050BC"
			(at 620.628998 266.849 0)
			(layer "F.Fab")
			(hide yes)
			(effects
				(font
					(size 1 1)
					(thickness 0.15)
				)
			)
		)
		(property "Manufacturer" "TDK"
			(at 620.628998 266.849 0)
			(layer "F.Fab")
			(hide yes)
			(effects
				(font
					(size 1 1)
					(thickness 0.15)
				)
			)
		)
		(property "Public" "False"
			(at 620.628998 266.849 0)
			(layer "F.Fab")
			(hide yes)
			(effects
				(font
					(size 1 1)
					(thickness 0.15)
				)
			)
		)
		(property "Val" "1u"
			(at 620.628998 266.849 0)
			(layer "F.Fab")
			(hide yes)
			(effects
				(font
					(size 1 1)
					(thickness 0.15)
				)
			)
		)
		(property "Voltage" ""
			(at 620.628998 266.849 0)
			(layer "F.Fab")
			(hide yes)
			(effects
				(font
					(size 1 1)
					(thickness 0.15)
				)
			)
		)
		(sheetname "Power")
		(sheetfile "power.kicad_sch")
		(attr smd)
		(fp_rect
			(start -0.925 -0.47)
			(end 0.925 0.47)
			(stroke
				(width 0.05)
				(type default)
			)
			(fill no)
			(layer "F.CrtYd")
		)
		(fp_line
			(start 0.504 0.248)
			(end -0.494 0.248)
			(stroke
				(width 0.15)
				(type solid)
			)
			(layer "F.Fab")
		)
		(fp_line
			(start 0.504 -0.25)
			(end 0.504 0.248)
			(stroke
				(width 0.15)
				(type solid)
			)
			(layer "F.Fab")
		)
		(fp_line
			(start -0.494 0.248)
			(end -0.494 -0.25)
			(stroke
				(width 0.15)
				(type solid)
			)
			(layer "F.Fab")
		)
		(fp_line
			(start -0.494 -0.25)
			(end 0.504 -0.25)
			(stroke
				(width 0.15)
				(type solid)
			)
			(layer "F.Fab")
		)
		(pad "1" smd roundrect
			(at -0.48 0 180)
			(size 0.59 0.64)
			(layers "F.Cu" "F.Mask" "F.Paste")
			(roundrect_rratio 0.25)
			(net 1 "GND")
			(pintype "passive")
			(teardrops
				(best_length_ratio 0.2)
				(max_length 1)
				(best_width_ratio 0.9)
				(max_width 2)
				(curved_edges yes)
				(filter_ratio 0.9)
				(enabled yes)
				(allow_two_segments yes)
				(prefer_zone_connections yes)
			)
		)
		(pad "2" smd roundrect
			(at 0.48 0 180)
			(size 0.59 0.64)
			(layers "F.Cu" "F.Mask" "F.Paste")
			(roundrect_rratio 0.25)
			(net 76 "Net-(C63-Pad2)")
			(pintype "passive")
			(teardrops
				(best_length_ratio 0.2)
				(max_length 1)
				(best_width_ratio 0.9)
				(max_width 2)
				(curved_edges yes)
				(filter_ratio 0.9)
				(enabled yes)
				(allow_two_segments yes)
				(prefer_zone_connections yes)
			)
		)
	)
	(footprint "antmicro-footprints:LED_0603_1608Metric_G"
		(layer "F.Cu")
		(at 146.49 168.44 180)
		(descr "LED SMD 0603 Green")
		(tags "LED SMD 0603 Green")
		(property "Reference" "D7"
			(at 1.19 -0.47 0)
			(layer "F.SilkS")
			(effects
				(font
					(size 0.7 0.7)
					(thickness 0.15)
				)
				(justify right bottom)
			)
		)
		(property "Value" "LED_G_0603_LTST-C190GKT"
			(at -0.001 1.599 0)
			(layer "F.Fab")
			(effects
				(font
					(size 0.7 0.7)
					(thickness 0.15)
				)
				(justify right bottom)
			)
		)
		(property "Datasheet" "https://media.digikey.com/pdf/Data%20Sheets/Lite-On%20PDFs/LTST-C190GKT.pdf"
			(at 0 0 180)
			(layer "F.Fab")
			(hide yes)
			(effects
				(font
					(size 1.27 1.27)
					(thickness 0.15)
				)
			)
		)
		(property "Author" "Antmicro"
			(at 292.98 336.88 0)
			(layer "F.Fab")
			(hide yes)
			(effects
				(font
					(size 1 1)
					(thickness 0.15)
				)
			)
		)
		(property "Color" "Green"
			(at 292.98 336.88 0)
			(layer "F.Fab")
			(hide yes)
			(effects
				(font
					(size 1 1)
					(thickness 0.15)
				)
			)
		)
		(property "License" "Apache-2.0"
			(at 292.98 336.88 0)
			(layer "F.Fab")
			(hide yes)
			(effects
				(font
					(size 1 1)
					(thickness 0.15)
				)
			)
		)
		(property "MPN" "LTST-C190GKT"
			(at 292.98 336.88 0)
			(layer "F.Fab")
			(hide yes)
			(effects
				(font
					(size 1 1)
					(thickness 0.15)
				)
			)
		)
		(property "Manufacturer" "Lite-On"
			(at 292.98 336.88 0)
			(layer "F.Fab")
			(hide yes)
			(effects
				(font
					(size 1 1)
					(thickness 0.15)
				)
			)
		)
		(property "Public" "False"
			(at 292.98 336.88 0)
			(layer "F.Fab")
			(hide yes)
			(effects
				(font
					(size 1 1)
					(thickness 0.15)
				)
			)
		)
		(sheetname "2xSFP+")
		(sheetfile "2xSFP+.kicad_sch")
		(attr smd)
		(fp_line
			(start 0.22 0.35)
			(end -0.22 0.35)
			(stroke
				(width 0.15)
				(type solid)
			)
			(layer "F.SilkS")
		)
		(fp_line
			(start 0.22 -0.35)
			(end -0.22 -0.35)
			(stroke
				(width 0.15)
				(type solid)
			)
			(layer "F.SilkS")
		)
		(fp_line
			(start 0.105328 0.201008)
			(end 0.105328 -0.198992)
			(stroke
				(width 0.1)
				(type solid)
			)
			(layer "F.SilkS")
		)
		(fp_line
			(start 0.105328 0.201008)
			(end -0.094672 0.001008)
			(stroke
				(width 0.1)
				(type solid)
			)
			(layer "F.SilkS")
		)
		(fp_line
			(start 0.105328 0.001008)
			(end 0.24 0.001)
			(stroke
				(width 0.1)
				(type solid)
			)
			(layer "F.SilkS")
		)
		(fp_line
			(start -0.094672 0.201008)
			(end -0.094672 -0.198992)
			(stroke
				(width 0.1)
				(type solid)
			)
			(layer "F.SilkS")
		)
		(fp_line
			(start -0.094672 0.001008)
			(end 0.105328 -0.198992)
			(stroke
				(width 0.1)
				(type solid)
			)
			(layer "F.SilkS")
		)
		(fp_line
			(start -0.094672 0.001008)
			(end -0.24 0.001008)
			(stroke
				(width 0.1)
				(type solid)
			)
			(layer "F.SilkS")
		)
		(fp_line
			(start -1.18 -0.319)
			(end -1.18 0.321)
			(stroke
				(width 0.15)
				(type solid)
			)
			(layer "F.SilkS")
		)
		(fp_rect
			(start 1.25 0.65)
			(end -1.25 -0.65)
			(stroke
				(width 0.05)
				(type solid)
			)
			(fill no)
			(layer "F.CrtYd")
		)
		(fp_line
			(start 0.599 0)
			(end 0.201 0)
			(stroke
				(width 0.15)
				(type solid)
			)
			(layer "F.Fab")
		)
		(fp_line
			(start 0.201 0.2)
			(end 0.201 0)
			(stroke
				(width 0.15)
				(type solid)
			)
			(layer "F.Fab")
		)
		(fp_line
			(start 0.201 0)
			(end 0.201 -0.202)
			(stroke
				(width 0.15)
				(type solid)
			)
			(layer "F.Fab")
		)
		(fp_line
			(start 0.201 -0.202)
			(end -0.101 0)
			(stroke
				(width 0.15)
				(type solid)
			)
			(layer "F.Fab")
		)
		(fp_line
			(start -0.101 0)
			(end 0.201 0.2)
			(stroke
				(width 0.15)
				(type solid)
			)
			(layer "F.Fab")
		)
		(fp_line
			(start -0.199 0.2)
			(end -0.199 0.1)
			(stroke
				(width 0.15)
				(type solid)
			)
			(layer "F.Fab")
		)
		(fp_line
			(start -0.199 0)
			(end -0.597 0)
			(stroke
				(width 0.15)
				(type solid)
			)
			(layer "F.Fab")
		)
		(fp_line
			(start -0.199 -0.202)
			(end -0.199 0.1)
			(stroke
				(width 0.15)
				(type solid)
			)
			(layer "F.Fab")
		)
		(fp_rect
			(start 0.848 0.4)
			(end -0.85 -0.402)
			(stroke
				(width 0.15)
				(type solid)
			)
			(fill no)
			(layer "F.Fab")
		)
		(pad "1" smd roundrect
			(at -0.7 0)
			(size 0.8 1)
			(layers "F.Cu" "F.Mask" "F.Paste")
			(roundrect_rratio 0.2)
			(net 932 "Net-(D7-C)")
			(pinfunction "C")
			(pintype "passive")
			(teardrops
				(best_length_ratio 0.2)
				(max_length 1)
				(best_width_ratio 0.9)
				(max_width 2)
				(curved_edges yes)
				(filter_ratio 0.9)
				(enabled yes)
				(allow_two_segments yes)
				(prefer_zone_connections yes)
			)
		)
		(pad "2" smd roundrect
			(at 0.7 0)
			(size 0.8 1)
			(layers "F.Cu" "F.Mask" "F.Paste")
			(roundrect_rratio 0.2)
			(net 2 "+3V3")
			(pinfunction "A")
			(pintype "passive")
			(teardrops
				(best_length_ratio 0.2)
				(max_length 1)
				(best_width_ratio 0.9)
				(max_width 2)
				(curved_edges yes)
				(filter_ratio 0.9)
				(enabled yes)
				(allow_two_segments yes)
				(prefer_zone_connections yes)
			)
		)
	)
	(footprint "antmicro-footprints:R_0402_1005Metric"
		(layer "F.Cu")
		(at 178.4 142.999998 180)
		(descr "Resistor SMD 0402")
		(tags "resistor SMD 0402")
		(property "Reference" "R37"
			(at -2.95 -0.45 0)
			(layer "F.SilkS")
			(effects
				(font
					(size 0.7 0.7)
					(thickness 0.15)
				)
				(justify right bottom)
			)
		)
		(property "Value" "R_0R_0402"
			(at -1.011843 1.772046 0)
			(layer "F.Fab")
			(effects
				(font
					(size 0.7 0.7)
					(thickness 0.15)
				)
				(justify right bottom)
			)
		)
		(property "Datasheet" "https://industrial.panasonic.com/cdbs/www-data/pdf/RDA0000/AOA0000C301.pdf"
			(at 0 0 0)
			(layer "F.Fab")
			(hide yes)
			(effects
				(font
					(size 1.27 1.27)
					(thickness 0.15)
				)
			)
		)
		(property "Author" "Antmicro"
			(at 337.9 328.52 0)
			(layer "F.Fab")
			(hide yes)
			(effects
				(font
					(size 1 1)
					(thickness 0.15)
				)
			)
		)
		(property "Current" "1A"
			(at 337.9 328.52 0)
			(layer "F.Fab")
			(hide yes)
			(effects
				(font
					(size 1 1)
					(thickness 0.15)
				)
			)
		)
		(property "License" "Apache-2.0"
			(at 337.9 328.52 0)
			(layer "F.Fab")
			(hide yes)
			(effects
				(font
					(size 1 1)
					(thickness 0.15)
				)
			)
		)
		(property "MPN" "ERJ2GE0R00X"
			(at 337.9 328.52 0)
			(layer "F.Fab")
			(hide yes)
			(effects
				(font
					(size 1 1)
					(thickness 0.15)
				)
			)
		)
		(property "Manufacturer" "Panasonic"
			(at 337.9 328.52 0)
			(layer "F.Fab")
			(hide yes)
			(effects
				(font
					(size 1 1)
					(thickness 0.15)
				)
			)
		)
		(property "Public" "False"
			(at 337.9 328.52 0)
			(layer "F.Fab")
			(hide yes)
			(effects
				(font
					(size 1 1)
					(thickness 0.15)
				)
			)
		)
		(property "Tolerance" ""
			(at 337.9 328.52 0)
			(layer "F.Fab")
			(hide yes)
			(effects
				(font
					(size 1 1)
					(thickness 0.15)
				)
			)
		)
		(property "Val" "0R"
			(at 337.9 328.52 0)
			(layer "F.Fab")
			(hide yes)
			(effects
				(font
					(size 1 1)
					(thickness 0.15)
				)
			)
		)
		(sheetname "2xSFP+")
		(sheetfile "2xSFP+.kicad_sch")
		(attr smd)
		(fp_rect
			(start -0.925 -0.47)
			(end 0.925 0.47)
			(stroke
				(width 0.05)
				(type default)
			)
			(fill no)
			(layer "F.CrtYd")
		)
		(fp_rect
			(start -0.5 -0.25)
			(end 0.5 0.25)
			(stroke
				(width 0.15)
				(type solid)
			)
			(fill no)
			(layer "F.Fab")
		)
		(pad "1" smd roundrect
			(at -0.48 0 180)
			(size 0.59 0.64)
			(layers "F.Cu" "F.Mask" "F.Paste")
			(roundrect_rratio 0.25)
			(net 425 "/2xSFP+/I2C_{SFP0}.SDA")
			(pintype "passive")
			(teardrops
				(best_length_ratio 0.2)
				(max_length 1)
				(best_width_ratio 0.9)
				(max_width 2)
				(curved_edges yes)
				(filter_ratio 0.9)
				(enabled yes)
				(allow_two_segments yes)
				(prefer_zone_connections yes)
			)
		)
		(pad "2" smd roundrect
			(at 0.48 0 180)
			(size 0.59 0.64)
			(layers "F.Cu" "F.Mask" "F.Paste")
			(roundrect_rratio 0.25)
			(net 164 "/2xSFP+/SDA0")
			(pintype "passive")
			(teardrops
				(best_length_ratio 0.2)
				(max_length 1)
				(best_width_ratio 0.9)
				(max_width 2)
				(curved_edges yes)
				(filter_ratio 0.9)
				(enabled yes)
				(allow_two_segments yes)
				(prefer_zone_connections yes)
			)
		)
	)
	(footprint "antmicro-footprints:TP_SMD_0.75mm"
		(layer "F.Cu")
		(at 145.95 129.56)
		(property "Reference" "TP75"
			(at 0.45 -1.25 90)
			(layer "F.SilkS")
			(effects
				(font
					(size 0.7 0.7)
					(thickness 0.15)
				)
				(justify left bottom)
			)
		)
		(property "Value" "TP_0.75mm_SMD"
			(at 0 1.2 0)
			(layer "F.Fab")
			(effects
				(font
					(size 0.7 0.7)
					(thickness 0.15)
				)
				(justify left bottom)
			)
		)
		(property "Author" "Antmicro"
			(at 0 0 0)
			(layer "F.Fab")
			(hide yes)
			(effects
				(font
					(size 1 1)
					(thickness 0.15)
				)
			)
		)
		(property "License" "Apache-2.0"
			(at 0 0 0)
			(layer "F.Fab")
			(hide yes)
			(effects
				(font
					(size 1 1)
					(thickness 0.15)
				)
			)
		)
		(property "MPN" ""
			(at 0 0 0)
			(layer "F.Fab")
			(hide yes)
			(effects
				(font
					(size 1 1)
					(thickness 0.15)
				)
			)
		)
		(property "Manufacturer" ""
			(at 0 0 0)
			(layer "F.Fab")
			(hide yes)
			(effects
				(font
					(size 1 1)
					(thickness 0.15)
				)
			)
		)
		(property "Public" "False"
			(at 0 0 0)
			(layer "F.Fab")
			(hide yes)
			(effects
				(font
					(size 1 1)
					(thickness 0.15)
				)
			)
		)
		(sheetname "KR to SFI #1")
		(sheetfile "kr_sfi.kicad_sch")
		(attr exclude_from_pos_files exclude_from_bom)
		(fp_circle
			(center 0 0)
			(end 0.475 0)
			(stroke
				(width 0.05)
				(type default)
			)
			(fill no)
			(layer "F.CrtYd")
		)
		(pad "1" smd circle
			(at 0 0)
			(size 0.75 0.75)
			(layers "F.Cu" "F.Mask")
			(net 738 "Net-(U43B-LS_OK_{IN_B})")
			(pinfunction "1")
			(pintype "passive")
			(teardrops
				(best_length_ratio 0.4)
				(max_length 1)
				(best_width_ratio 0.9)
				(max_width 2)
				(curved_edges yes)
				(filter_ratio 0.9)
				(enabled yes)
				(allow_two_segments yes)
				(prefer_zone_connections yes)
			)
		)
	)
	(footprint "antmicro-footprints:Mech_Lightpipe_Bivar_SLP3-300-250-F"
		(layer "F.Cu")
		(at 105.1405 76.266 -90)
		(property "Reference" "H5"
			(at -0.056 -1.5595 270)
			(unlocked yes)
			(layer "F.SilkS")
			(effects
				(font
					(size 0.7 0.7)
					(thickness 0.15)
				)
				(justify left bottom)
			)
		)
		(property "Value" "Lightpipe_Bivar_SLP3-300-250-F"
			(at 0 6.6 270)
			(unlocked yes)
			(layer "F.Fab")
			(effects
				(font
					(size 0.7 0.7)
					(thickness 0.15)
				)
				(justify left bottom)
			)
		)
		(property "Datasheet" "https://www.bivar.com/parts_content/Datasheets/SLP3-XXX-XXX-X.pdf"
			(at 0 0 90)
			(layer "F.Fab")
			(hide yes)
			(effects
				(font
					(size 1.27 1.27)
					(thickness 0.15)
				)
			)
		)
		(property "Manufacturer" "BIVAR"
			(at 0 0 270)
			(unlocked yes)
			(layer "F.Fab")
			(hide yes)
			(effects
				(font
					(size 1 1)
					(thickness 0.15)
				)
			)
		)
		(property "MPN" "SLP3-150-300-F"
			(at 0 0 270)
			(unlocked yes)
			(layer "F.Fab")
			(hide yes)
			(effects
				(font
					(size 1 1)
					(thickness 0.15)
				)
			)
		)
		(property "Author" "Antmicro"
			(at 0 0 270)
			(unlocked yes)
			(layer "F.Fab")
			(hide yes)
			(effects
				(font
					(size 1 1)
					(thickness 0.15)
				)
			)
		)
		(property "License" "Apache-2.0"
			(at 0 0 270)
			(unlocked yes)
			(layer "F.Fab")
			(hide yes)
			(effects
				(font
					(size 1 1)
					(thickness 0.15)
				)
			)
		)
		(sheetname "Misc")
		(sheetfile "misc.kicad_sch")
		(attr through_hole)
		(fp_rect
			(start -1.04 -1.225)
			(end 3.559 5.326)
			(stroke
				(width 0.15)
				(type solid)
			)
			(fill no)
			(layer "F.SilkS")
		)
		(fp_rect
			(start -1.3 4.196)
			(end 3.819 5.596)
			(stroke
				(width 0.05)
				(type solid)
			)
			(fill no)
			(layer "F.CrtYd")
		)
		(fp_rect
			(start -1.301 -1.504)
			(end 3.819 1.196)
			(stroke
				(width 0.05)
				(type solid)
			)
			(fill no)
			(layer "F.CrtYd")
		)
		(fp_line
			(start 0.55 2.5)
			(end 1.25 2.5)
			(stroke
				(width 0.15)
				(type solid)
			)
			(layer "F.Fab")
		)
		(fp_line
			(start 1.25 2.5)
			(end 1.25 3.201)
			(stroke
				(width 0.15)
				(type solid)
			)
			(layer "F.Fab")
		)
		(fp_line
			(start 1.25 2.5)
			(end 1.95 2.5)
			(stroke
				(width 0.15)
				(type solid)
			)
			(layer "F.Fab")
		)
		(fp_line
			(start 1.25 1.8)
			(end 1.25 2.5)
			(stroke
				(width 0.15)
				(type solid)
			)
			(layer "F.Fab")
		)
		(fp_rect
			(start -0.791 1.376)
			(end 3.309 3.625)
			(stroke
				(width 0.15)
				(type solid)
			)
			(fill no)
			(layer "F.Fab")
		)
		(pad "" np_thru_hole circle
			(at 0 0 270)
			(size 1.2 1.2)
			(drill 1.3208)
			(layers "F&B.Cu" "*.Mask")
		)
		(pad "" np_thru_hole circle
			(at 2.5 0 270)
			(size 1.2 1.2)
			(drill 1.3208)
			(layers "F&B.Cu" "*.Mask")
		)
	)
	(footprint "antmicro-footprints:Spacer_Drill3.7mm_H5mm_9774050151R"
		(layer "F.Cu")
		(at 278.93 167.8 90)
		(descr "Spacer M=3 h=5mm fi=5.1mm")
		(property "Reference" "H10"
			(at -1.19 -3.43 90)
			(layer "F.SilkS")
			(hide yes)
			(effects
				(font
					(size 0.7 0.7)
					(thickness 0.15)
				)
				(justify left bottom)
			)
		)
		(property "Value" "Spacer_Drill3.7mm_H5mm_9774050151R"
			(at 0 4 90)
			(layer "F.Fab")
			(effects
				(font
					(size 0.7 0.7)
					(thickness 0.15)
				)
				(justify left bottom)
			)
		)
		(property "Datasheet" "https://www.we-online.com/catalog/datasheet/9774050151.pdf"
			(at 0 0 90)
			(layer "F.Fab")
			(hide yes)
			(effects
				(font
					(size 1.27 1.27)
					(thickness 0.15)
				)
			)
		)
		(property "Author" "Antmicro"
			(at 446.74 -111.12 0)
			(layer "F.Fab")
			(hide yes)
			(effects
				(font
					(size 1 1)
					(thickness 0.15)
				)
			)
		)
		(property "License" "Apache-2.0"
			(at 446.74 -111.12 0)
			(layer "F.Fab")
			(hide yes)
			(effects
				(font
					(size 1 1)
					(thickness 0.15)
				)
			)
		)
		(property "MPN" "9774050151R"
			(at 446.74 -111.12 0)
			(layer "F.Fab")
			(hide yes)
			(effects
				(font
					(size 1 1)
					(thickness 0.15)
				)
			)
		)
		(property "Manufacturer" "Würth Elektronik"
			(at 446.74 -111.12 0)
			(layer "F.Fab")
			(hide yes)
			(effects
				(font
					(size 1 1)
					(thickness 0.15)
				)
			)
		)
		(sheetname "Com Express 7 Interfaces")
		(sheetfile "com_express_7_interfaces.kicad_sch")
		(solder_paste_margin_ratio -1)
		(attr smd)
		(fp_circle
			(center 0 0)
			(end 3.05 0)
			(stroke
				(width 0.05)
				(type solid)
			)
			(fill no)
			(layer "F.CrtYd")
		)
		(fp_circle
			(center 0 0)
			(end 2.6 0)
			(stroke
				(width 0.15)
				(type solid)
			)
			(fill no)
			(layer "F.Fab")
		)
		(pad "" smd custom
			(at -1.7 -1.7 90)
			(size 0.62 0.62)
			(layers "F.Paste")
			(thermal_bridge_angle 90)
			(options
				(clearance outline)
				(anchor circle)
			)
			(primitives
				(gr_arc
					(start -0.250195 1.279127)
					(mid 0.285453 0.294389)
					(end 1.266786 -0.24747)
					(width 0.2)
				)
				(gr_arc
					(start -0.34334 1.279127)
					(mid 0.218448 0.232561)
					(end 1.259603 -0.339191)
					(width 0.2)
				)
				(gr_arc
					(start -0.436309 1.279127)
					(mid 0.152481 0.169693)
					(end 1.255279 -0.431435)
					(width 0.2)
				)
				(gr_arc
					(start -0.529126 1.279127)
					(mid 0.087542 0.105784)
					(end 1.253811 -0.524161)
					(width 0.2)
				)
				(gr_arc
					(start -0.621807 1.279127)
					(mid 0.0309 0.033527)
					(end 1.275473 -0.621136)
					(width 0.2)
				)
				(gr_arc
					(start -0.71437 1.279127)
					(mid -0.037758 -0.026651)
					(end 1.263664 -0.711602)
					(width 0.2)
				)
				(gr_arc
					(start -0.806826 1.279127)
					(mid -0.105837 -0.087395)
					(end 1.253435 -0.802342)
					(width 0.2)
				)
				(gr_arc
					(start -0.899187 1.279127)
					(mid -0.165236 -0.156885)
					(end 1.267475 -0.897258)
					(width 0.2)
				)
				(gr_arc
					(start -0.991463 1.279127)
					(mid -0.228522 -0.222449)
					(end 1.270645 -0.990112)
					(width 0.2)
				)
				(gr_arc
					(start -1.083663 1.279127)
					(mid -0.294507 -0.285313)
					(end 1.266278 -1.081674)
					(width 0.2)
				)
				(gr_line
					(start 1.279127 -0.250195)
					(end 1.279127 -1.083663)
					(width 0.2)
				)
				(gr_line
					(start -0.250195 1.279127)
					(end -1.083663 1.279127)
					(width 0.2)
				)
			)
			(teardrops
				(best_length_ratio 0.2)
				(max_length 1)
				(best_width_ratio 0.9)
				(max_width 2)
				(curved_edges yes)
				(filter_ratio 0.9)
				(enabled yes)
				(allow_two_segments yes)
				(prefer_zone_connections yes)
			)
		)
		(pad "" smd custom
			(at -1.7 1.7 180)
			(size 0.62 0.62)
			(layers "F.Paste")
			(thermal_bridge_angle 90)
			(options
				(clearance outline)
				(anchor circle)
			)
			(primitives
				(gr_arc
					(start -0.250195 1.279127)
					(mid 0.285453 0.294389)
					(end 1.266786 -0.24747)
					(width 0.2)
				)
				(gr_arc
					(start -0.34334 1.279127)
					(mid 0.218448 0.232561)
					(end 1.259603 -0.339191)
					(width 0.2)
				)
				(gr_arc
					(start -0.436309 1.279127)
					(mid 0.152481 0.169693)
					(end 1.255279 -0.431435)
					(width 0.2)
				)
				(gr_arc
					(start -0.529126 1.279127)
					(mid 0.087542 0.105784)
					(end 1.253811 -0.524161)
					(width 0.2)
				)
				(gr_arc
					(start -0.621807 1.279127)
					(mid 0.0309 0.033527)
					(end 1.275473 -0.621136)
					(width 0.2)
				)
				(gr_arc
					(start -0.71437 1.279127)
					(mid -0.037758 -0.026651)
					(end 1.263664 -0.711602)
					(width 0.2)
				)
				(gr_arc
					(start -0.806826 1.279127)
					(mid -0.105837 -0.087395)
					(end 1.253435 -0.802342)
					(width 0.2)
				)
				(gr_arc
					(start -0.899187 1.279127)
					(mid -0.165236 -0.156885)
					(end 1.267475 -0.897258)
					(width 0.2)
				)
				(gr_arc
					(start -0.991463 1.279127)
					(mid -0.228522 -0.222449)
					(end 1.270645 -0.990112)
					(width 0.2)
				)
				(gr_arc
					(start -1.083663 1.279127)
					(mid -0.294507 -0.285313)
					(end 1.266278 -1.081674)
					(width 0.2)
				)
				(gr_line
					(start 1.279127 -0.250195)
					(end 1.279127 -1.083663)
					(width 0.2)
				)
				(gr_line
					(start -0.250195 1.279127)
					(end -1.083663 1.279127)
					(width 0.2)
				)
			)
			(teardrops
				(best_length_ratio 0.2)
				(max_length 1)
				(best_width_ratio 0.9)
				(max_width 2)
				(curved_edges yes)
				(filter_ratio 0.9)
				(enabled yes)
				(allow_two_segments yes)
				(prefer_zone_connections yes)
			)
		)
		(pad "" smd custom
			(at 1.7 -1.7)
			(size 0.62 0.62)
			(layers "F.Paste")
			(thermal_bridge_angle 90)
			(options
				(clearance outline)
				(anchor circle)
			)
			(primitives
				(gr_arc
					(start -0.250195 1.279127)
					(mid 0.285453 0.294389)
					(end 1.266786 -0.24747)
					(width 0.2)
				)
				(gr_arc
					(start -0.34334 1.279127)
					(mid 0.218448 0.232561)
					(end 1.259603 -0.339191)
					(width 0.2)
				)
				(gr_arc
					(start -0.436309 1.279127)
					(mid 0.152481 0.169693)
					(end 1.255279 -0.431435)
					(width 0.2)
				)
				(gr_arc
					(start -0.529126 1.279127)
					(mid 0.087542 0.105784)
					(end 1.253811 -0.524161)
					(width 0.2)
				)
				(gr_arc
					(start -0.621807 1.279127)
					(mid 0.0309 0.033527)
					(end 1.275473 -0.621136)
					(width 0.2)
				)
				(gr_arc
					(start -0.71437 1.279127)
					(mid -0.037758 -0.026651)
					(end 1.263664 -0.711602)
					(width 0.2)
				)
				(gr_arc
					(start -0.806826 1.279127)
					(mid -0.105837 -0.087395)
					(end 1.253435 -0.802342)
					(width 0.2)
				)
				(gr_arc
					(start -0.899187 1.279127)
					(mid -0.165236 -0.156885)
					(end 1.267475 -0.897258)
					(width 0.2)
				)
				(gr_arc
					(start -0.991463 1.279127)
					(mid -0.228522 -0.222449)
					(end 1.270645 -0.990112)
					(width 0.2)
				)
				(gr_arc
					(start -1.083663 1.279127)
					(mid -0.294507 -0.285313)
					(end 1.266278 -1.081674)
					(width 0.2)
				)
				(gr_line
					(start 1.279127 -0.250195)
					(end 1.279127 -1.083663)
					(width 0.2)
				)
				(gr_line
					(start -0.250195 1.279127)
					(end -1.083663 1.279127)
					(width 0.2)
				)
			)
			(teardrops
				(best_length_ratio 0.2)
				(max_length 1)
				(best_width_ratio 0.9)
				(max_width 2)
				(curved_edges yes)
				(filter_ratio 0.9)
				(enabled yes)
				(allow_two_segments yes)
				(prefer_zone_connections yes)
			)
		)
		(pad "" smd custom
			(at 1.7 1.7 270)
			(size 0.62 0.62)
			(layers "F.Paste")
			(thermal_bridge_angle 90)
			(options
				(clearance outline)
				(anchor circle)
			)
			(primitives
				(gr_arc
					(start -0.250195 1.279127)
					(mid 0.285453 0.294389)
					(end 1.266786 -0.24747)
					(width 0.2)
				)
				(gr_arc
					(start -0.34334 1.279127)
					(mid 0.218448 0.232561)
					(end 1.259603 -0.339191)
					(width 0.2)
				)
				(gr_arc
					(start -0.436309 1.279127)
					(mid 0.152481 0.169693)
					(end 1.255279 -0.431435)
					(width 0.2)
				)
				(gr_arc
					(start -0.529126 1.279127)
					(mid 0.087542 0.105784)
					(end 1.253811 -0.524161)
					(width 0.2)
				)
				(gr_arc
					(start -0.621807 1.279127)
					(mid 0.0309 0.033527)
					(end 1.275473 -0.621136)
					(width 0.2)
				)
				(gr_arc
					(start -0.71437 1.279127)
					(mid -0.037758 -0.026651)
					(end 1.263664 -0.711602)
					(width 0.2)
				)
				(gr_arc
					(start -0.806826 1.279127)
					(mid -0.105837 -0.087395)
					(end 1.253435 -0.802342)
					(width 0.2)
				)
				(gr_arc
					(start -0.899187 1.279127)
					(mid -0.165236 -0.156885)
					(end 1.267475 -0.897258)
					(width 0.2)
				)
				(gr_arc
					(start -0.991463 1.279127)
					(mid -0.228522 -0.222449)
					(end 1.270645 -0.990112)
					(width 0.2)
				)
				(gr_arc
					(start -1.083663 1.279127)
					(mid -0.294507 -0.285313)
					(end 1.266278 -1.081674)
					(width 0.2)
				)
				(gr_line
					(start 1.279127 -0.250195)
					(end 1.279127 -1.083663)
					(width 0.2)
				)
				(gr_line
					(start -0.250195 1.279127)
					(end -1.083663 1.279127)
					(width 0.2)
				)
			)
			(teardrops
				(best_length_ratio 0.2)
				(max_length 1)
				(best_width_ratio 0.9)
				(max_width 2)
				(curved_edges yes)
				(filter_ratio 0.9)
				(enabled yes)
				(allow_two_segments yes)
				(prefer_zone_connections yes)
			)
		)
		(pad "1" thru_hole circle
			(at 0 0 90)
			(size 6 6)
			(drill 3.7)
			(layers "*.Cu" "*.Mask")
			(remove_unused_layers no)
			(net 1 "GND")
			(pintype "passive")
			(teardrops
				(best_length_ratio 0.4)
				(max_length 1)
				(best_width_ratio 0.9)
				(max_width 2)
				(curved_edges yes)
				(filter_ratio 0.9)
				(enabled yes)
				(allow_two_segments yes)
				(prefer_zone_connections yes)
			)
		)
	)
	(footprint "antmicro-footprints:R_0201"
		(layer "F.Cu")
		(at 153.33 147.31 90)
		(descr "Resistor SMD 0201")
		(tags "resistor SMD 0201")
		(property "Reference" "R256"
			(at -4.125 0.57 90)
			(layer "F.SilkS")
			(effects
				(font
					(size 0.7 0.7)
					(thickness 0.15)
				)
				(justify left bottom)
			)
		)
		(property "Value" "R_0R_0201"
			(at 0 1.25 90)
			(layer "F.Fab")
			(effects
				(font
					(size 0.7 0.7)
					(thickness 0.15)
				)
				(justify left bottom)
			)
		)
		(property "Datasheet" "https://www.bourns.com/docs/product-datasheets/cr.pdf"
			(at 0 0 90)
			(layer "F.Fab")
			(hide yes)
			(effects
				(font
					(size 1.27 1.27)
					(thickness 0.15)
				)
			)
		)
		(property "Author" "Antmicro"
			(at 300.64 -6.02 0)
			(layer "F.Fab")
			(hide yes)
			(effects
				(font
					(size 1 1)
					(thickness 0.15)
				)
			)
		)
		(property "License" "Apache-2.0"
			(at 300.64 -6.02 0)
			(layer "F.Fab")
			(hide yes)
			(effects
				(font
					(size 1 1)
					(thickness 0.15)
				)
			)
		)
		(property "MPN" "CR0201-FX-0R00GLF"
			(at 300.64 -6.02 0)
			(layer "F.Fab")
			(hide yes)
			(effects
				(font
					(size 1 1)
					(thickness 0.15)
				)
			)
		)
		(property "Manufacturer" "Bourns"
			(at 300.64 -6.02 0)
			(layer "F.Fab")
			(hide yes)
			(effects
				(font
					(size 1 1)
					(thickness 0.15)
				)
			)
		)
		(property "Tolerance" "1%"
			(at 300.64 -6.02 0)
			(layer "F.Fab")
			(hide yes)
			(effects
				(font
					(size 1 1)
					(thickness 0.15)
				)
			)
		)
		(property "Val" "0R"
			(at 300.64 -6.02 0)
			(layer "F.Fab")
			(hide yes)
			(effects
				(font
					(size 1 1)
					(thickness 0.15)
				)
			)
		)
		(sheetname "KR to SFI #1")
		(sheetfile "kr_sfi.kicad_sch")
		(attr smd)
		(fp_rect
			(start -0.7 -0.35)
			(end 0.7 0.35)
			(stroke
				(width 0.05)
				(type default)
			)
			(fill no)
			(layer "F.CrtYd")
		)
		(fp_rect
			(start -0.3 -0.15)
			(end 0.298 0.148)
			(stroke
				(width 0.15)
				(type solid)
			)
			(fill no)
			(layer "F.Fab")
		)
		(pad "" smd roundrect
			(at -0.346 0 90)
			(size 0.318 0.36)
			(layers "F.Paste")
			(roundrect_rratio 0.25)
			(teardrops
				(best_length_ratio 0.2)
				(max_length 1)
				(best_width_ratio 0.9)
				(max_width 2)
				(curved_edges yes)
				(filter_ratio 0.9)
				(enabled yes)
				(allow_two_segments yes)
				(prefer_zone_connections yes)
			)
		)
		(pad "" smd roundrect
			(at 0.344 0 90)
			(size 0.318 0.36)
			(layers "F.Paste")
			(roundrect_rratio 0.25)
			(teardrops
				(best_length_ratio 0.2)
				(max_length 1)
				(best_width_ratio 0.9)
				(max_width 2)
				(curved_edges yes)
				(filter_ratio 0.9)
				(enabled yes)
				(allow_two_segments yes)
				(prefer_zone_connections yes)
			)
		)
		(pad "1" smd roundrect
			(at -0.32 0 90)
			(size 0.46 0.4)
			(layers "F.Cu" "F.Mask")
			(roundrect_rratio 0.25)
			(net 432 "/2xSFP+/10GKR_SFP0.RX+")
			(pintype "passive")
			(teardrops
				(best_length_ratio 0.2)
				(max_length 1)
				(best_width_ratio 0.9)
				(max_width 2)
				(curved_edges yes)
				(filter_ratio 0.9)
				(enabled yes)
				(allow_two_segments yes)
				(prefer_zone_connections yes)
			)
		)
		(pad "2" smd roundrect
			(at 0.32 0 90)
			(size 0.46 0.4)
			(layers "F.Cu" "F.Mask")
			(roundrect_rratio 0.25)
			(net 664 "/2xSFP+/KR to SFI #1/KR_R.RX+")
			(pintype "passive")
			(teardrops
				(best_length_ratio 0.2)
				(max_length 1)
				(best_width_ratio 0.9)
				(max_width 2)
				(curved_edges yes)
				(filter_ratio 0.9)
				(enabled yes)
				(allow_two_segments yes)
				(prefer_zone_connections yes)
			)
		)
	)
	(footprint "antmicro-footprints:R_0402_1005Metric"
		(layer "F.Cu")
		(at 157.55 156.81 -90)
		(descr "Resistor SMD 0402")
		(tags "resistor SMD 0402")
		(property "Reference" "R35"
			(at -3.013 -0.449 90)
			(layer "F.SilkS")
			(effects
				(font
					(size 0.7 0.7)
					(thickness 0.15)
				)
				(justify right bottom)
			)
		)
		(property "Value" "R_0R_0402"
			(at -1.011843 1.772047 90)
			(layer "F.Fab")
			(effects
				(font
					(size 0.7 0.7)
					(thickness 0.15)
				)
				(justify right bottom)
			)
		)
		(property "Datasheet" "https://industrial.panasonic.com/cdbs/www-data/pdf/RDA0000/AOA0000C301.pdf"
			(at 0 0 270)
			(layer "F.Fab")
			(hide yes)
			(effects
				(font
					(size 1.27 1.27)
					(thickness 0.15)
				)
			)
		)
		(property "Author" "Antmicro"
			(at 0.74 314.36 0)
			(layer "F.Fab")
			(hide yes)
			(effects
				(font
					(size 1 1)
					(thickness 0.15)
				)
			)
		)
		(property "Current" "1A"
			(at 0.74 314.36 0)
			(layer "F.Fab")
			(hide yes)
			(effects
				(font
					(size 1 1)
					(thickness 0.15)
				)
			)
		)
		(property "License" "Apache-2.0"
			(at 0.74 314.36 0)
			(layer "F.Fab")
			(hide yes)
			(effects
				(font
					(size 1 1)
					(thickness 0.15)
				)
			)
		)
		(property "MPN" "ERJ2GE0R00X"
			(at 0.74 314.36 0)
			(layer "F.Fab")
			(hide yes)
			(effects
				(font
					(size 1 1)
					(thickness 0.15)
				)
			)
		)
		(property "Manufacturer" "Panasonic"
			(at 0.74 314.36 0)
			(layer "F.Fab")
			(hide yes)
			(effects
				(font
					(size 1 1)
					(thickness 0.15)
				)
			)
		)
		(property "Public" "False"
			(at 0.74 314.36 0)
			(layer "F.Fab")
			(hide yes)
			(effects
				(font
					(size 1 1)
					(thickness 0.15)
				)
			)
		)
		(property "Tolerance" ""
			(at 0.74 314.36 0)
			(layer "F.Fab")
			(hide yes)
			(effects
				(font
					(size 1 1)
					(thickness 0.15)
				)
			)
		)
		(property "Val" "0R"
			(at 0.74 314.36 0)
			(layer "F.Fab")
			(hide yes)
			(effects
				(font
					(size 1 1)
					(thickness 0.15)
				)
			)
		)
		(sheetname "2xSFP+")
		(sheetfile "2xSFP+.kicad_sch")
		(attr smd)
		(fp_rect
			(start -0.925 -0.47)
			(end 0.925 0.47)
			(stroke
				(width 0.05)
				(type default)
			)
			(fill no)
			(layer "F.CrtYd")
		)
		(fp_rect
			(start -0.5 -0.25)
			(end 0.5 0.25)
			(stroke
				(width 0.15)
				(type solid)
			)
			(fill no)
			(layer "F.Fab")
		)
		(pad "1" smd roundrect
			(at -0.48 0 270)
			(size 0.59 0.64)
			(layers "F.Cu" "F.Mask" "F.Paste")
			(roundrect_rratio 0.25)
			(net 528 "/Backplane/~{PERST}")
			(pintype "passive")
			(teardrops
				(best_length_ratio 0.2)
				(max_length 1)
				(best_width_ratio 0.9)
				(max_width 2)
				(curved_edges yes)
				(filter_ratio 0.9)
				(enabled yes)
				(allow_two_segments yes)
				(prefer_zone_connections yes)
			)
		)
		(pad "2" smd roundrect
			(at 0.48 0 270)
			(size 0.59 0.64)
			(layers "F.Cu" "F.Mask" "F.Paste")
			(roundrect_rratio 0.25)
			(net 560 "Net-(U5-~{RESET})")
			(pintype "passive")
			(teardrops
				(best_length_ratio 0.2)
				(max_length 1)
				(best_width_ratio 0.9)
				(max_width 2)
				(curved_edges yes)
				(filter_ratio 0.9)
				(enabled yes)
				(allow_two_segments yes)
				(prefer_zone_connections yes)
			)
		)
	)
	(footprint "antmicro-footprints:R_0402_1005Metric"
		(layer "F.Cu")
		(at 136.6 105.3 180)
		(descr "Resistor SMD 0402")
		(tags "resistor SMD 0402")
		(property "Reference" "R15"
			(at -1.1 -1.4 0)
			(layer "F.SilkS")
			(effects
				(font
					(size 0.7 0.7)
					(thickness 0.15)
				)
				(justify right bottom)
			)
		)
		(property "Value" "R_75R_0402"
			(at -1.011843 1.772047 0)
			(layer "F.Fab")
			(effects
				(font
					(size 0.7 0.7)
					(thickness 0.15)
				)
				(justify right bottom)
			)
		)
		(property "Datasheet" "https://www.bourns.com/docs/product-datasheets/cr.pdf"
			(at 0 0 180)
			(layer "F.Fab")
			(hide yes)
			(effects
				(font
					(size 1.27 1.27)
					(thickness 0.15)
				)
			)
		)
		(property "Author" "Antmicro"
			(at 273.2 210.6 0)
			(layer "F.Fab")
			(hide yes)
			(effects
				(font
					(size 1 1)
					(thickness 0.15)
				)
			)
		)
		(property "License" "Apache-2.0"
			(at 273.2 210.6 0)
			(layer "F.Fab")
			(hide yes)
			(effects
				(font
					(size 1 1)
					(thickness 0.15)
				)
			)
		)
		(property "MPN" "CR0402-FX-75R0GLF"
			(at 273.2 210.6 0)
			(layer "F.Fab")
			(hide yes)
			(effects
				(font
					(size 1 1)
					(thickness 0.15)
				)
			)
		)
		(property "Manufacturer" "Bourns"
			(at 273.2 210.6 0)
			(layer "F.Fab")
			(hide yes)
			(effects
				(font
					(size 1 1)
					(thickness 0.15)
				)
			)
		)
		(property "Public" "False"
			(at 273.2 210.6 0)
			(layer "F.Fab")
			(hide yes)
			(effects
				(font
					(size 1 1)
					(thickness 0.15)
				)
			)
		)
		(property "Tolerance" "1%"
			(at 273.2 210.6 0)
			(layer "F.Fab")
			(hide yes)
			(effects
				(font
					(size 1 1)
					(thickness 0.15)
				)
			)
		)
		(property "Val" "75R"
			(at 273.2 210.6 0)
			(layer "F.Fab")
			(hide yes)
			(effects
				(font
					(size 1 1)
					(thickness 0.15)
				)
			)
		)
		(sheetname "2xUSB3.0+RJ45")
		(sheetfile "usb3+rj45.kicad_sch")
		(attr smd)
		(fp_rect
			(start -0.925 -0.47)
			(end 0.925 0.47)
			(stroke
				(width 0.05)
				(type default)
			)
			(fill no)
			(layer "F.CrtYd")
		)
		(fp_rect
			(start -0.5 -0.25)
			(end 0.5 0.25)
			(stroke
				(width 0.15)
				(type solid)
			)
			(fill no)
			(layer "F.Fab")
		)
		(pad "1" smd roundrect
			(at -0.48 0 180)
			(size 0.59 0.64)
			(layers "F.Cu" "F.Mask" "F.Paste")
			(roundrect_rratio 0.25)
			(net 50 "Net-(C12-Pad2)")
			(pintype "passive")
			(teardrops
				(best_length_ratio 0.2)
				(max_length 1)
				(best_width_ratio 0.9)
				(max_width 2)
				(curved_edges yes)
				(filter_ratio 0.9)
				(enabled yes)
				(allow_two_segments yes)
				(prefer_zone_connections yes)
			)
		)
		(pad "2" smd roundrect
			(at 0.48 0 180)
			(size 0.59 0.64)
			(layers "F.Cu" "F.Mask" "F.Paste")
			(roundrect_rratio 0.25)
			(net 550 "Net-(R15-Pad2)")
			(pintype "passive")
			(teardrops
				(best_length_ratio 0.2)
				(max_length 1)
				(best_width_ratio 0.9)
				(max_width 2)
				(curved_edges yes)
				(filter_ratio 0.9)
				(enabled yes)
				(allow_two_segments yes)
				(prefer_zone_connections yes)
			)
		)
	)
	(footprint "antmicro-footprints:R_0402_1005Metric"
		(layer "F.Cu")
		(at 246.35 128.31 90)
		(descr "Resistor SMD 0402")
		(tags "resistor SMD 0402")
		(property "Reference" "R166"
			(at 0.8 0.45 90)
			(layer "F.SilkS")
			(effects
				(font
					(size 0.7 0.7)
					(thickness 0.15)
				)
				(justify left bottom)
			)
		)
		(property "Value" "R_1k_0402"
			(at -1.011843 1.772047 90)
			(layer "F.Fab")
			(effects
				(font
					(size 0.7 0.7)
					(thickness 0.15)
				)
				(justify left bottom)
			)
		)
		(property "Datasheet" "https://www.bourns.com/docs/product-datasheets/cr.pdf"
			(at 0 0 90)
			(layer "F.Fab")
			(hide yes)
			(effects
				(font
					(size 1.27 1.27)
					(thickness 0.15)
				)
			)
		)
		(property "Author" "Antmicro"
			(at 374.66 -118.04 0)
			(layer "F.Fab")
			(hide yes)
			(effects
				(font
					(size 1 1)
					(thickness 0.15)
				)
			)
		)
		(property "License" "Apache-2.0"
			(at 374.66 -118.04 0)
			(layer "F.Fab")
			(hide yes)
			(effects
				(font
					(size 1 1)
					(thickness 0.15)
				)
			)
		)
		(property "MPN" "CR0402-FX-1001GLF"
			(at 374.66 -118.04 0)
			(layer "F.Fab")
			(hide yes)
			(effects
				(font
					(size 1 1)
					(thickness 0.15)
				)
			)
		)
		(property "Manufacturer" "Bourns"
			(at 374.66 -118.04 0)
			(layer "F.Fab")
			(hide yes)
			(effects
				(font
					(size 1 1)
					(thickness 0.15)
				)
			)
		)
		(property "Public" "False"
			(at 374.66 -118.04 0)
			(layer "F.Fab")
			(hide yes)
			(effects
				(font
					(size 1 1)
					(thickness 0.15)
				)
			)
		)
		(property "Tolerance" "1%"
			(at 374.66 -118.04 0)
			(layer "F.Fab")
			(hide yes)
			(effects
				(font
					(size 1 1)
					(thickness 0.15)
				)
			)
		)
		(property "Val" "1k"
			(at 374.66 -118.04 0)
			(layer "F.Fab")
			(hide yes)
			(effects
				(font
					(size 1 1)
					(thickness 0.15)
				)
			)
		)
		(sheetname "Com Express 7 MGMT")
		(sheetfile "com_express_7_mgmt.kicad_sch")
		(attr smd dnp)
		(fp_rect
			(start -0.925 -0.47)
			(end 0.925 0.47)
			(stroke
				(width 0.05)
				(type default)
			)
			(fill no)
			(layer "F.CrtYd")
		)
		(fp_rect
			(start -0.5 -0.25)
			(end 0.5 0.25)
			(stroke
				(width 0.15)
				(type solid)
			)
			(fill no)
			(layer "F.Fab")
		)
		(pad "1" smd roundrect
			(at -0.48 0 90)
			(size 0.59 0.64)
			(layers "F.Cu" "F.Mask" "F.Paste")
			(roundrect_rratio 0.25)
			(net 84 "/Com Express 7 MGMT/PWRBTN")
			(pintype "passive")
			(teardrops
				(best_length_ratio 0.2)
				(max_length 1)
				(best_width_ratio 0.9)
				(max_width 2)
				(curved_edges yes)
				(filter_ratio 0.9)
				(enabled yes)
				(allow_two_segments yes)
				(prefer_zone_connections yes)
			)
		)
		(pad "2" smd roundrect
			(at 0.48 0 90)
			(size 0.59 0.64)
			(layers "F.Cu" "F.Mask" "F.Paste")
			(roundrect_rratio 0.25)
			(net 73 "+3V3_AON")
			(pintype "passive")
			(teardrops
				(best_length_ratio 0.2)
				(max_length 1)
				(best_width_ratio 0.9)
				(max_width 2)
				(curved_edges yes)
				(filter_ratio 0.9)
				(enabled yes)
				(allow_two_segments yes)
				(prefer_zone_connections yes)
			)
		)
	)
	(footprint "antmicro-footprints:R_0402_1005Metric"
		(layer "F.Cu")
		(at 143 132.88)
		(descr "Resistor SMD 0402")
		(tags "resistor SMD 0402")
		(property "Reference" "R268"
			(at -3.6 0.43 0)
			(layer "F.SilkS")
			(effects
				(font
					(size 0.7 0.7)
					(thickness 0.15)
				)
				(justify left bottom)
			)
		)
		(property "Value" "R_10k_0402"
			(at -1.011843 1.772047 0)
			(layer "F.Fab")
			(effects
				(font
					(size 0.7 0.7)
					(thickness 0.15)
				)
				(justify left bottom)
			)
		)
		(property "Datasheet" "https://www.bourns.com/docs/product-datasheets/cr.pdf"
			(at 0 0 0)
			(layer "F.Fab")
			(hide yes)
			(effects
				(font
					(size 1.27 1.27)
					(thickness 0.15)
				)
			)
		)
		(property "Author" "Antmicro"
			(at 0 0 0)
			(layer "F.Fab")
			(hide yes)
			(effects
				(font
					(size 1 1)
					(thickness 0.15)
				)
			)
		)
		(property "License" "Apache-2.0"
			(at 0 0 0)
			(layer "F.Fab")
			(hide yes)
			(effects
				(font
					(size 1 1)
					(thickness 0.15)
				)
			)
		)
		(property "MPN" "CR0402-FX-1002GLF"
			(at 0 0 0)
			(layer "F.Fab")
			(hide yes)
			(effects
				(font
					(size 1 1)
					(thickness 0.15)
				)
			)
		)
		(property "Manufacturer" "Bourns"
			(at 0 0 0)
			(layer "F.Fab")
			(hide yes)
			(effects
				(font
					(size 1 1)
					(thickness 0.15)
				)
			)
		)
		(property "Public" "False"
			(at 0 0 0)
			(layer "F.Fab")
			(hide yes)
			(effects
				(font
					(size 1 1)
					(thickness 0.15)
				)
			)
		)
		(property "Tolerance" "1%"
			(at 0 0 0)
			(layer "F.Fab")
			(hide yes)
			(effects
				(font
					(size 1 1)
					(thickness 0.15)
				)
			)
		)
		(property "Val" "10k"
			(at 0 0 0)
			(layer "F.Fab")
			(hide yes)
			(effects
				(font
					(size 1 1)
					(thickness 0.15)
				)
			)
		)
		(sheetname "KR to SFI #1")
		(sheetfile "kr_sfi.kicad_sch")
		(attr smd)
		(fp_rect
			(start -0.925 -0.47)
			(end 0.925 0.47)
			(stroke
				(width 0.05)
				(type default)
			)
			(fill no)
			(layer "F.CrtYd")
		)
		(fp_rect
			(start -0.5 -0.25)
			(end 0.5 0.25)
			(stroke
				(width 0.15)
				(type solid)
			)
			(fill no)
			(layer "F.Fab")
		)
		(pad "1" smd roundrect
			(at -0.48 0)
			(size 0.59 0.64)
			(layers "F.Cu" "F.Mask" "F.Paste")
			(roundrect_rratio 0.25)
			(net 1 "GND")
			(pintype "passive")
			(teardrops
				(best_length_ratio 0.2)
				(max_length 1)
				(best_width_ratio 0.9)
				(max_width 2)
				(curved_edges yes)
				(filter_ratio 0.9)
				(enabled yes)
				(allow_two_segments yes)
				(prefer_zone_connections yes)
			)
		)
		(pad "2" smd roundrect
			(at 0.48 0)
			(size 0.59 0.64)
			(layers "F.Cu" "F.Mask" "F.Paste")
			(roundrect_rratio 0.25)
			(net 661 "Net-(U43C-PRTAD4)")
			(pintype "passive")
			(teardrops
				(best_length_ratio 0.2)
				(max_length 1)
				(best_width_ratio 0.9)
				(max_width 2)
				(curved_edges yes)
				(filter_ratio 0.9)
				(enabled yes)
				(allow_two_segments yes)
				(prefer_zone_connections yes)
			)
		)
	)
	(footprint "antmicro-footprints:QFN-24-1EP_4x4mm_P0.5_EP2.1x2.1mm"
		(layer "F.Cu")
		(at 130.65 85.56)
		(property "Reference" "U41"
			(at 0.2 3.45 0)
			(layer "F.SilkS")
			(effects
				(font
					(size 0.7 0.7)
					(thickness 0.15)
				)
				(justify left bottom)
			)
		)
		(property "Value" "PCA9539AHF"
			(at 0 3.4 0)
			(layer "F.Fab")
			(effects
				(font
					(size 0.7 0.7)
					(thickness 0.15)
				)
				(justify left bottom)
			)
		)
		(property "Datasheet" "https://www.nxp.com/docs/en/data-sheet/PCA9539A.pdf"
			(at 0 0 0)
			(layer "F.Fab")
			(hide yes)
			(effects
				(font
					(size 1.27 1.27)
					(thickness 0.15)
				)
			)
		)
		(property "Author" "Antmicro"
			(at 0 0 0)
			(layer "F.Fab")
			(hide yes)
			(effects
				(font
					(size 1 1)
					(thickness 0.15)
				)
			)
		)
		(property "License" "Apache-2.0"
			(at 0 0 0)
			(layer "F.Fab")
			(hide yes)
			(effects
				(font
					(size 1 1)
					(thickness 0.15)
				)
			)
		)
		(property "MPN" "PCA9539AHF,128"
			(at 0 0 0)
			(layer "F.Fab")
			(hide yes)
			(effects
				(font
					(size 1 1)
					(thickness 0.15)
				)
			)
		)
		(property "Manufacturer" "NXP"
			(at 0 0 0)
			(layer "F.Fab")
			(hide yes)
			(effects
				(font
					(size 1 1)
					(thickness 0.15)
				)
			)
		)
		(property ki_fp_filters "VFQFN-16-1EP_3x3mm")
		(sheetname "GPIO expander")
		(sheetfile "gpio_exp.kicad_sch")
		(attr smd)
		(fp_line
			(start -2.11 -1.636)
			(end -2.11 -2.11)
			(stroke
				(width 0.15)
				(type solid)
			)
			(layer "F.SilkS")
		)
		(fp_line
			(start -2.11 2.108)
			(end -2.11 1.634)
			(stroke
				(width 0.15)
				(type solid)
			)
			(layer "F.SilkS")
		)
		(fp_line
			(start -1.635 -2.11)
			(end -2.11 -2.11)
			(stroke
				(width 0.15)
				(type solid)
			)
			(layer "F.SilkS")
		)
		(fp_line
			(start -1.635 2.108)
			(end -2.11 2.108)
			(stroke
				(width 0.15)
				(type solid)
			)
			(layer "F.SilkS")
		)
		(fp_line
			(start 1.634 -2.11)
			(end 2.108 -2.11)
			(stroke
				(width 0.15)
				(type solid)
			)
			(layer "F.SilkS")
		)
		(fp_line
			(start 1.634 2.108)
			(end 2.108 2.108)
			(stroke
				(width 0.15)
				(type solid)
			)
			(layer "F.SilkS")
		)
		(fp_line
			(start 2.108 -2.11)
			(end 2.108 -1.635)
			(stroke
				(width 0.15)
				(type solid)
			)
			(layer "F.SilkS")
		)
		(fp_line
			(start 2.108 2.108)
			(end 2.108 1.634)
			(stroke
				(width 0.15)
				(type solid)
			)
			(layer "F.SilkS")
		)
		(fp_circle
			(center -2.3 -2.3)
			(end -2.25 -2.3)
			(stroke
				(width 0.15)
				(type solid)
			)
			(fill yes)
			(layer "F.SilkS")
		)
		(fp_rect
			(start -2.503 -2.503)
			(end 2.5 2.5)
			(stroke
				(width 0.05)
				(type solid)
			)
			(fill no)
			(layer "F.CrtYd")
		)
		(fp_line
			(start -2 -1)
			(end -1 -2)
			(stroke
				(width 0.15)
				(type solid)
			)
			(layer "F.Fab")
		)
		(fp_line
			(start -2 1.999)
			(end -2 -1)
			(stroke
				(width 0.15)
				(type solid)
			)
			(layer "F.Fab")
		)
		(fp_line
			(start -1 -2)
			(end 1.999 -2)
			(stroke
				(width 0.15)
				(type solid)
			)
			(layer "F.Fab")
		)
		(fp_line
			(start 1.999 -2)
			(end 1.999 1.999)
			(stroke
				(width 0.15)
				(type solid)
			)
			(layer "F.Fab")
		)
		(fp_line
			(start 1.999 1.999)
			(end -2 1.999)
			(stroke
				(width 0.15)
				(type solid)
			)
			(layer "F.Fab")
		)
		(pad "" smd roundrect
			(at -0.5 -0.5)
			(size 0.8 0.8)
			(layers "F.Paste")
			(roundrect_rratio 0.238095)
			(teardrops
				(best_length_ratio 0.2)
				(max_length 1)
				(best_width_ratio 0.9)
				(max_width 2)
				(curved_edges yes)
				(filter_ratio 0.9)
				(enabled yes)
				(allow_two_segments yes)
				(prefer_zone_connections yes)
			)
		)
		(pad "" smd roundrect
			(at -0.5 0.5)
			(size 0.8 0.8)
			(layers "F.Paste")
			(roundrect_rratio 0.238095)
			(teardrops
				(best_length_ratio 0.2)
				(max_length 1)
				(best_width_ratio 0.9)
				(max_width 2)
				(curved_edges yes)
				(filter_ratio 0.9)
				(enabled yes)
				(allow_two_segments yes)
				(prefer_zone_connections yes)
			)
		)
		(pad "" smd roundrect
			(at 0.5 -0.5)
			(size 0.8 0.8)
			(layers "F.Paste")
			(roundrect_rratio 0.238095)
			(teardrops
				(best_length_ratio 0.2)
				(max_length 1)
				(best_width_ratio 0.9)
				(max_width 2)
				(curved_edges yes)
				(filter_ratio 0.9)
				(enabled yes)
				(allow_two_segments yes)
				(prefer_zone_connections yes)
			)
		)
		(pad "" smd roundrect
			(at 0.5 0.5)
			(size 0.8 0.8)
			(layers "F.Paste")
			(roundrect_rratio 0.238095)
			(teardrops
				(best_length_ratio 0.2)
				(max_length 1)
				(best_width_ratio 0.9)
				(max_width 2)
				(curved_edges yes)
				(filter_ratio 0.9)
				(enabled yes)
				(allow_two_segments yes)
				(prefer_zone_connections yes)
			)
		)
		(pad "1" smd roundrect
			(at -1.938 -1.25)
			(size 0.825 0.25)
			(layers "F.Cu" "F.Mask" "F.Paste")
			(roundrect_rratio 0.25)
			(net 639 "Net-(U41-IO0_0)")
			(pinfunction "IO0_0")
			(pintype "bidirectional")
			(teardrops
				(best_length_ratio 0.2)
				(max_length 1)
				(best_width_ratio 0.9)
				(max_width 2)
				(curved_edges yes)
				(filter_ratio 0.9)
				(enabled yes)
				(allow_two_segments yes)
				(prefer_zone_connections yes)
			)
		)
		(pad "2" smd roundrect
			(at -1.938 -0.75)
			(size 0.825 0.25)
			(layers "F.Cu" "F.Mask" "F.Paste")
			(roundrect_rratio 0.25)
			(net 640 "Net-(U41-IO0_1)")
			(pinfunction "IO0_1")
			(pintype "bidirectional")
			(teardrops
				(best_length_ratio 0.2)
				(max_length 1)
				(best_width_ratio 0.9)
				(max_width 2)
				(curved_edges yes)
				(filter_ratio 0.9)
				(enabled yes)
				(allow_two_segments yes)
				(prefer_zone_connections yes)
			)
		)
		(pad "3" smd roundrect
			(at -1.938 -0.25)
			(size 0.825 0.25)
			(layers "F.Cu" "F.Mask" "F.Paste")
			(roundrect_rratio 0.25)
			(net 641 "Net-(U41-IO0_2)")
			(pinfunction "IO0_2")
			(pintype "bidirectional")
			(teardrops
				(best_length_ratio 0.2)
				(max_length 1)
				(best_width_ratio 0.9)
				(max_width 2)
				(curved_edges yes)
				(filter_ratio 0.9)
				(enabled yes)
				(allow_two_segments yes)
				(prefer_zone_connections yes)
			)
		)
		(pad "4" smd roundrect
			(at -1.938 0.248)
			(size 0.825 0.25)
			(layers "F.Cu" "F.Mask" "F.Paste")
			(roundrect_rratio 0.25)
			(net 642 "Net-(U41-IO0_3)")
			(pinfunction "IO0_3")
			(pintype "bidirectional")
			(teardrops
				(best_length_ratio 0.2)
				(max_length 1)
				(best_width_ratio 0.9)
				(max_width 2)
				(curved_edges yes)
				(filter_ratio 0.9)
				(enabled yes)
				(allow_two_segments yes)
				(prefer_zone_connections yes)
			)
		)
		(pad "5" smd roundrect
			(at -1.938 0.748)
			(size 0.825 0.25)
			(layers "F.Cu" "F.Mask" "F.Paste")
			(roundrect_rratio 0.25)
			(net 643 "Net-(U41-IO0_4)")
			(pinfunction "IO0_4")
			(pintype "bidirectional")
			(teardrops
				(best_length_ratio 0.2)
				(max_length 1)
				(best_width_ratio 0.9)
				(max_width 2)
				(curved_edges yes)
				(filter_ratio 0.9)
				(enabled yes)
				(allow_two_segments yes)
				(prefer_zone_connections yes)
			)
		)
		(pad "6" smd roundrect
			(at -1.938 1.249)
			(size 0.825 0.25)
			(layers "F.Cu" "F.Mask" "F.Paste")
			(roundrect_rratio 0.25)
			(net 644 "Net-(U41-IO0_5)")
			(pinfunction "IO0_5")
			(pintype "bidirectional")
			(teardrops
				(best_length_ratio 0.2)
				(max_length 1)
				(best_width_ratio 0.9)
				(max_width 2)
				(curved_edges yes)
				(filter_ratio 0.9)
				(enabled yes)
				(allow_two_segments yes)
				(prefer_zone_connections yes)
			)
		)
		(pad "7" smd roundrect
			(at -1.25 1.937)
			(size 0.25 0.825)
			(layers "F.Cu" "F.Mask" "F.Paste")
			(roundrect_rratio 0.25)
			(net 645 "Net-(U41-IO0_6)")
			(pinfunction "IO0_6")
			(pintype "bidirectional")
			(teardrops
				(best_length_ratio 0.2)
				(max_length 1)
				(best_width_ratio 0.9)
				(max_width 2)
				(curved_edges yes)
				(filter_ratio 0.9)
				(enabled yes)
				(allow_two_segments yes)
				(prefer_zone_connections yes)
			)
		)
		(pad "8" smd roundrect
			(at -0.75 1.937)
			(size 0.25 0.825)
			(layers "F.Cu" "F.Mask" "F.Paste")
			(roundrect_rratio 0.25)
			(net 646 "Net-(U41-IO0_7)")
			(pinfunction "IO0_7")
			(pintype "bidirectional")
			(teardrops
				(best_length_ratio 0.2)
				(max_length 1)
				(best_width_ratio 0.9)
				(max_width 2)
				(curved_edges yes)
				(filter_ratio 0.9)
				(enabled yes)
				(allow_two_segments yes)
				(prefer_zone_connections yes)
			)
		)
		(pad "9" smd roundrect
			(at -0.25 1.937)
			(size 0.25 0.825)
			(layers "F.Cu" "F.Mask" "F.Paste")
			(roundrect_rratio 0.25)
			(net 1 "GND")
			(pinfunction "GND")
			(pintype "power_in")
			(teardrops
				(best_length_ratio 0.2)
				(max_length 1)
				(best_width_ratio 0.9)
				(max_width 2)
				(curved_edges yes)
				(filter_ratio 0.9)
				(enabled no)
				(allow_two_segments yes)
				(prefer_zone_connections yes)
			)
		)
		(pad "10" smd roundrect
			(at 0.248 1.937)
			(size 0.25 0.825)
			(layers "F.Cu" "F.Mask" "F.Paste")
			(roundrect_rratio 0.25)
			(net 792 "unconnected-(U41-IO1_0-Pad10)")
			(pinfunction "IO1_0")
			(pintype "bidirectional+no_connect")
			(teardrops
				(best_length_ratio 0.2)
				(max_length 1)
				(best_width_ratio 0.9)
				(max_width 2)
				(curved_edges yes)
				(filter_ratio 0.9)
				(enabled yes)
				(allow_two_segments yes)
				(prefer_zone_connections yes)
			)
		)
		(pad "11" smd roundrect
			(at 0.748 1.937)
			(size 0.25 0.825)
			(layers "F.Cu" "F.Mask" "F.Paste")
			(roundrect_rratio 0.25)
			(net 793 "unconnected-(U41-IO1_1-Pad11)")
			(pinfunction "IO1_1")
			(pintype "bidirectional+no_connect")
			(teardrops
				(best_length_ratio 0.2)
				(max_length 1)
				(best_width_ratio 0.9)
				(max_width 2)
				(curved_edges yes)
				(filter_ratio 0.9)
				(enabled yes)
				(allow_two_segments yes)
				(prefer_zone_connections yes)
			)
		)
		(pad "12" smd roundrect
			(at 1.249 1.937)
			(size 0.25 0.825)
			(layers "F.Cu" "F.Mask" "F.Paste")
			(roundrect_rratio 0.25)
			(net 794 "unconnected-(U41-IO1_2-Pad12)")
			(pinfunction "IO1_2")
			(pintype "bidirectional+no_connect")
			(teardrops
				(best_length_ratio 0.2)
				(max_length 1)
				(best_width_ratio 0.9)
				(max_width 2)
				(curved_edges yes)
				(filter_ratio 0.9)
				(enabled yes)
				(allow_two_segments yes)
				(prefer_zone_connections yes)
			)
		)
		(pad "13" smd roundrect
			(at 1.937 1.249)
			(size 0.825 0.25)
			(layers "F.Cu" "F.Mask" "F.Paste")
			(roundrect_rratio 0.25)
			(net 795 "unconnected-(U41-IO1_3-Pad13)")
			(pinfunction "IO1_3")
			(pintype "bidirectional+no_connect")
			(teardrops
				(best_length_ratio 0.2)
				(max_length 1)
				(best_width_ratio 0.9)
				(max_width 2)
				(curved_edges yes)
				(filter_ratio 0.9)
				(enabled yes)
				(allow_two_segments yes)
				(prefer_zone_connections yes)
			)
		)
		(pad "14" smd roundrect
			(at 1.937 0.748)
			(size 0.825 0.25)
			(layers "F.Cu" "F.Mask" "F.Paste")
			(roundrect_rratio 0.25)
			(net 796 "unconnected-(U41-IO1_4-Pad14)")
			(pinfunction "IO1_4")
			(pintype "bidirectional+no_connect")
			(teardrops
				(best_length_ratio 0.2)
				(max_length 1)
				(best_width_ratio 0.9)
				(max_width 2)
				(curved_edges yes)
				(filter_ratio 0.9)
				(enabled yes)
				(allow_two_segments yes)
				(prefer_zone_connections yes)
			)
		)
		(pad "15" smd roundrect
			(at 1.937 0.248)
			(size 0.825 0.25)
			(layers "F.Cu" "F.Mask" "F.Paste")
			(roundrect_rratio 0.25)
			(net 797 "unconnected-(U41-IO1_5-Pad15)")
			(pinfunction "IO1_5")
			(pintype "bidirectional+no_connect")
			(teardrops
				(best_length_ratio 0.2)
				(max_length 1)
				(best_width_ratio 0.9)
				(max_width 2)
				(curved_edges yes)
				(filter_ratio 0.9)
				(enabled yes)
				(allow_two_segments yes)
				(prefer_zone_connections yes)
			)
		)
		(pad "16" smd roundrect
			(at 1.937 -0.25)
			(size 0.825 0.25)
			(layers "F.Cu" "F.Mask" "F.Paste")
			(roundrect_rratio 0.25)
			(net 798 "unconnected-(U41-IO1_6-Pad16)")
			(pinfunction "IO1_6")
			(pintype "bidirectional+no_connect")
			(teardrops
				(best_length_ratio 0.2)
				(max_length 1)
				(best_width_ratio 0.9)
				(max_width 2)
				(curved_edges yes)
				(filter_ratio 0.9)
				(enabled yes)
				(allow_two_segments yes)
				(prefer_zone_connections yes)
			)
		)
		(pad "17" smd roundrect
			(at 1.937 -0.75)
			(size 0.825 0.25)
			(layers "F.Cu" "F.Mask" "F.Paste")
			(roundrect_rratio 0.25)
			(net 799 "unconnected-(U41-IO1_7-Pad17)")
			(pinfunction "IO1_7")
			(pintype "bidirectional+no_connect")
			(teardrops
				(best_length_ratio 0.2)
				(max_length 1)
				(best_width_ratio 0.9)
				(max_width 2)
				(curved_edges yes)
				(filter_ratio 0.9)
				(enabled yes)
				(allow_two_segments yes)
				(prefer_zone_connections yes)
			)
		)
		(pad "18" smd roundrect
			(at 1.937 -1.25)
			(size 0.825 0.25)
			(layers "F.Cu" "F.Mask" "F.Paste")
			(roundrect_rratio 0.25)
			(net 633 "Net-(U41-A0)")
			(pinfunction "A0")
			(pintype "input")
			(teardrops
				(best_length_ratio 0.2)
				(max_length 1)
				(best_width_ratio 0.9)
				(max_width 2)
				(curved_edges yes)
				(filter_ratio 0.9)
				(enabled yes)
				(allow_two_segments yes)
				(prefer_zone_connections yes)
			)
		)
		(pad "19" smd roundrect
			(at 1.249 -1.938)
			(size 0.25 0.825)
			(layers "F.Cu" "F.Mask" "F.Paste")
			(roundrect_rratio 0.25)
			(net 635 "Net-(U41-SCL)")
			(pinfunction "SCL")
			(pintype "input")
			(teardrops
				(best_length_ratio 0.2)
				(max_length 1)
				(best_width_ratio 0.9)
				(max_width 2)
				(curved_edges yes)
				(filter_ratio 0.9)
				(enabled yes)
				(allow_two_segments yes)
				(prefer_zone_connections yes)
			)
		)
		(pad "20" smd roundrect
			(at 0.748 -1.938)
			(size 0.25 0.825)
			(layers "F.Cu" "F.Mask" "F.Paste")
			(roundrect_rratio 0.25)
			(net 634 "Net-(U41-SDA)")
			(pinfunction "SDA")
			(pintype "bidirectional")
			(teardrops
				(best_length_ratio 0.2)
				(max_length 1)
				(best_width_ratio 0.9)
				(max_width 2)
				(curved_edges yes)
				(filter_ratio 0.9)
				(enabled yes)
				(allow_two_segments yes)
				(prefer_zone_connections yes)
			)
		)
		(pad "21" smd roundrect
			(at 0.248 -1.938)
			(size 0.25 0.825)
			(layers "F.Cu" "F.Mask" "F.Paste")
			(roundrect_rratio 0.25)
			(net 2 "+3V3")
			(pinfunction "VDD")
			(pintype "power_in")
			(teardrops
				(best_length_ratio 0.2)
				(max_length 1)
				(best_width_ratio 0.9)
				(max_width 2)
				(curved_edges yes)
				(filter_ratio 0.9)
				(enabled yes)
				(allow_two_segments yes)
				(prefer_zone_connections yes)
			)
		)
		(pad "22" smd roundrect
			(at -0.25 -1.938)
			(size 0.25 0.825)
			(layers "F.Cu" "F.Mask" "F.Paste")
			(roundrect_rratio 0.25)
			(net 636 "Net-(U41-~{INT})")
			(pinfunction "~{INT}")
			(pintype "output")
			(teardrops
				(best_length_ratio 0.2)
				(max_length 1)
				(best_width_ratio 0.9)
				(max_width 2)
				(curved_edges yes)
				(filter_ratio 0.9)
				(enabled yes)
				(allow_two_segments yes)
				(prefer_zone_connections yes)
			)
		)
		(pad "23" smd roundrect
			(at -0.75 -1.938)
			(size 0.25 0.825)
			(layers "F.Cu" "F.Mask" "F.Paste")
			(roundrect_rratio 0.25)
			(net 638 "Net-(U41-A1)")
			(pinfunction "A1")
			(pintype "input")
			(teardrops
				(best_length_ratio 0.2)
				(max_length 1)
				(best_width_ratio 0.9)
				(max_width 2)
				(curved_edges yes)
				(filter_ratio 0.9)
				(enabled yes)
				(allow_two_segments yes)
				(prefer_zone_connections yes)
			)
		)
		(pad "24" smd roundrect
			(at -1.25 -1.938)
			(size 0.25 0.825)
			(layers "F.Cu" "F.Mask" "F.Paste")
			(roundrect_rratio 0.25)
			(net 637 "Net-(U41-~{RESET})")
			(pinfunction "~{RESET}")
			(pintype "input")
			(teardrops
				(best_length_ratio 0.2)
				(max_length 1)
				(best_width_ratio 0.9)
				(max_width 2)
				(curved_edges yes)
				(filter_ratio 0.9)
				(enabled yes)
				(allow_two_segments yes)
				(prefer_zone_connections yes)
			)
		)
		(pad "25" smd rect
			(at 0 0)
			(size 2.1 2.1)
			(layers "F.Cu" "F.Mask")
			(net 1 "GND")
			(pinfunction "GND")
			(pintype "passive")
			(teardrops
				(best_length_ratio 0.2)
				(max_length 1)
				(best_width_ratio 0.9)
				(max_width 2)
				(curved_edges yes)
				(filter_ratio 0.9)
				(enabled no)
				(allow_two_segments yes)
				(prefer_zone_connections yes)
			)
		)
	)
	(footprint "antmicro-footprints:C_0402_1005Metric"
		(layer "F.Cu")
		(at 314.114999 106.129999 -90)
		(descr "Capacitor SMD 0402")
		(tags "capacitor SMD 0402")
		(property "Reference" "C48"
			(at 1.730001 -1.735001 90)
			(layer "F.SilkS")
			(effects
				(font
					(size 0.7 0.7)
					(thickness 0.15)
				)
				(justify right bottom)
			)
		)
		(property "Value" "C_100n_0402"
			(at -1.022927 2.155213 90)
			(layer "F.Fab")
			(effects
				(font
					(size 0.7 0.7)
					(thickness 0.15)
				)
				(justify right bottom)
			)
		)
		(property "Datasheet" "https://www.murata.com/products/productdetail?partno=GRM155R61H104KE14%23"
			(at 0 0 270)
			(layer "F.Fab")
			(hide yes)
			(effects
				(font
					(size 1.27 1.27)
					(thickness 0.15)
				)
			)
		)
		(property "Author" "Antmicro"
			(at 207.985 420.244998 0)
			(layer "F.Fab")
			(hide yes)
			(effects
				(font
					(size 1 1)
					(thickness 0.15)
				)
			)
		)
		(property "Dielectric" "X5R"
			(at 207.985 420.244998 0)
			(layer "F.Fab")
			(hide yes)
			(effects
				(font
					(size 1 1)
					(thickness 0.15)
				)
			)
		)
		(property "License" "Apache-2.0"
			(at 207.985 420.244998 0)
			(layer "F.Fab")
			(hide yes)
			(effects
				(font
					(size 1 1)
					(thickness 0.15)
				)
			)
		)
		(property "MPN" "GRM155R61H104KE14D"
			(at 207.985 420.244998 0)
			(layer "F.Fab")
			(hide yes)
			(effects
				(font
					(size 1 1)
					(thickness 0.15)
				)
			)
		)
		(property "Manufacturer" "Murata"
			(at 207.985 420.244998 0)
			(layer "F.Fab")
			(hide yes)
			(effects
				(font
					(size 1 1)
					(thickness 0.15)
				)
			)
		)
		(property "Public" "False"
			(at 207.985 420.244998 0)
			(layer "F.Fab")
			(hide yes)
			(effects
				(font
					(size 1 1)
					(thickness 0.15)
				)
			)
		)
		(property "Val" "100n"
			(at 207.985 420.244998 0)
			(layer "F.Fab")
			(hide yes)
			(effects
				(font
					(size 1 1)
					(thickness 0.15)
				)
			)
		)
		(property "Voltage" "50V"
			(at 207.985 420.244998 0)
			(layer "F.Fab")
			(hide yes)
			(effects
				(font
					(size 1 1)
					(thickness 0.15)
				)
			)
		)
		(sheetname "Power")
		(sheetfile "power.kicad_sch")
		(attr smd)
		(fp_rect
			(start -0.925 -0.47)
			(end 0.925 0.47)
			(stroke
				(width 0.05)
				(type default)
			)
			(fill no)
			(layer "F.CrtYd")
		)
		(fp_line
			(start -0.494 0.248)
			(end -0.494 -0.25)
			(stroke
				(width 0.15)
				(type solid)
			)
			(layer "F.Fab")
		)
		(fp_line
			(start 0.504 0.248)
			(end -0.494 0.248)
			(stroke
				(width 0.15)
				(type solid)
			)
			(layer "F.Fab")
		)
		(fp_line
			(start -0.494 -0.25)
			(end 0.504 -0.25)
			(stroke
				(width 0.15)
				(type solid)
			)
			(layer "F.Fab")
		)
		(fp_line
			(start 0.504 -0.25)
			(end 0.504 0.248)
			(stroke
				(width 0.15)
				(type solid)
			)
			(layer "F.Fab")
		)
		(pad "1" smd roundrect
			(at -0.48 0 270)
			(size 0.59 0.64)
			(layers "F.Cu" "F.Mask" "F.Paste")
			(roundrect_rratio 0.25)
			(net 68 "Net-(U19-BST)")
			(pintype "passive")
			(teardrops
				(best_length_ratio 0.2)
				(max_length 1)
				(best_width_ratio 0.9)
				(max_width 2)
				(curved_edges yes)
				(filter_ratio 0.9)
				(enabled yes)
				(allow_two_segments yes)
				(prefer_zone_connections yes)
			)
		)
		(pad "2" smd roundrect
			(at 0.48 0 270)
			(size 0.59 0.64)
			(layers "F.Cu" "F.Mask" "F.Paste")
			(roundrect_rratio 0.25)
			(net 69 "Net-(C48-Pad2)")
			(pintype "passive")
			(teardrops
				(best_length_ratio 0.2)
				(max_length 1)
				(best_width_ratio 0.9)
				(max_width 2)
				(curved_edges yes)
				(filter_ratio 0.9)
				(enabled yes)
				(allow_two_segments yes)
				(prefer_zone_connections yes)
			)
		)
	)
	(footprint "antmicro-footprints:R_0402_1005Metric"
		(layer "F.Cu")
		(at 216.935 136.94 90)
		(descr "Resistor SMD 0402")
		(tags "resistor SMD 0402")
		(property "Reference" "R315"
			(at -3.72 0.465 90)
			(layer "F.SilkS")
			(effects
				(font
					(size 0.7 0.7)
					(thickness 0.15)
				)
				(justify left bottom)
			)
		)
		(property "Value" "R_0R_0402"
			(at -1.011843 1.772047 90)
			(layer "F.Fab")
			(effects
				(font
					(size 0.7 0.7)
					(thickness 0.15)
				)
				(justify left bottom)
			)
		)
		(property "Datasheet" "https://industrial.panasonic.com/cdbs/www-data/pdf/RDA0000/AOA0000C301.pdf"
			(at 0 0 90)
			(layer "F.Fab")
			(hide yes)
			(effects
				(font
					(size 1.27 1.27)
					(thickness 0.15)
				)
			)
		)
		(property "Author" "Antmicro"
			(at 353.875 -79.995 0)
			(layer "F.Fab")
			(hide yes)
			(effects
				(font
					(size 1 1)
					(thickness 0.15)
				)
			)
		)
		(property "Current" "1A"
			(at 353.875 -79.995 0)
			(layer "F.Fab")
			(hide yes)
			(effects
				(font
					(size 1 1)
					(thickness 0.15)
				)
			)
		)
		(property "License" "Apache-2.0"
			(at 353.875 -79.995 0)
			(layer "F.Fab")
			(hide yes)
			(effects
				(font
					(size 1 1)
					(thickness 0.15)
				)
			)
		)
		(property "MPN" "ERJ2GE0R00X"
			(at 353.875 -79.995 0)
			(layer "F.Fab")
			(hide yes)
			(effects
				(font
					(size 1 1)
					(thickness 0.15)
				)
			)
		)
		(property "Manufacturer" "Panasonic"
			(at 353.875 -79.995 0)
			(layer "F.Fab")
			(hide yes)
			(effects
				(font
					(size 1 1)
					(thickness 0.15)
				)
			)
		)
		(property "Public" "False"
			(at 353.875 -79.995 0)
			(layer "F.Fab")
			(hide yes)
			(effects
				(font
					(size 1 1)
					(thickness 0.15)
				)
			)
		)
		(property "Tolerance" ""
			(at 353.875 -79.995 0)
			(layer "F.Fab")
			(hide yes)
			(effects
				(font
					(size 1 1)
					(thickness 0.15)
				)
			)
		)
		(property "Val" "0R"
			(at 353.875 -79.995 0)
			(layer "F.Fab")
			(hide yes)
			(effects
				(font
					(size 1 1)
					(thickness 0.15)
				)
			)
		)
		(sheetname "PCIe misc")
		(sheetfile "pcie_misc.kicad_sch")
		(attr smd dnp)
		(fp_rect
			(start -0.925 -0.47)
			(end 0.925 0.47)
			(stroke
				(width 0.05)
				(type default)
			)
			(fill no)
			(layer "F.CrtYd")
		)
		(fp_rect
			(start -0.5 -0.25)
			(end 0.5 0.25)
			(stroke
				(width 0.15)
				(type solid)
			)
			(fill no)
			(layer "F.Fab")
		)
		(pad "1" smd roundrect
			(at -0.48 0 90)
			(size 0.59 0.64)
			(layers "F.Cu" "F.Mask" "F.Paste")
			(roundrect_rratio 0.25)
			(net 24 "/M.2 key E/~{CLKREQ}")
			(pintype "passive")
			(teardrops
				(best_length_ratio 0.2)
				(max_length 1)
				(best_width_ratio 0.9)
				(max_width 2)
				(curved_edges yes)
				(filter_ratio 0.9)
				(enabled yes)
				(allow_two_segments yes)
				(prefer_zone_connections yes)
			)
		)
		(pad "2" smd roundrect
			(at 0.48 0 90)
			(size 0.59 0.64)
			(layers "F.Cu" "F.Mask" "F.Paste")
			(roundrect_rratio 0.25)
			(net 604 "Net-(U37-~{OE2})")
			(pintype "passive")
			(teardrops
				(best_length_ratio 0.2)
				(max_length 1)
				(best_width_ratio 0.9)
				(max_width 2)
				(curved_edges yes)
				(filter_ratio 0.9)
				(enabled yes)
				(allow_two_segments yes)
				(prefer_zone_connections yes)
			)
		)
	)
	(footprint "antmicro-footprints:SOT-23-5"
		(layer "F.Cu")
		(at 303.19 130.09)
		(property "Reference" "U20"
			(at -1.09 2.72 0)
			(layer "F.SilkS")
			(effects
				(font
					(size 0.7 0.7)
					(thickness 0.15)
				)
				(justify left bottom)
			)
		)
		(property "Value" "TPS3840PL30DBVR"
			(at 0.002 2.799 0)
			(layer "F.Fab")
			(effects
				(font
					(size 0.7 0.7)
					(thickness 0.15)
				)
				(justify left bottom)
			)
		)
		(property "Datasheet" "https://www.ti.com/lit/ds/symlink/tps3840.pdf?HQS=dis-mous-null-mousermode-dsf-pf-null-wwe&DCM=yes&ref_url=https%3A%2F%2Fwww.mouser.com%2F&distId=26"
			(at 0 0 0)
			(layer "F.Fab")
			(hide yes)
			(effects
				(font
					(size 1.27 1.27)
					(thickness 0.15)
				)
			)
		)
		(property "Author" "Antmicro"
			(at 0 0 0)
			(layer "F.Fab")
			(hide yes)
			(effects
				(font
					(size 1 1)
					(thickness 0.15)
				)
			)
		)
		(property "License" "Apache-2.0"
			(at 0 0 0)
			(layer "F.Fab")
			(hide yes)
			(effects
				(font
					(size 1 1)
					(thickness 0.15)
				)
			)
		)
		(property "MPN" "TPS3840PL30DBVR"
			(at 0 0 0)
			(layer "F.Fab")
			(hide yes)
			(effects
				(font
					(size 1 1)
					(thickness 0.15)
				)
			)
		)
		(property "Manufacturer" "Texas Instruments"
			(at 0 0 0)
			(layer "F.Fab")
			(hide yes)
			(effects
				(font
					(size 1 1)
					(thickness 0.15)
				)
			)
		)
		(property ki_fp_filters "DBV0005A_N DBV0005A_M DBV0005A_L")
		(sheetname "Power")
		(sheetfile "power.kicad_sch")
		(attr smd)
		(fp_line
			(start -0.85 1.6)
			(end -0.85 1.301)
			(stroke
				(width 0.15)
				(type solid)
			)
			(layer "F.SilkS")
		)
		(fp_line
			(start -0.8 -1.6)
			(end -0.8 -1.3)
			(stroke
				(width 0.15)
				(type solid)
			)
			(layer "F.SilkS")
		)
		(fp_line
			(start -0.8 -1.6)
			(end -0.5 -1.6)
			(stroke
				(width 0.15)
				(type solid)
			)
			(layer "F.SilkS")
		)
		(fp_line
			(start -0.55 1.6)
			(end -0.85 1.6)
			(stroke
				(width 0.15)
				(type solid)
			)
			(layer "F.SilkS")
		)
		(fp_line
			(start 0.8 -1.6)
			(end 0.5 -1.6)
			(stroke
				(width 0.15)
				(type solid)
			)
			(layer "F.SilkS")
		)
		(fp_line
			(start 0.8 -1.3)
			(end 0.8 -1.6)
			(stroke
				(width 0.15)
				(type solid)
			)
			(layer "F.SilkS")
		)
		(fp_line
			(start 0.8 0.55)
			(end 0.8 -0.55)
			(stroke
				(width 0.15)
				(type solid)
			)
			(layer "F.SilkS")
		)
		(fp_line
			(start 0.8 1.3)
			(end 0.8 1.599)
			(stroke
				(width 0.15)
				(type solid)
			)
			(layer "F.SilkS")
		)
		(fp_line
			(start 0.8 1.599)
			(end 0.549 1.599)
			(stroke
				(width 0.15)
				(type solid)
			)
			(layer "F.SilkS")
		)
		(fp_circle
			(center -1.25 -1.5)
			(end -1.2 -1.5)
			(stroke
				(width 0.15)
				(type solid)
			)
			(fill yes)
			(layer "F.SilkS")
		)
		(fp_rect
			(start 1.9 -1.76)
			(end -1.9 1.75)
			(stroke
				(width 0.05)
				(type solid)
			)
			(fill no)
			(layer "F.CrtYd")
		)
		(fp_line
			(start -0.398 -1.526)
			(end -0.874 -1.05)
			(stroke
				(width 0.15)
				(type solid)
			)
			(layer "F.Fab")
		)
		(fp_rect
			(start 0.874 1.523)
			(end -0.873 -1.525)
			(stroke
				(width 0.15)
				(type solid)
			)
			(fill no)
			(layer "F.Fab")
		)
		(pad "1" smd rect
			(at -1.351 -0.951 270)
			(size 0.55 1)
			(layers "F.Cu" "F.Mask" "F.Paste")
			(net 365 "/Com Express 7 MGMT/PWR_OK")
			(pinfunction "~{RESET}")
			(pintype "output")
			(teardrops
				(best_length_ratio 0.2)
				(max_length 1)
				(best_width_ratio 0.9)
				(max_width 2)
				(curved_edges yes)
				(filter_ratio 0.9)
				(enabled yes)
				(allow_two_segments yes)
				(prefer_zone_connections yes)
			)
		)
		(pad "2" smd rect
			(at -1.351 0 270)
			(size 0.55 1)
			(layers "F.Cu" "F.Mask" "F.Paste")
			(net 73 "+3V3_AON")
			(pinfunction "VDD")
			(pintype "power_in")
			(teardrops
				(best_length_ratio 0.2)
				(max_length 1)
				(best_width_ratio 0.9)
				(max_width 2)
				(curved_edges yes)
				(filter_ratio 0.9)
				(enabled yes)
				(allow_two_segments yes)
				(prefer_zone_connections yes)
			)
		)
		(pad "3" smd rect
			(at -1.351 0.949 270)
			(size 0.55 1)
			(layers "F.Cu" "F.Mask" "F.Paste")
			(net 1 "GND")
			(pinfunction "GND")
			(pintype "power_in")
			(teardrops
				(best_length_ratio 0.2)
				(max_length 1)
				(best_width_ratio 0.9)
				(max_width 2)
				(curved_edges yes)
				(filter_ratio 0.9)
				(enabled yes)
				(allow_two_segments yes)
				(prefer_zone_connections yes)
			)
		)
		(pad "4" smd rect
			(at 1.35 0.949 270)
			(size 0.55 1)
			(layers "F.Cu" "F.Mask" "F.Paste")
			(net 582 "Net-(U20-~{MR})")
			(pinfunction "~{MR}")
			(pintype "input")
			(teardrops
				(best_length_ratio 0.2)
				(max_length 1)
				(best_width_ratio 0.9)
				(max_width 2)
				(curved_edges yes)
				(filter_ratio 0.9)
				(enabled yes)
				(allow_two_segments yes)
				(prefer_zone_connections yes)
			)
		)
		(pad "5" smd rect
			(at 1.35 -0.951 270)
			(size 0.55 1)
			(layers "F.Cu" "F.Mask" "F.Paste")
			(net 72 "Net-(U20-CT)")
			(pinfunction "CT")
			(pintype "passive")
			(teardrops
				(best_length_ratio 0.2)
				(max_length 1)
				(best_width_ratio 0.9)
				(max_width 2)
				(curved_edges yes)
				(filter_ratio 0.9)
				(enabled yes)
				(allow_two_segments yes)
				(prefer_zone_connections yes)
			)
		)
	)
	(footprint "antmicro-footprints:Spacer_Drill3.7mm_H2.5mm_9774025151R"
		(layer "F.Cu")
		(at 295.4495 157.485)
		(descr "Spacer M=3 h=2.5mm fi=5.1mm")
		(property "Reference" "H1"
			(at 0 -3.2 0)
			(layer "F.SilkS")
			(hide yes)
			(effects
				(font
					(size 0.7 0.7)
					(thickness 0.15)
				)
				(justify left bottom)
			)
		)
		(property "Value" "Spacer_Drill3.7mm_H2.5mm_9774025151R"
			(at 0 4 0)
			(layer "F.Fab")
			(effects
				(font
					(size 0.7 0.7)
					(thickness 0.15)
				)
				(justify left bottom)
			)
		)
		(property "Datasheet" "https://www.we-online.com/components/products/datasheet/9774025151R.pdf"
			(at 0 0 0)
			(layer "F.Fab")
			(hide yes)
			(effects
				(font
					(size 1.27 1.27)
					(thickness 0.15)
				)
			)
		)
		(property "Author" "Antmicro"
			(at 0 0 0)
			(layer "F.Fab")
			(hide yes)
			(effects
				(font
					(size 1 1)
					(thickness 0.15)
				)
			)
		)
		(property "License" "Apache-2.0"
			(at 0 0 0)
			(layer "F.Fab")
			(hide yes)
			(effects
				(font
					(size 1 1)
					(thickness 0.15)
				)
			)
		)
		(property "MPN" "9774025151R"
			(at 0 0 0)
			(layer "F.Fab")
			(hide yes)
			(effects
				(font
					(size 1 1)
					(thickness 0.15)
				)
			)
		)
		(property "Manufacturer" "Würth Elektronik"
			(at 0 0 0)
			(layer "F.Fab")
			(hide yes)
			(effects
				(font
					(size 1 1)
					(thickness 0.15)
				)
			)
		)
		(property "Public" "False"
			(at 0 0 0)
			(layer "F.Fab")
			(hide yes)
			(effects
				(font
					(size 1 1)
					(thickness 0.15)
				)
			)
		)
		(sheetname "M.2 key M #2")
		(sheetfile "m2keym.kicad_sch")
		(solder_paste_margin_ratio -1)
		(attr smd)
		(fp_circle
			(center 0 0)
			(end 3.05 0)
			(stroke
				(width 0.05)
				(type solid)
			)
			(fill no)
			(layer "F.CrtYd")
		)
		(fp_circle
			(center 0 0)
			(end 2.6 0)
			(stroke
				(width 0.15)
				(type solid)
			)
			(fill no)
			(layer "F.Fab")
		)
		(pad "" smd custom
			(at -1.7 -1.7)
			(size 0.62 0.62)
			(layers "F.Paste")
			(thermal_bridge_angle 90)
			(options
				(clearance outline)
				(anchor circle)
			)
			(primitives
				(gr_arc
					(start -0.250195 1.279127)
					(mid 0.285453 0.294389)
					(end 1.266786 -0.24747)
					(width 0.2)
				)
				(gr_arc
					(start -0.34334 1.279127)
					(mid 0.218448 0.232561)
					(end 1.259603 -0.339191)
					(width 0.2)
				)
				(gr_arc
					(start -0.436309 1.279127)
					(mid 0.152481 0.169693)
					(end 1.255279 -0.431435)
					(width 0.2)
				)
				(gr_arc
					(start -0.529126 1.279127)
					(mid 0.087542 0.105784)
					(end 1.253811 -0.524161)
					(width 0.2)
				)
				(gr_arc
					(start -0.621807 1.279127)
					(mid 0.0309 0.033527)
					(end 1.275473 -0.621136)
					(width 0.2)
				)
				(gr_arc
					(start -0.71437 1.279127)
					(mid -0.037758 -0.026651)
					(end 1.263664 -0.711602)
					(width 0.2)
				)
				(gr_arc
					(start -0.806826 1.279127)
					(mid -0.105837 -0.087395)
					(end 1.253435 -0.802342)
					(width 0.2)
				)
				(gr_arc
					(start -0.899187 1.279127)
					(mid -0.165236 -0.156885)
					(end 1.267475 -0.897258)
					(width 0.2)
				)
				(gr_arc
					(start -0.991463 1.279127)
					(mid -0.228522 -0.222449)
					(end 1.270645 -0.990112)
					(width 0.2)
				)
				(gr_arc
					(start -1.083663 1.279127)
					(mid -0.294507 -0.285313)
					(end 1.266278 -1.081674)
					(width 0.2)
				)
				(gr_line
					(start 1.279127 -0.250195)
					(end 1.279127 -1.083663)
					(width 0.2)
				)
				(gr_line
					(start -0.250195 1.279127)
					(end -1.083663 1.279127)
					(width 0.2)
				)
			)
			(teardrops
				(best_length_ratio 0.2)
				(max_length 1)
				(best_width_ratio 0.9)
				(max_width 2)
				(curved_edges yes)
				(filter_ratio 0.9)
				(enabled yes)
				(allow_two_segments yes)
				(prefer_zone_connections yes)
			)
		)
		(pad "" smd custom
			(at -1.7 1.7 90)
			(size 0.62 0.62)
			(layers "F.Paste")
			(thermal_bridge_angle 90)
			(options
				(clearance outline)
				(anchor circle)
			)
			(primitives
				(gr_arc
					(start -0.250195 1.279127)
					(mid 0.285453 0.294389)
					(end 1.266786 -0.24747)
					(width 0.2)
				)
				(gr_arc
					(start -0.34334 1.279127)
					(mid 0.218448 0.232561)
					(end 1.259603 -0.339191)
					(width 0.2)
				)
				(gr_arc
					(start -0.436309 1.279127)
					(mid 0.152481 0.169693)
					(end 1.255279 -0.431435)
					(width 0.2)
				)
				(gr_arc
					(start -0.529126 1.279127)
					(mid 0.087542 0.105784)
					(end 1.253811 -0.524161)
					(width 0.2)
				)
				(gr_arc
					(start -0.621807 1.279127)
					(mid 0.0309 0.033527)
					(end 1.275473 -0.621136)
					(width 0.2)
				)
				(gr_arc
					(start -0.71437 1.279127)
					(mid -0.037758 -0.026651)
					(end 1.263664 -0.711602)
					(width 0.2)
				)
				(gr_arc
					(start -0.806826 1.279127)
					(mid -0.105837 -0.087395)
					(end 1.253435 -0.802342)
					(width 0.2)
				)
				(gr_arc
					(start -0.899187 1.279127)
					(mid -0.165236 -0.156885)
					(end 1.267475 -0.897258)
					(width 0.2)
				)
				(gr_arc
					(start -0.991463 1.279127)
					(mid -0.228522 -0.222449)
					(end 1.270645 -0.990112)
					(width 0.2)
				)
				(gr_arc
					(start -1.083663 1.279127)
					(mid -0.294507 -0.285313)
					(end 1.266278 -1.081674)
					(width 0.2)
				)
				(gr_line
					(start 1.279127 -0.250195)
					(end 1.279127 -1.083663)
					(width 0.2)
				)
				(gr_line
					(start -0.250195 1.279127)
					(end -1.083663 1.279127)
					(width 0.2)
				)
			)
			(teardrops
				(best_length_ratio 0.2)
				(max_length 1)
				(best_width_ratio 0.9)
				(max_width 2)
				(curved_edges yes)
				(filter_ratio 0.9)
				(enabled yes)
				(allow_two_segments yes)
				(prefer_zone_connections yes)
			)
		)
		(pad "" smd custom
			(at 1.7 -1.7 270)
			(size 0.62 0.62)
			(layers "F.Paste")
			(thermal_bridge_angle 90)
			(options
				(clearance outline)
				(anchor circle)
			)
			(primitives
				(gr_arc
					(start -0.250195 1.279127)
					(mid 0.285453 0.294389)
					(end 1.266786 -0.24747)
					(width 0.2)
				)
				(gr_arc
					(start -0.34334 1.279127)
					(mid 0.218448 0.232561)
					(end 1.259603 -0.339191)
					(width 0.2)
				)
				(gr_arc
					(start -0.436309 1.279127)
					(mid 0.152481 0.169693)
					(end 1.255279 -0.431435)
					(width 0.2)
				)
				(gr_arc
					(start -0.529126 1.279127)
					(mid 0.087542 0.105784)
					(end 1.253811 -0.524161)
					(width 0.2)
				)
				(gr_arc
					(start -0.621807 1.279127)
					(mid 0.0309 0.033527)
					(end 1.275473 -0.621136)
					(width 0.2)
				)
				(gr_arc
					(start -0.71437 1.279127)
					(mid -0.037758 -0.026651)
					(end 1.263664 -0.711602)
					(width 0.2)
				)
				(gr_arc
					(start -0.806826 1.279127)
					(mid -0.105837 -0.087395)
					(end 1.253435 -0.802342)
					(width 0.2)
				)
				(gr_arc
					(start -0.899187 1.279127)
					(mid -0.165236 -0.156885)
					(end 1.267475 -0.897258)
					(width 0.2)
				)
				(gr_arc
					(start -0.991463 1.279127)
					(mid -0.228522 -0.222449)
					(end 1.270645 -0.990112)
					(width 0.2)
				)
				(gr_arc
					(start -1.083663 1.279127)
					(mid -0.294507 -0.285313)
					(end 1.266278 -1.081674)
					(width 0.2)
				)
				(gr_line
					(start 1.279127 -0.250195)
					(end 1.279127 -1.083663)
					(width 0.2)
				)
				(gr_line
					(start -0.250195 1.279127)
					(end -1.083663 1.279127)
					(width 0.2)
				)
			)
			(teardrops
				(best_length_ratio 0.2)
				(max_length 1)
				(best_width_ratio 0.9)
				(max_width 2)
				(curved_edges yes)
				(filter_ratio 0.9)
				(enabled yes)
				(allow_two_segments yes)
				(prefer_zone_connections yes)
			)
		)
		(pad "" smd custom
			(at 1.7 1.7 180)
			(size 0.62 0.62)
			(layers "F.Paste")
			(thermal_bridge_angle 90)
			(options
				(clearance outline)
				(anchor circle)
			)
			(primitives
				(gr_arc
					(start -0.250195 1.279127)
					(mid 0.285453 0.294389)
					(end 1.266786 -0.24747)
					(width 0.2)
				)
				(gr_arc
					(start -0.34334 1.279127)
					(mid 0.218448 0.232561)
					(end 1.259603 -0.339191)
					(width 0.2)
				)
				(gr_arc
					(start -0.436309 1.279127)
					(mid 0.152481 0.169693)
					(end 1.255279 -0.431435)
					(width 0.2)
				)
				(gr_arc
					(start -0.529126 1.279127)
					(mid 0.087542 0.105784)
					(end 1.253811 -0.524161)
					(width 0.2)
				)
				(gr_arc
					(start -0.621807 1.279127)
					(mid 0.0309 0.033527)
					(end 1.275473 -0.621136)
					(width 0.2)
				)
				(gr_arc
					(start -0.71437 1.279127)
					(mid -0.037758 -0.026651)
					(end 1.263664 -0.711602)
					(width 0.2)
				)
				(gr_arc
					(start -0.806826 1.279127)
					(mid -0.105837 -0.087395)
					(end 1.253435 -0.802342)
					(width 0.2)
				)
				(gr_arc
					(start -0.899187 1.279127)
					(mid -0.165236 -0.156885)
					(end 1.267475 -0.897258)
					(width 0.2)
				)
				(gr_arc
					(start -0.991463 1.279127)
					(mid -0.228522 -0.222449)
					(end 1.270645 -0.990112)
					(width 0.2)
				)
				(gr_arc
					(start -1.083663 1.279127)
					(mid -0.294507 -0.285313)
					(end 1.266278 -1.081674)
					(width 0.2)
				)
				(gr_line
					(start 1.279127 -0.250195)
					(end 1.279127 -1.083663)
					(width 0.2)
				)
				(gr_line
					(start -0.250195 1.279127)
					(end -1.083663 1.279127)
					(width 0.2)
				)
			)
			(teardrops
				(best_length_ratio 0.2)
				(max_length 1)
				(best_width_ratio 0.9)
				(max_width 2)
				(curved_edges yes)
				(filter_ratio 0.9)
				(enabled yes)
				(allow_two_segments yes)
				(prefer_zone_connections yes)
			)
		)
		(pad "1" thru_hole circle
			(at 0 0)
			(size 6 6)
			(drill 3.7)
			(layers "*.Cu" "*.Mask")
			(remove_unused_layers no)
			(net 1 "GND")
			(pintype "passive")
			(teardrops
				(best_length_ratio 0.4)
				(max_length 1)
				(best_width_ratio 0.9)
				(max_width 2)
				(curved_edges yes)
				(filter_ratio 0.9)
				(enabled yes)
				(allow_two_segments yes)
				(prefer_zone_connections yes)
			)
		)
	)
	(footprint "antmicro-footprints:R_0201"
		(layer "F.Cu")
		(at 147.33 147.935 -90)
		(descr "Resistor SMD 0201")
		(tags "resistor SMD 0201")
		(property "Reference" "R279"
			(at 3.62 -0.57 90)
			(layer "F.SilkS")
			(effects
				(font
					(size 0.7 0.7)
					(thickness 0.15)
				)
				(justify right bottom)
			)
		)
		(property "Value" "R_0R_0201"
			(at 0 1.25 90)
			(layer "F.Fab")
			(effects
				(font
					(size 0.7 0.7)
					(thickness 0.15)
				)
				(justify right bottom)
			)
		)
		(property "Datasheet" "https://www.bourns.com/docs/product-datasheets/cr.pdf"
			(at 0 0 270)
			(layer "F.Fab")
			(hide yes)
			(effects
				(font
					(size 1.27 1.27)
					(thickness 0.15)
				)
			)
		)
		(property "Author" "Antmicro"
			(at -0.605 295.265 0)
			(layer "F.Fab")
			(hide yes)
			(effects
				(font
					(size 1 1)
					(thickness 0.15)
				)
			)
		)
		(property "License" "Apache-2.0"
			(at -0.605 295.265 0)
			(layer "F.Fab")
			(hide yes)
			(effects
				(font
					(size 1 1)
					(thickness 0.15)
				)
			)
		)
		(property "MPN" "CR0201-FX-0R00GLF"
			(at -0.605 295.265 0)
			(layer "F.Fab")
			(hide yes)
			(effects
				(font
					(size 1 1)
					(thickness 0.15)
				)
			)
		)
		(property "Manufacturer" "Bourns"
			(at -0.605 295.265 0)
			(layer "F.Fab")
			(hide yes)
			(effects
				(font
					(size 1 1)
					(thickness 0.15)
				)
			)
		)
		(property "Tolerance" "1%"
			(at -0.605 295.265 0)
			(layer "F.Fab")
			(hide yes)
			(effects
				(font
					(size 1 1)
					(thickness 0.15)
				)
			)
		)
		(property "Val" "0R"
			(at -0.605 295.265 0)
			(layer "F.Fab")
			(hide yes)
			(effects
				(font
					(size 1 1)
					(thickness 0.15)
				)
			)
		)
		(sheetname "KR to SFI #1")
		(sheetfile "kr_sfi.kicad_sch")
		(attr smd dnp)
		(fp_rect
			(start -0.7 -0.35)
			(end 0.7 0.35)
			(stroke
				(width 0.05)
				(type default)
			)
			(fill no)
			(layer "F.CrtYd")
		)
		(fp_rect
			(start -0.3 -0.15)
			(end 0.298 0.148)
			(stroke
				(width 0.15)
				(type solid)
			)
			(fill no)
			(layer "F.Fab")
		)
		(pad "" smd roundrect
			(at -0.346 0 270)
			(size 0.318 0.36)
			(layers "F.Paste")
			(roundrect_rratio 0.25)
			(teardrops
				(best_length_ratio 0.2)
				(max_length 1)
				(best_width_ratio 0.9)
				(max_width 2)
				(curved_edges yes)
				(filter_ratio 0.9)
				(enabled yes)
				(allow_two_segments yes)
				(prefer_zone_connections yes)
			)
		)
		(pad "" smd roundrect
			(at 0.344 0 270)
			(size 0.318 0.36)
			(layers "F.Paste")
			(roundrect_rratio 0.25)
			(teardrops
				(best_length_ratio 0.2)
				(max_length 1)
				(best_width_ratio 0.9)
				(max_width 2)
				(curved_edges yes)
				(filter_ratio 0.9)
				(enabled yes)
				(allow_two_segments yes)
				(prefer_zone_connections yes)
			)
		)
		(pad "1" smd roundrect
			(at -0.32 0 270)
			(size 0.46 0.4)
			(layers "F.Cu" "F.Mask")
			(roundrect_rratio 0.25)
			(net 172 "/2xSFP+/SFI0.TX+")
			(pintype "passive")
			(teardrops
				(best_length_ratio 0.2)
				(max_length 1)
				(best_width_ratio 0.9)
				(max_width 2)
				(curved_edges yes)
				(filter_ratio 0.9)
				(enabled yes)
				(allow_two_segments yes)
				(prefer_zone_connections yes)
			)
		)
		(pad "2" smd roundrect
			(at 0.32 0 270)
			(size 0.46 0.4)
			(layers "F.Cu" "F.Mask")
			(roundrect_rratio 0.25)
			(net 954 "/2xSFP+/KR to SFI #1/BYP_TX+")
			(pintype "passive")
			(teardrops
				(best_length_ratio 0.2)
				(max_length 1)
				(best_width_ratio 0.9)
				(max_width 2)
				(curved_edges yes)
				(filter_ratio 0.9)
				(enabled yes)
				(allow_two_segments yes)
				(prefer_zone_connections yes)
			)
		)
	)
	(footprint "antmicro-footprints:R_0402_1005Metric"
		(layer "F.Cu")
		(at 111.206998 76.326)
		(descr "Resistor SMD 0402")
		(tags "resistor SMD 0402")
		(property "Reference" "R70"
			(at -1.056998 1.334 0)
			(layer "F.SilkS")
			(effects
				(font
					(size 0.7 0.7)
					(thickness 0.15)
				)
				(justify left bottom)
			)
		)
		(property "Value" "R_27R_0402"
			(at -1.011843 1.772047 0)
			(layer "F.Fab")
			(effects
				(font
					(size 0.7 0.7)
					(thickness 0.15)
				)
				(justify left bottom)
			)
		)
		(property "Datasheet" "https://www.bourns.com/docs/product-datasheets/cr.pdf"
			(at 0 0 0)
			(layer "F.Fab")
			(hide yes)
			(effects
				(font
					(size 1.27 1.27)
					(thickness 0.15)
				)
			)
		)
		(property "Author" "Antmicro"
			(at 0 0 0)
			(layer "F.Fab")
			(hide yes)
			(effects
				(font
					(size 1 1)
					(thickness 0.15)
				)
			)
		)
		(property "License" "Apache-2.0"
			(at 0 0 0)
			(layer "F.Fab")
			(hide yes)
			(effects
				(font
					(size 1 1)
					(thickness 0.15)
				)
			)
		)
		(property "MPN" "CR0402-FX-27R0GLF"
			(at 0 0 0)
			(layer "F.Fab")
			(hide yes)
			(effects
				(font
					(size 1 1)
					(thickness 0.15)
				)
			)
		)
		(property "Manufacturer" "Bourns"
			(at 0 0 0)
			(layer "F.Fab")
			(hide yes)
			(effects
				(font
					(size 1 1)
					(thickness 0.15)
				)
			)
		)
		(property "Public" "False"
			(at 0 0 0)
			(layer "F.Fab")
			(hide yes)
			(effects
				(font
					(size 1 1)
					(thickness 0.15)
				)
			)
		)
		(property "Tolerance" "1%"
			(at 0 0 0)
			(layer "F.Fab")
			(hide yes)
			(effects
				(font
					(size 1 1)
					(thickness 0.15)
				)
			)
		)
		(property "Val" "27R"
			(at 0 0 0)
			(layer "F.Fab")
			(hide yes)
			(effects
				(font
					(size 1 1)
					(thickness 0.15)
				)
			)
		)
		(sheetname "USB-C console")
		(sheetfile "usb-c_console.kicad_sch")
		(attr smd)
		(fp_rect
			(start -0.925 -0.47)
			(end 0.925 0.47)
			(stroke
				(width 0.05)
				(type default)
			)
			(fill no)
			(layer "F.CrtYd")
		)
		(fp_rect
			(start -0.5 -0.25)
			(end 0.5 0.25)
			(stroke
				(width 0.15)
				(type solid)
			)
			(fill no)
			(layer "F.Fab")
		)
		(pad "1" smd roundrect
			(at -0.48 0)
			(size 0.59 0.64)
			(layers "F.Cu" "F.Mask" "F.Paste")
			(roundrect_rratio 0.25)
			(net 56 "/USB-C console/USB_D-")
			(pintype "passive")
			(teardrops
				(best_length_ratio 0.2)
				(max_length 1)
				(best_width_ratio 0.9)
				(max_width 2)
				(curved_edges yes)
				(filter_ratio 0.9)
				(enabled yes)
				(allow_two_segments yes)
				(prefer_zone_connections yes)
			)
		)
		(pad "2" smd roundrect
			(at 0.48 0)
			(size 0.59 0.64)
			(layers "F.Cu" "F.Mask" "F.Paste")
			(roundrect_rratio 0.25)
			(net 569 "/USB-C console/FTDI_D-")
			(pintype "passive")
			(teardrops
				(best_length_ratio 0.2)
				(max_length 1)
				(best_width_ratio 0.9)
				(max_width 2)
				(curved_edges yes)
				(filter_ratio 0.9)
				(enabled yes)
				(allow_two_segments yes)
				(prefer_zone_connections yes)
			)
		)
	)
	(footprint "antmicro-footprints:R_0201"
		(layer "F.Cu")
		(at 132.17 147.336 -90)
		(descr "Resistor SMD 0201")
		(tags "resistor SMD 0201")
		(property "Reference" "R309"
			(at 4.073 -0.58 270)
			(layer "F.SilkS")
			(effects
				(font
					(size 0.7 0.7)
					(thickness 0.15)
				)
				(justify left bottom)
			)
		)
		(property "Value" "R_0R_0201"
			(at 0 1.25 270)
			(layer "F.Fab")
			(effects
				(font
					(size 0.7 0.7)
					(thickness 0.15)
				)
				(justify left bottom)
			)
		)
		(property "Datasheet" "https://www.bourns.com/docs/product-datasheets/cr.pdf"
			(at 0 0 270)
			(layer "F.Fab")
			(hide yes)
			(effects
				(font
					(size 1.27 1.27)
					(thickness 0.15)
				)
			)
		)
		(property "Author" "Antmicro"
			(at -15.166 279.506 0)
			(layer "F.Fab")
			(hide yes)
			(effects
				(font
					(size 1 1)
					(thickness 0.15)
				)
			)
		)
		(property "License" "Apache-2.0"
			(at -15.166 279.506 0)
			(layer "F.Fab")
			(hide yes)
			(effects
				(font
					(size 1 1)
					(thickness 0.15)
				)
			)
		)
		(property "MPN" "CR0201-FX-0R00GLF"
			(at -15.166 279.506 0)
			(layer "F.Fab")
			(hide yes)
			(effects
				(font
					(size 1 1)
					(thickness 0.15)
				)
			)
		)
		(property "Manufacturer" "Bourns"
			(at -15.166 279.506 0)
			(layer "F.Fab")
			(hide yes)
			(effects
				(font
					(size 1 1)
					(thickness 0.15)
				)
			)
		)
		(property "Tolerance" "1%"
			(at -15.166 279.506 0)
			(layer "F.Fab")
			(hide yes)
			(effects
				(font
					(size 1 1)
					(thickness 0.15)
				)
			)
		)
		(property "Val" "0R"
			(at -15.166 279.506 0)
			(layer "F.Fab")
			(hide yes)
			(effects
				(font
					(size 1 1)
					(thickness 0.15)
				)
			)
		)
		(sheetname "KR to SFI #2")
		(sheetfile "kr_sfi.kicad_sch")
		(attr smd)
		(fp_rect
			(start -0.7 -0.35)
			(end 0.7 0.35)
			(stroke
				(width 0.05)
				(type default)
			)
			(fill no)
			(layer "F.CrtYd")
		)
		(fp_rect
			(start -0.3 -0.15)
			(end 0.298 0.148)
			(stroke
				(width 0.15)
				(type solid)
			)
			(fill no)
			(layer "F.Fab")
		)
		(pad "" smd roundrect
			(at -0.346 0 270)
			(size 0.318 0.36)
			(layers "F.Paste")
			(roundrect_rratio 0.25)
			(teardrops
				(best_length_ratio 0.2)
				(max_length 1)
				(best_width_ratio 0.9)
				(max_width 2)
				(curved_edges yes)
				(filter_ratio 0.9)
				(enabled yes)
				(allow_two_segments yes)
				(prefer_zone_connections yes)
			)
		)
		(pad "" smd roundrect
			(at 0.344 0 270)
			(size 0.318 0.36)
			(layers "F.Paste")
			(roundrect_rratio 0.25)
			(teardrops
				(best_length_ratio 0.2)
				(max_length 1)
				(best_width_ratio 0.9)
				(max_width 2)
				(curved_edges yes)
				(filter_ratio 0.9)
				(enabled yes)
				(allow_two_segments yes)
				(prefer_zone_connections yes)
			)
		)
		(pad "1" smd roundrect
			(at -0.32 0 270)
			(size 0.46 0.4)
			(layers "F.Cu" "F.Mask")
			(roundrect_rratio 0.25)
			(net 953 "/2xSFP+/KR to SFI #2/SFI_R.RX-")
			(pintype "passive")
			(teardrops
				(best_length_ratio 0.2)
				(max_length 1)
				(best_width_ratio 0.9)
				(max_width 2)
				(curved_edges yes)
				(filter_ratio 0.9)
				(enabled yes)
				(allow_two_segments yes)
				(prefer_zone_connections yes)
			)
		)
		(pad "2" smd roundrect
			(at 0.32 0 270)
			(size 0.46 0.4)
			(layers "F.Cu" "F.Mask")
			(roundrect_rratio 0.25)
			(net 877 "/2xSFP+/SFI1.RX-")
			(pintype "passive")
			(teardrops
				(best_length_ratio 0.2)
				(max_length 1)
				(best_width_ratio 0.9)
				(max_width 2)
				(curved_edges yes)
				(filter_ratio 0.9)
				(enabled yes)
				(allow_two_segments yes)
				(prefer_zone_connections yes)
			)
		)
	)
	(footprint "antmicro-footprints:C_0402_1005Metric"
		(layer "F.Cu")
		(at 300.64 130.56 90)
		(descr "Capacitor SMD 0402")
		(tags "capacitor SMD 0402")
		(property "Reference" "C54"
			(at -1.1 -0.49 90)
			(layer "F.SilkS")
			(effects
				(font
					(size 0.7 0.7)
					(thickness 0.15)
				)
				(justify left bottom)
			)
		)
		(property "Value" "C_100n_0402"
			(at -1.022927 2.155213 90)
			(layer "F.Fab")
			(effects
				(font
					(size 0.7 0.7)
					(thickness 0.15)
				)
				(justify left bottom)
			)
		)
		(property "Datasheet" "https://www.murata.com/products/productdetail?partno=GRM155R61H104KE14%23"
			(at 0 0 90)
			(layer "F.Fab")
			(hide yes)
			(effects
				(font
					(size 1.27 1.27)
					(thickness 0.15)
				)
			)
		)
		(property "Author" "Antmicro"
			(at 431.2 -170.08 0)
			(layer "F.Fab")
			(hide yes)
			(effects
				(font
					(size 1 1)
					(thickness 0.15)
				)
			)
		)
		(property "Dielectric" "X5R"
			(at 431.2 -170.08 0)
			(layer "F.Fab")
			(hide yes)
			(effects
				(font
					(size 1 1)
					(thickness 0.15)
				)
			)
		)
		(property "License" "Apache-2.0"
			(at 431.2 -170.08 0)
			(layer "F.Fab")
			(hide yes)
			(effects
				(font
					(size 1 1)
					(thickness 0.15)
				)
			)
		)
		(property "MPN" "GRM155R61H104KE14D"
			(at 431.2 -170.08 0)
			(layer "F.Fab")
			(hide yes)
			(effects
				(font
					(size 1 1)
					(thickness 0.15)
				)
			)
		)
		(property "Manufacturer" "Murata"
			(at 431.2 -170.08 0)
			(layer "F.Fab")
			(hide yes)
			(effects
				(font
					(size 1 1)
					(thickness 0.15)
				)
			)
		)
		(property "Public" "False"
			(at 431.2 -170.08 0)
			(layer "F.Fab")
			(hide yes)
			(effects
				(font
					(size 1 1)
					(thickness 0.15)
				)
			)
		)
		(property "Val" "100n"
			(at 431.2 -170.08 0)
			(layer "F.Fab")
			(hide yes)
			(effects
				(font
					(size 1 1)
					(thickness 0.15)
				)
			)
		)
		(property "Voltage" "50V"
			(at 431.2 -170.08 0)
			(layer "F.Fab")
			(hide yes)
			(effects
				(font
					(size 1 1)
					(thickness 0.15)
				)
			)
		)
		(sheetname "Power")
		(sheetfile "power.kicad_sch")
		(attr smd)
		(fp_rect
			(start -0.925 -0.47)
			(end 0.925 0.47)
			(stroke
				(width 0.05)
				(type default)
			)
			(fill no)
			(layer "F.CrtYd")
		)
		(fp_line
			(start 0.504 -0.25)
			(end 0.504 0.248)
			(stroke
				(width 0.15)
				(type solid)
			)
			(layer "F.Fab")
		)
		(fp_line
			(start -0.494 -0.25)
			(end 0.504 -0.25)
			(stroke
				(width 0.15)
				(type solid)
			)
			(layer "F.Fab")
		)
		(fp_line
			(start 0.504 0.248)
			(end -0.494 0.248)
			(stroke
				(width 0.15)
				(type solid)
			)
			(layer "F.Fab")
		)
		(fp_line
			(start -0.494 0.248)
			(end -0.494 -0.25)
			(stroke
				(width 0.15)
				(type solid)
			)
			(layer "F.Fab")
		)
		(pad "1" smd roundrect
			(at -0.48 0 90)
			(size 0.59 0.64)
			(layers "F.Cu" "F.Mask" "F.Paste")
			(roundrect_rratio 0.25)
			(net 1 "GND")
			(pintype "passive")
			(teardrops
				(best_length_ratio 0.2)
				(max_length 1)
				(best_width_ratio 0.9)
				(max_width 2)
				(curved_edges yes)
				(filter_ratio 0.9)
				(enabled yes)
				(allow_two_segments yes)
				(prefer_zone_connections yes)
			)
		)
		(pad "2" smd roundrect
			(at 0.48 0 90)
			(size 0.59 0.64)
			(layers "F.Cu" "F.Mask" "F.Paste")
			(roundrect_rratio 0.25)
			(net 73 "+3V3_AON")
			(pintype "passive")
			(teardrops
				(best_length_ratio 0.2)
				(max_length 1)
				(best_width_ratio 0.9)
				(max_width 2)
				(curved_edges yes)
				(filter_ratio 0.9)
				(enabled yes)
				(allow_two_segments yes)
				(prefer_zone_connections yes)
			)
		)
	)
	(footprint "antmicro-footprints:C_0402_1005Metric"
		(layer "F.Cu")
		(at 114.4 148.421 -90)
		(descr "Capacitor SMD 0402")
		(tags "capacitor SMD 0402")
		(property "Reference" "C111"
			(at -12.611 -2.6 90)
			(layer "F.SilkS")
			(effects
				(font
					(size 0.7 0.7)
					(thickness 0.15)
				)
				(justify right bottom)
			)
		)
		(property "Value" "C_100n_0402"
			(at -1.022927 2.155213 90)
			(layer "F.Fab")
			(effects
				(font
					(size 0.7 0.7)
					(thickness 0.15)
				)
				(justify right bottom)
			)
		)
		(property "Datasheet" "https://www.murata.com/products/productdetail?partno=GRM155R61H104KE14%23"
			(at 0 0 270)
			(layer "F.Fab")
			(hide yes)
			(effects
				(font
					(size 1.27 1.27)
					(thickness 0.15)
				)
			)
		)
		(property "Author" "Antmicro"
			(at -34.021 262.821 0)
			(layer "F.Fab")
			(hide yes)
			(effects
				(font
					(size 1 1)
					(thickness 0.15)
				)
			)
		)
		(property "Dielectric" "X5R"
			(at -34.021 262.821 0)
			(layer "F.Fab")
			(hide yes)
			(effects
				(font
					(size 1 1)
					(thickness 0.15)
				)
			)
		)
		(property "License" "Apache-2.0"
			(at -34.021 262.821 0)
			(layer "F.Fab")
			(hide yes)
			(effects
				(font
					(size 1 1)
					(thickness 0.15)
				)
			)
		)
		(property "MPN" "GRM155R61H104KE14D"
			(at -34.021 262.821 0)
			(layer "F.Fab")
			(hide yes)
			(effects
				(font
					(size 1 1)
					(thickness 0.15)
				)
			)
		)
		(property "Manufacturer" "Murata"
			(at -34.021 262.821 0)
			(layer "F.Fab")
			(hide yes)
			(effects
				(font
					(size 1 1)
					(thickness 0.15)
				)
			)
		)
		(property "Public" "False"
			(at -34.021 262.821 0)
			(layer "F.Fab")
			(hide yes)
			(effects
				(font
					(size 1 1)
					(thickness 0.15)
				)
			)
		)
		(property "Val" "100n"
			(at -34.021 262.821 0)
			(layer "F.Fab")
			(hide yes)
			(effects
				(font
					(size 1 1)
					(thickness 0.15)
				)
			)
		)
		(property "Voltage" "50V"
			(at -34.021 262.821 0)
			(layer "F.Fab")
			(hide yes)
			(effects
				(font
					(size 1 1)
					(thickness 0.15)
				)
			)
		)
		(sheetname "PCIe redriver")
		(sheetfile "pcie_redriver.kicad_sch")
		(attr smd)
		(fp_rect
			(start -0.925 -0.47)
			(end 0.925 0.47)
			(stroke
				(width 0.05)
				(type default)
			)
			(fill no)
			(layer "F.CrtYd")
		)
		(fp_line
			(start -0.494 0.248)
			(end -0.494 -0.25)
			(stroke
				(width 0.15)
				(type solid)
			)
			(layer "F.Fab")
		)
		(fp_line
			(start 0.504 0.248)
			(end -0.494 0.248)
			(stroke
				(width 0.15)
				(type solid)
			)
			(layer "F.Fab")
		)
		(fp_line
			(start -0.494 -0.25)
			(end 0.504 -0.25)
			(stroke
				(width 0.15)
				(type solid)
			)
			(layer "F.Fab")
		)
		(fp_line
			(start 0.504 -0.25)
			(end 0.504 0.248)
			(stroke
				(width 0.15)
				(type solid)
			)
			(layer "F.Fab")
		)
		(pad "1" smd roundrect
			(at -0.48 0 270)
			(size 0.59 0.64)
			(layers "F.Cu" "F.Mask" "F.Paste")
			(roundrect_rratio 0.25)
			(net 1 "GND")
			(pintype "passive")
			(teardrops
				(best_length_ratio 0.2)
				(max_length 1)
				(best_width_ratio 0.9)
				(max_width 2)
				(curved_edges yes)
				(filter_ratio 0.9)
				(enabled yes)
				(allow_two_segments yes)
				(prefer_zone_connections yes)
			)
		)
		(pad "2" smd roundrect
			(at 0.48 0 270)
			(size 0.59 0.64)
			(layers "F.Cu" "F.Mask" "F.Paste")
			(roundrect_rratio 0.25)
			(net 2 "+3V3")
			(pintype "passive")
			(teardrops
				(best_length_ratio 0.2)
				(max_length 1)
				(best_width_ratio 0.9)
				(max_width 2)
				(curved_edges yes)
				(filter_ratio 0.9)
				(enabled yes)
				(allow_two_segments yes)
				(prefer_zone_connections yes)
			)
		)
	)
	(footprint "antmicro-footprints:SOT-323"
		(layer "F.Cu")
		(at 261.35 92.41 90)
		(property "Reference" "Q6"
			(at -0.75 -1.45 90)
			(layer "F.SilkS")
			(effects
				(font
					(size 0.7 0.7)
					(thickness 0.15)
				)
				(justify left bottom)
			)
		)
		(property "Value" "BSS84AKW"
			(at 0 2.749 90)
			(layer "F.Fab")
			(effects
				(font
					(size 0.7 0.7)
					(thickness 0.15)
				)
				(justify left bottom)
			)
		)
		(property "Datasheet" "https://assets.nexperia.com/documents/data-sheet/BSS84AKW.pdf"
			(at 0 0 90)
			(layer "F.Fab")
			(hide yes)
			(effects
				(font
					(size 1.27 1.27)
					(thickness 0.15)
				)
			)
		)
		(property "Author" "Antmicro"
			(at 353.76 -168.94 0)
			(layer "F.Fab")
			(hide yes)
			(effects
				(font
					(size 1 1)
					(thickness 0.15)
				)
			)
		)
		(property "License" "Apache-2.0"
			(at 353.76 -168.94 0)
			(layer "F.Fab")
			(hide yes)
			(effects
				(font
					(size 1 1)
					(thickness 0.15)
				)
			)
		)
		(property "MPN" "BSS84AKW,115"
			(at 353.76 -168.94 0)
			(layer "F.Fab")
			(hide yes)
			(effects
				(font
					(size 1 1)
					(thickness 0.15)
				)
			)
		)
		(property "Manufacturer" "Nexperia"
			(at 353.76 -168.94 0)
			(layer "F.Fab")
			(hide yes)
			(effects
				(font
					(size 1 1)
					(thickness 0.15)
				)
			)
		)
		(sheetname "Misc")
		(sheetfile "misc.kicad_sch")
		(attr smd)
		(fp_line
			(start 0.8 -1.2)
			(end 0.8 -0.902)
			(stroke
				(width 0.15)
				(type solid)
			)
			(layer "F.SilkS")
		)
		(fp_line
			(start 0.498 -1.2)
			(end 0.8 -1.2)
			(stroke
				(width 0.15)
				(type solid)
			)
			(layer "F.SilkS")
		)
		(fp_line
			(start -0.402 -1.2)
			(end -0.802 -1.2)
			(stroke
				(width 0.15)
				(type solid)
			)
			(layer "F.SilkS")
		)
		(fp_line
			(start -0.802 -1.2)
			(end -0.802 -1.05)
			(stroke
				(width 0.15)
				(type solid)
			)
			(layer "F.SilkS")
		)
		(fp_line
			(start -0.802 1.05)
			(end -0.802 1.199)
			(stroke
				(width 0.15)
				(type solid)
			)
			(layer "F.SilkS")
		)
		(fp_line
			(start 0.8 1.199)
			(end 0.8 0.9)
			(stroke
				(width 0.15)
				(type solid)
			)
			(layer "F.SilkS")
		)
		(fp_line
			(start 0.498 1.199)
			(end 0.8 1.199)
			(stroke
				(width 0.15)
				(type solid)
			)
			(layer "F.SilkS")
		)
		(fp_line
			(start -0.802 1.199)
			(end -0.5 1.199)
			(stroke
				(width 0.15)
				(type solid)
			)
			(layer "F.SilkS")
		)
		(fp_circle
			(center -1.05 -1.156824)
			(end -1 -1.129824)
			(stroke
				(width 0.15)
				(type solid)
			)
			(fill no)
			(layer "F.SilkS")
		)
		(fp_rect
			(start -1.35 -1.35)
			(end 1.35 1.35)
			(stroke
				(width 0.05)
				(type solid)
			)
			(fill no)
			(layer "F.CrtYd")
		)
		(fp_line
			(start 0.675 -1.101)
			(end 0.675 1.1)
			(stroke
				(width 0.15)
				(type solid)
			)
			(layer "F.Fab")
		)
		(fp_line
			(start -0.677 -1.101)
			(end 0.675 -1.101)
			(stroke
				(width 0.15)
				(type solid)
			)
			(layer "F.Fab")
		)
		(fp_line
			(start -0.677 -1.101)
			(end -0.677 1.1)
			(stroke
				(width 0.15)
				(type solid)
			)
			(layer "F.Fab")
		)
		(fp_line
			(start -0.677 1.1)
			(end 0.675 1.1)
			(stroke
				(width 0.15)
				(type solid)
			)
			(layer "F.Fab")
		)
		(pad "1" smd rect
			(at -0.927 -0.652 90)
			(size 0.55 0.6)
			(layers "F.Cu" "F.Mask" "F.Paste")
			(net 538 "Net-(Q5-D)")
			(pinfunction "G")
			(pintype "bidirectional")
			(teardrops
				(best_length_ratio 0.2)
				(max_length 1)
				(best_width_ratio 0.9)
				(max_width 2)
				(curved_edges yes)
				(filter_ratio 0.9)
				(enabled yes)
				(allow_two_segments yes)
				(prefer_zone_connections yes)
			)
		)
		(pad "2" smd rect
			(at -0.927 0.65 90)
			(size 0.55 0.6)
			(layers "F.Cu" "F.Mask" "F.Paste")
			(net 2 "+3V3")
			(pinfunction "S")
			(pintype "bidirectional")
			(teardrops
				(best_length_ratio 0.2)
				(max_length 1)
				(best_width_ratio 0.9)
				(max_width 2)
				(curved_edges yes)
				(filter_ratio 0.9)
				(enabled yes)
				(allow_two_segments yes)
				(prefer_zone_connections yes)
			)
		)
		(pad "3" smd rect
			(at 0.925 0 90)
			(size 0.55 0.6)
			(layers "F.Cu" "F.Mask" "F.Paste")
			(net 80 "Net-(Q6-D)")
			(pinfunction "D")
			(pintype "bidirectional")
			(teardrops
				(best_length_ratio 0.2)
				(max_length 1)
				(best_width_ratio 0.9)
				(max_width 2)
				(curved_edges yes)
				(filter_ratio 0.9)
				(enabled yes)
				(allow_two_segments yes)
				(prefer_zone_connections yes)
			)
		)
	)
	(footprint "antmicro-footprints:USON-10_2.5x1mm_P0.5mm"
		(layer "F.Cu")
		(at 112.15 132.41)
		(descr "USON-10 2.5x1mm_ Pitch 0.5mm")
		(tags "USON-10 2.5x1mm Pitch 0.5mm")
		(property "Reference" "U47"
			(at 1.75 1.25 90)
			(layer "F.SilkS")
			(effects
				(font
					(size 0.7 0.7)
					(thickness 0.15)
				)
				(justify left bottom)
			)
		)
		(property "Value" "ESD204DQAR"
			(at 0.018 2.499 0)
			(layer "F.Fab")
			(effects
				(font
					(size 0.7 0.7)
					(thickness 0.15)
				)
				(justify left bottom)
			)
		)
		(property "Datasheet" "https://www.ti.com/lit/ds/symlink/esd204.pdf?ts=1706004844383&ref_url=https%253A%252F%252Fwww.ti.com%252Finterface%252Fdiodes%252Fesd-protection-diodes%252Fproducts.html"
			(at 0 0 0)
			(layer "F.Fab")
			(hide yes)
			(effects
				(font
					(size 1.27 1.27)
					(thickness 0.15)
				)
			)
		)
		(property "Author" "Antmicro"
			(at 0 0 0)
			(layer "F.Fab")
			(hide yes)
			(effects
				(font
					(size 1 1)
					(thickness 0.15)
				)
			)
		)
		(property "License" "Apache-2.0"
			(at 0 0 0)
			(layer "F.Fab")
			(hide yes)
			(effects
				(font
					(size 1 1)
					(thickness 0.15)
				)
			)
		)
		(property "MPN" "ESD204DQAR"
			(at 0 0 0)
			(layer "F.Fab")
			(hide yes)
			(effects
				(font
					(size 1 1)
					(thickness 0.15)
				)
			)
		)
		(property "Manufacturer" "Texas Instruments"
			(at 0 0 0)
			(layer "F.Fab")
			(hide yes)
			(effects
				(font
					(size 1 1)
					(thickness 0.15)
				)
			)
		)
		(sheetname "SD card")
		(sheetfile "sd_card.kicad_sch")
		(attr smd)
		(fp_line
			(start 0.498 -1.401)
			(end -0.5 -1.401)
			(stroke
				(width 0.15)
				(type solid)
			)
			(layer "F.SilkS")
		)
		(fp_line
			(start 0.498 1.398)
			(end -0.5 1.398)
			(stroke
				(width 0.15)
				(type solid)
			)
			(layer "F.SilkS")
		)
		(fp_circle
			(center -0.68 -1.27)
			(end -0.63 -1.27)
			(stroke
				(width 0.15)
				(type solid)
			)
			(fill yes)
			(layer "F.SilkS")
		)
		(fp_rect
			(start -0.8 -1.5)
			(end 0.8 1.499)
			(stroke
				(width 0.05)
				(type solid)
			)
			(fill no)
			(layer "F.CrtYd")
		)
		(fp_line
			(start -0.5 -1)
			(end -0.5 1.249)
			(stroke
				(width 0.15)
				(type solid)
			)
			(layer "F.Fab")
		)
		(fp_line
			(start -0.5 1.249)
			(end 0.498 1.249)
			(stroke
				(width 0.15)
				(type solid)
			)
			(layer "F.Fab")
		)
		(fp_line
			(start -0.25 -1.25)
			(end -0.5 -1)
			(stroke
				(width 0.15)
				(type solid)
			)
			(layer "F.Fab")
		)
		(fp_line
			(start 0.498 -1.25)
			(end -0.25 -1.25)
			(stroke
				(width 0.15)
				(type solid)
			)
			(layer "F.Fab")
		)
		(fp_line
			(start 0.498 -1.25)
			(end 0.498 1.249)
			(stroke
				(width 0.15)
				(type solid)
			)
			(layer "F.Fab")
		)
		(pad "1" smd roundrect
			(at -0.387 -1 270)
			(size 0.25 0.55)
			(layers "F.Cu" "F.Mask" "F.Paste")
			(roundrect_rratio 0.25)
			(net 531 "/Com Express 7 Interfaces/SD_CD")
			(pintype "passive")
			(teardrops
				(best_length_ratio 0.2)
				(max_length 1)
				(best_width_ratio 0.9)
				(max_width 2)
				(curved_edges yes)
				(filter_ratio 0.9)
				(enabled yes)
				(allow_two_segments yes)
				(prefer_zone_connections yes)
			)
		)
		(pad "2" smd roundrect
			(at -0.387 -0.5 270)
			(size 0.25 0.55)
			(layers "F.Cu" "F.Mask" "F.Paste")
			(roundrect_rratio 0.25)
			(net 322 "/Com Express 7 Interfaces/SDIO.DAT1")
			(pintype "passive")
			(teardrops
				(best_length_ratio 0.2)
				(max_length 1)
				(best_width_ratio 0.9)
				(max_width 2)
				(curved_edges yes)
				(filter_ratio 0.9)
				(enabled yes)
				(allow_two_segments yes)
				(prefer_zone_connections yes)
			)
		)
		(pad "3" smd roundrect
			(at -0.387 0 270)
			(size 0.4 0.55)
			(layers "F.Cu" "F.Mask" "F.Paste")
			(roundrect_rratio 0.25)
			(net 1 "GND")
			(pintype "power_in")
			(teardrops
				(best_length_ratio 0.2)
				(max_length 1)
				(best_width_ratio 0.9)
				(max_width 2)
				(curved_edges yes)
				(filter_ratio 0.9)
				(enabled yes)
				(allow_two_segments yes)
				(prefer_zone_connections yes)
			)
		)
		(pad "4" smd roundrect
			(at -0.387 0.498 270)
			(size 0.25 0.55)
			(layers "F.Cu" "F.Mask" "F.Paste")
			(roundrect_rratio 0.25)
			(net 321 "/Com Express 7 Interfaces/SDIO.DAT0")
			(pintype "passive")
			(teardrops
				(best_length_ratio 0.2)
				(max_length 1)
				(best_width_ratio 0.9)
				(max_width 2)
				(curved_edges yes)
				(filter_ratio 0.9)
				(enabled yes)
				(allow_two_segments yes)
				(prefer_zone_connections yes)
			)
		)
		(pad "5" smd roundrect
			(at -0.387 0.998 270)
			(size 0.25 0.55)
			(layers "F.Cu" "F.Mask" "F.Paste")
			(roundrect_rratio 0.25)
			(net 339 "/Com Express 7 Interfaces/SDIO.CLK")
			(pintype "passive")
			(teardrops
				(best_length_ratio 0.2)
				(max_length 1)
				(best_width_ratio 0.9)
				(max_width 2)
				(curved_edges yes)
				(filter_ratio 0.9)
				(enabled yes)
				(allow_two_segments yes)
				(prefer_zone_connections yes)
			)
		)
		(pad "6" smd roundrect
			(at 0.385 0.998 270)
			(size 0.25 0.55)
			(layers "F.Cu" "F.Mask" "F.Paste")
			(roundrect_rratio 0.25)
			(net 339 "/Com Express 7 Interfaces/SDIO.CLK")
			(pintype "passive")
			(teardrops
				(best_length_ratio 0.2)
				(max_length 1)
				(best_width_ratio 0.9)
				(max_width 2)
				(curved_edges yes)
				(filter_ratio 0.9)
				(enabled yes)
				(allow_two_segments yes)
				(prefer_zone_connections yes)
			)
		)
		(pad "7" smd roundrect
			(at 0.385 0.498 270)
			(size 0.25 0.55)
			(layers "F.Cu" "F.Mask" "F.Paste")
			(roundrect_rratio 0.25)
			(net 321 "/Com Express 7 Interfaces/SDIO.DAT0")
			(pintype "passive")
			(teardrops
				(best_length_ratio 0.2)
				(max_length 1)
				(best_width_ratio 0.9)
				(max_width 2)
				(curved_edges yes)
				(filter_ratio 0.9)
				(enabled yes)
				(allow_two_segments yes)
				(prefer_zone_connections yes)
			)
		)
		(pad "8" smd roundrect
			(at 0.385 0 270)
			(size 0.4 0.55)
			(layers "F.Cu" "F.Mask" "F.Paste")
			(roundrect_rratio 0.25)
			(net 1 "GND")
			(pintype "passive")
			(teardrops
				(best_length_ratio 0.2)
				(max_length 1)
				(best_width_ratio 0.9)
				(max_width 2)
				(curved_edges yes)
				(filter_ratio 0.9)
				(enabled yes)
				(allow_two_segments yes)
				(prefer_zone_connections yes)
			)
		)
		(pad "9" smd roundrect
			(at 0.385 -0.5 270)
			(size 0.25 0.55)
			(layers "F.Cu" "F.Mask" "F.Paste")
			(roundrect_rratio 0.25)
			(net 322 "/Com Express 7 Interfaces/SDIO.DAT1")
			(pintype "passive")
			(teardrops
				(best_length_ratio 0.2)
				(max_length 1)
				(best_width_ratio 0.9)
				(max_width 2)
				(curved_edges yes)
				(filter_ratio 0.9)
				(enabled yes)
				(allow_two_segments yes)
				(prefer_zone_connections yes)
			)
		)
		(pad "10" smd roundrect
			(at 0.385 -1 270)
			(size 0.25 0.55)
			(layers "F.Cu" "F.Mask" "F.Paste")
			(roundrect_rratio 0.25)
			(net 531 "/Com Express 7 Interfaces/SD_CD")
			(pintype "passive")
			(teardrops
				(best_length_ratio 0.2)
				(max_length 1)
				(best_width_ratio 0.9)
				(max_width 2)
				(curved_edges yes)
				(filter_ratio 0.9)
				(enabled yes)
				(allow_two_segments yes)
				(prefer_zone_connections yes)
			)
		)
	)
	(footprint "antmicro-footprints:R_0402_1005Metric"
		(layer "F.Cu")
		(at 302.95 84.01 -90)
		(descr "Resistor SMD 0402")
		(tags "resistor SMD 0402")
		(property "Reference" "R130"
			(at -1.35 0.5 90)
			(layer "F.SilkS")
			(effects
				(font
					(size 0.7 0.7)
					(thickness 0.15)
				)
				(justify right bottom)
			)
		)
		(property "Value" "R_0R_0402"
			(at -1.011843 1.772047 90)
			(layer "F.Fab")
			(effects
				(font
					(size 0.7 0.7)
					(thickness 0.15)
				)
				(justify right bottom)
			)
		)
		(property "Datasheet" "https://industrial.panasonic.com/cdbs/www-data/pdf/RDA0000/AOA0000C301.pdf"
			(at 0 0 270)
			(layer "F.Fab")
			(hide yes)
			(effects
				(font
					(size 1.27 1.27)
					(thickness 0.15)
				)
			)
		)
		(property "Author" "Antmicro"
			(at 218.94 386.96 0)
			(layer "F.Fab")
			(hide yes)
			(effects
				(font
					(size 1 1)
					(thickness 0.15)
				)
			)
		)
		(property "Current" "1A"
			(at 218.94 386.96 0)
			(layer "F.Fab")
			(hide yes)
			(effects
				(font
					(size 1 1)
					(thickness 0.15)
				)
			)
		)
		(property "License" "Apache-2.0"
			(at 218.94 386.96 0)
			(layer "F.Fab")
			(hide yes)
			(effects
				(font
					(size 1 1)
					(thickness 0.15)
				)
			)
		)
		(property "MPN" "ERJ2GE0R00X"
			(at 218.94 386.96 0)
			(layer "F.Fab")
			(hide yes)
			(effects
				(font
					(size 1 1)
					(thickness 0.15)
				)
			)
		)
		(property "Manufacturer" "Panasonic"
			(at 218.94 386.96 0)
			(layer "F.Fab")
			(hide yes)
			(effects
				(font
					(size 1 1)
					(thickness 0.15)
				)
			)
		)
		(property "Public" "False"
			(at 218.94 386.96 0)
			(layer "F.Fab")
			(hide yes)
			(effects
				(font
					(size 1 1)
					(thickness 0.15)
				)
			)
		)
		(property "Tolerance" ""
			(at 218.94 386.96 0)
			(layer "F.Fab")
			(hide yes)
			(effects
				(font
					(size 1 1)
					(thickness 0.15)
				)
			)
		)
		(property "Val" "0R"
			(at 218.94 386.96 0)
			(layer "F.Fab")
			(hide yes)
			(effects
				(font
					(size 1 1)
					(thickness 0.15)
				)
			)
		)
		(sheetname "M.2 key M #2")
		(sheetfile "m2keym.kicad_sch")
		(attr smd)
		(fp_rect
			(start -0.925 -0.47)
			(end 0.925 0.47)
			(stroke
				(width 0.05)
				(type default)
			)
			(fill no)
			(layer "F.CrtYd")
		)
		(fp_rect
			(start -0.5 -0.25)
			(end 0.5 0.25)
			(stroke
				(width 0.15)
				(type solid)
			)
			(fill no)
			(layer "F.Fab")
		)
		(pad "1" smd roundrect
			(at -0.48 0 270)
			(size 0.59 0.64)
			(layers "F.Cu" "F.Mask" "F.Paste")
			(roundrect_rratio 0.25)
			(net 277 "Net-(J8-SUSCLK)")
			(pintype "passive")
			(teardrops
				(best_length_ratio 0.2)
				(max_length 1)
				(best_width_ratio 0.9)
				(max_width 2)
				(curved_edges yes)
				(filter_ratio 0.9)
				(enabled yes)
				(allow_two_segments yes)
				(prefer_zone_connections yes)
			)
		)
		(pad "2" smd roundrect
			(at 0.48 0 270)
			(size 0.59 0.64)
			(layers "F.Cu" "F.Mask" "F.Paste")
			(roundrect_rratio 0.25)
			(net 587 "/M.2 key E/SUSCLK")
			(pintype "passive")
			(teardrops
				(best_length_ratio 0.2)
				(max_length 1)
				(best_width_ratio 0.9)
				(max_width 2)
				(curved_edges yes)
				(filter_ratio 0.9)
				(enabled yes)
				(allow_two_segments yes)
				(prefer_zone_connections yes)
			)
		)
	)
	(footprint "antmicro-footprints:TP_SMD_0.75mm"
		(layer "F.Cu")
		(at 197.70861 72.802163 -90)
		(property "Reference" "TP98"
			(at 0 -0.6 90)
			(layer "F.SilkS")
			(hide yes)
			(effects
				(font
					(size 0.7 0.7)
					(thickness 0.15)
				)
				(justify right bottom)
			)
		)
		(property "Value" "TP_0.75mm_SMD"
			(at 0 1.2 90)
			(layer "F.Fab")
			(effects
				(font
					(size 0.7 0.7)
					(thickness 0.15)
				)
				(justify right bottom)
			)
		)
		(property "Author" "Antmicro"
			(at 124.906447 270.510773 0)
			(layer "F.Fab")
			(hide yes)
			(effects
				(font
					(size 1 1)
					(thickness 0.15)
				)
			)
		)
		(property "License" "Apache-2.0"
			(at 124.906447 270.510773 0)
			(layer "F.Fab")
			(hide yes)
			(effects
				(font
					(size 1 1)
					(thickness 0.15)
				)
			)
		)
		(property "MPN" ""
			(at 124.906447 270.510773 0)
			(layer "F.Fab")
			(hide yes)
			(effects
				(font
					(size 1 1)
					(thickness 0.15)
				)
			)
		)
		(property "Manufacturer" ""
			(at 124.906447 270.510773 0)
			(layer "F.Fab")
			(hide yes)
			(effects
				(font
					(size 1 1)
					(thickness 0.15)
				)
			)
		)
		(property "Public" "False"
			(at 124.906447 270.510773 0)
			(layer "F.Fab")
			(hide yes)
			(effects
				(font
					(size 1 1)
					(thickness 0.15)
				)
			)
		)
		(sheetname "Power")
		(sheetfile "power.kicad_sch")
		(attr exclude_from_pos_files exclude_from_bom)
		(fp_circle
			(center 0 0)
			(end 0.475 0)
			(stroke
				(width 0.05)
				(type default)
			)
			(fill no)
			(layer "F.CrtYd")
		)
		(pad "1" smd circle
			(at 0 0 270)
			(size 0.75 0.75)
			(layers "F.Cu" "F.Mask")
			(net 2 "+3V3")
			(pinfunction "1")
			(pintype "passive")
			(teardrops
				(best_length_ratio 0.4)
				(max_length 1)
				(best_width_ratio 0.9)
				(max_width 2)
				(curved_edges yes)
				(filter_ratio 0.9)
				(enabled yes)
				(allow_two_segments yes)
				(prefer_zone_connections yes)
			)
		)
	)
	(footprint "antmicro-footprints:C_0402_1005Metric"
		(layer "F.Cu")
		(at 118.9 146.301 90)
		(descr "Capacitor SMD 0402")
		(tags "capacitor SMD 0402")
		(property "Reference" "C120"
			(at 10.541 1.1 90)
			(layer "F.SilkS")
			(effects
				(font
					(size 0.7 0.7)
					(thickness 0.15)
				)
				(justify left bottom)
			)
		)
		(property "Value" "C_100n_0402"
			(at -1.022927 2.155213 90)
			(layer "F.Fab")
			(effects
				(font
					(size 0.7 0.7)
					(thickness 0.15)
				)
				(justify left bottom)
			)
		)
		(property "Datasheet" "https://www.murata.com/products/productdetail?partno=GRM155R61H104KE14%23"
			(at 0 0 90)
			(layer "F.Fab")
			(hide yes)
			(effects
				(font
					(size 1.27 1.27)
					(thickness 0.15)
				)
			)
		)
		(property "Author" "Antmicro"
			(at 265.201 27.401 0)
			(layer "F.Fab")
			(hide yes)
			(effects
				(font
					(size 1 1)
					(thickness 0.15)
				)
			)
		)
		(property "Dielectric" "X5R"
			(at 265.201 27.401 0)
			(layer "F.Fab")
			(hide yes)
			(effects
				(font
					(size 1 1)
					(thickness 0.15)
				)
			)
		)
		(property "License" "Apache-2.0"
			(at 265.201 27.401 0)
			(layer "F.Fab")
			(hide yes)
			(effects
				(font
					(size 1 1)
					(thickness 0.15)
				)
			)
		)
		(property "MPN" "GRM155R61H104KE14D"
			(at 265.201 27.401 0)
			(layer "F.Fab")
			(hide yes)
			(effects
				(font
					(size 1 1)
					(thickness 0.15)
				)
			)
		)
		(property "Manufacturer" "Murata"
			(at 265.201 27.401 0)
			(layer "F.Fab")
			(hide yes)
			(effects
				(font
					(size 1 1)
					(thickness 0.15)
				)
			)
		)
		(property "Public" "False"
			(at 265.201 27.401 0)
			(layer "F.Fab")
			(hide yes)
			(effects
				(font
					(size 1 1)
					(thickness 0.15)
				)
			)
		)
		(property "Val" "100n"
			(at 265.201 27.401 0)
			(layer "F.Fab")
			(hide yes)
			(effects
				(font
					(size 1 1)
					(thickness 0.15)
				)
			)
		)
		(property "Voltage" "50V"
			(at 265.201 27.401 0)
			(layer "F.Fab")
			(hide yes)
			(effects
				(font
					(size 1 1)
					(thickness 0.15)
				)
			)
		)
		(sheetname "PCIe redriver")
		(sheetfile "pcie_redriver.kicad_sch")
		(attr smd)
		(fp_rect
			(start -0.925 -0.47)
			(end 0.925 0.47)
			(stroke
				(width 0.05)
				(type default)
			)
			(fill no)
			(layer "F.CrtYd")
		)
		(fp_line
			(start 0.504 -0.25)
			(end 0.504 0.248)
			(stroke
				(width 0.15)
				(type solid)
			)
			(layer "F.Fab")
		)
		(fp_line
			(start -0.494 -0.25)
			(end 0.504 -0.25)
			(stroke
				(width 0.15)
				(type solid)
			)
			(layer "F.Fab")
		)
		(fp_line
			(start 0.504 0.248)
			(end -0.494 0.248)
			(stroke
				(width 0.15)
				(type solid)
			)
			(layer "F.Fab")
		)
		(fp_line
			(start -0.494 0.248)
			(end -0.494 -0.25)
			(stroke
				(width 0.15)
				(type solid)
			)
			(layer "F.Fab")
		)
		(pad "1" smd roundrect
			(at -0.48 0 90)
			(size 0.59 0.64)
			(layers "F.Cu" "F.Mask" "F.Paste")
			(roundrect_rratio 0.25)
			(net 1 "GND")
			(pintype "passive")
			(teardrops
				(best_length_ratio 0.2)
				(max_length 1)
				(best_width_ratio 0.9)
				(max_width 2)
				(curved_edges yes)
				(filter_ratio 0.9)
				(enabled yes)
				(allow_two_segments yes)
				(prefer_zone_connections yes)
			)
		)
		(pad "2" smd roundrect
			(at 0.48 0 90)
			(size 0.59 0.64)
			(layers "F.Cu" "F.Mask" "F.Paste")
			(roundrect_rratio 0.25)
			(net 2 "+3V3")
			(pintype "passive")
			(teardrops
				(best_length_ratio 0.2)
				(max_length 1)
				(best_width_ratio 0.9)
				(max_width 2)
				(curved_edges yes)
				(filter_ratio 0.9)
				(enabled yes)
				(allow_two_segments yes)
				(prefer_zone_connections yes)
			)
		)
	)
	(footprint "antmicro-footprints:C_Pol_EIA-B"
		(layer "F.Cu")
		(at 308.825 96.74)
		(property "Reference" "C64"
			(at -4.325 1.82 0)
			(layer "F.SilkS")
			(effects
				(font
					(size 0.7 0.7)
					(thickness 0.15)
				)
				(justify left bottom)
			)
		)
		(property "Value" "C_Pol_100u_10V_KEMET-T520-B"
			(at 0 2.85 0)
			(layer "F.Fab")
			(effects
				(font
					(size 0.7 0.7)
					(thickness 0.15)
				)
				(justify left bottom)
			)
		)
		(property "Datasheet" "https://www.kemet.com/en/us/capacitors/product/T520B107M010ATE070.html"
			(at 0 0 0)
			(layer "F.Fab")
			(hide yes)
			(effects
				(font
					(size 1.27 1.27)
					(thickness 0.15)
				)
			)
		)
		(property "Author" "Antmicro"
			(at 0 0 0)
			(layer "F.Fab")
			(hide yes)
			(effects
				(font
					(size 1 1)
					(thickness 0.15)
				)
			)
		)
		(property "Dielectric" "template_dielectric"
			(at 0 0 0)
			(layer "F.Fab")
			(hide yes)
			(effects
				(font
					(size 1 1)
					(thickness 0.15)
				)
			)
		)
		(property "License" "Apache-2.0"
			(at 0 0 0)
			(layer "F.Fab")
			(hide yes)
			(effects
				(font
					(size 1 1)
					(thickness 0.15)
				)
			)
		)
		(property "MPN" "T520B107M010ATE070"
			(at 0 0 0)
			(layer "F.Fab")
			(hide yes)
			(effects
				(font
					(size 1 1)
					(thickness 0.15)
				)
			)
		)
		(property "Manufacturer" "KEMET"
			(at 0 0 0)
			(layer "F.Fab")
			(hide yes)
			(effects
				(font
					(size 1 1)
					(thickness 0.15)
				)
			)
		)
		(property "Public" "False"
			(at 0 0 0)
			(layer "F.Fab")
			(hide yes)
			(effects
				(font
					(size 1 1)
					(thickness 0.15)
				)
			)
		)
		(property "Val" "100u"
			(at 0 0 0)
			(layer "F.Fab")
			(hide yes)
			(effects
				(font
					(size 1 1)
					(thickness 0.15)
				)
			)
		)
		(property "Voltage" "10V"
			(at 0 0 0)
			(layer "F.Fab")
			(hide yes)
			(effects
				(font
					(size 1 1)
					(thickness 0.15)
				)
			)
		)
		(sheetname "Power")
		(sheetfile "power.kicad_sch")
		(attr smd)
		(fp_line
			(start -2.521 -1.676)
			(end -2.123 -1.676)
			(stroke
				(width 0.15)
				(type solid)
			)
			(layer "F.SilkS")
		)
		(fp_line
			(start -2.325 -1.475)
			(end -2.325 -1.878)
			(stroke
				(width 0.15)
				(type solid)
			)
			(layer "F.SilkS")
		)
		(fp_line
			(start -1.8 -1.6)
			(end 1.8 -1.6)
			(stroke
				(width 0.15)
				(type solid)
			)
			(layer "F.SilkS")
		)
		(fp_line
			(start -1.8 -1.3)
			(end -1.8 -1.6)
			(stroke
				(width 0.15)
				(type solid)
			)
			(layer "F.SilkS")
		)
		(fp_line
			(start -1.8 1.3)
			(end -1.8 1.6)
			(stroke
				(width 0.15)
				(type solid)
			)
			(layer "F.SilkS")
		)
		(fp_line
			(start 1.8 -1.3)
			(end 1.8 -1.6)
			(stroke
				(width 0.15)
				(type solid)
			)
			(layer "F.SilkS")
		)
		(fp_line
			(start 1.8 1.3)
			(end 1.8 1.6)
			(stroke
				(width 0.15)
				(type solid)
			)
			(layer "F.SilkS")
		)
		(fp_line
			(start 1.8 1.6)
			(end -1.8 1.6)
			(stroke
				(width 0.15)
				(type solid)
			)
			(layer "F.SilkS")
		)
		(fp_line
			(start -2.411 -1.35)
			(end -2.41 1.35)
			(stroke
				(width 0.05)
				(type solid)
			)
			(layer "F.CrtYd")
		)
		(fp_line
			(start -1.97 -1.75)
			(end -1.97 -1.35)
			(stroke
				(width 0.05)
				(type solid)
			)
			(layer "F.CrtYd")
		)
		(fp_line
			(start -1.97 -1.35)
			(end -2.41 -1.35)
			(stroke
				(width 0.05)
				(type solid)
			)
			(layer "F.CrtYd")
		)
		(fp_line
			(start -1.97 1.35)
			(end -2.41 1.35)
			(stroke
				(width 0.05)
				(type solid)
			)
			(layer "F.CrtYd")
		)
		(fp_line
			(start -1.97 1.35)
			(end -1.97 1.75)
			(stroke
				(width 0.05)
				(type solid)
			)
			(layer "F.CrtYd")
		)
		(fp_line
			(start 1.959 -1.75)
			(end -1.97 -1.75)
			(stroke
				(width 0.05)
				(type solid)
			)
			(layer "F.CrtYd")
		)
		(fp_line
			(start 1.959 -1.75)
			(end 1.959 -1.35)
			(stroke
				(width 0.05)
				(type solid)
			)
			(layer "F.CrtYd")
		)
		(fp_line
			(start 1.96 1.35)
			(end 1.96 1.75)
			(stroke
				(width 0.05)
				(type solid)
			)
			(layer "F.CrtYd")
		)
		(fp_line
			(start 1.96 1.75)
			(end -1.97 1.75)
			(stroke
				(width 0.05)
				(type solid)
			)
			(layer "F.CrtYd")
		)
		(fp_line
			(start 2.399 -1.35)
			(end 1.959 -1.35)
			(stroke
				(width 0.05)
				(type solid)
			)
			(layer "F.CrtYd")
		)
		(fp_line
			(start 2.399 -1.35)
			(end 2.4 1.35)
			(stroke
				(width 0.05)
				(type solid)
			)
			(layer "F.CrtYd")
		)
		(fp_line
			(start 2.4 1.35)
			(end 1.96 1.35)
			(stroke
				(width 0.05)
				(type solid)
			)
			(layer "F.CrtYd")
		)
		(fp_line
			(start -1.7 1.324)
			(end -1.551 1.475)
			(stroke
				(width 0.15)
				(type solid)
			)
			(layer "F.Fab")
		)
		(fp_rect
			(start -1.72 -1.5)
			(end 1.719 1.499)
			(stroke
				(width 0.15)
				(type solid)
			)
			(fill no)
			(layer "F.Fab")
		)
		(pad "1" smd roundrect
			(at -1.551 0)
			(size 1.2 2.2)
			(layers "F.Cu" "F.Mask" "F.Paste")
			(roundrect_rratio 0.1)
			(net 75 "Net-(U50-IN+)")
			(pintype "passive")
			(teardrops
				(best_length_ratio 0.2)
				(max_length 1)
				(best_width_ratio 0.9)
				(max_width 2)
				(curved_edges yes)
				(filter_ratio 0.9)
				(enabled yes)
				(allow_two_segments yes)
				(prefer_zone_connections yes)
			)
		)
		(pad "2" smd roundrect
			(at 1.55 0)
			(size 1.2 2.2)
			(layers "F.Cu" "F.Mask" "F.Paste")
			(roundrect_rratio 0.1)
			(net 1 "GND")
			(pintype "passive")
			(teardrops
				(best_length_ratio 0.2)
				(max_length 1)
				(best_width_ratio 0.9)
				(max_width 2)
				(curved_edges yes)
				(filter_ratio 0.9)
				(enabled yes)
				(allow_two_segments yes)
				(prefer_zone_connections yes)
			)
		)
	)
	(footprint "antmicro-footprints:R_0402_1005Metric"
		(layer "F.Cu")
		(at 201.70861 77.152163 90)
		(descr "Resistor SMD 0402")
		(tags "resistor SMD 0402")
		(property "Reference" "R318"
			(at -1.9 -0.5 90)
			(layer "F.SilkS")
			(effects
				(font
					(size 0.7 0.7)
					(thickness 0.15)
				)
				(justify left bottom)
			)
		)
		(property "Value" "R_2k2_0402"
			(at -1.011843 1.772047 90)
			(layer "F.Fab")
			(effects
				(font
					(size 0.7 0.7)
					(thickness 0.15)
				)
				(justify left bottom)
			)
		)
		(property "Datasheet" "https://www.bourns.com/docs/product-datasheets/cr.pdf"
			(at 0 0 90)
			(layer "F.Fab")
			(hide yes)
			(effects
				(font
					(size 1.27 1.27)
					(thickness 0.15)
				)
			)
		)
		(property "Author" "Antmicro"
			(at 278.860773 -124.556447 0)
			(layer "F.Fab")
			(hide yes)
			(effects
				(font
					(size 1 1)
					(thickness 0.15)
				)
			)
		)
		(property "License" "Apache-2.0"
			(at 278.860773 -124.556447 0)
			(layer "F.Fab")
			(hide yes)
			(effects
				(font
					(size 1 1)
					(thickness 0.15)
				)
			)
		)
		(property "MPN" "CR0402-FX-2201GLF"
			(at 278.860773 -124.556447 0)
			(layer "F.Fab")
			(hide yes)
			(effects
				(font
					(size 1 1)
					(thickness 0.15)
				)
			)
		)
		(property "Manufacturer" "Bourns"
			(at 278.860773 -124.556447 0)
			(layer "F.Fab")
			(hide yes)
			(effects
				(font
					(size 1 1)
					(thickness 0.15)
				)
			)
		)
		(property "Tolerance" "1%"
			(at 278.860773 -124.556447 0)
			(layer "F.Fab")
			(hide yes)
			(effects
				(font
					(size 1 1)
					(thickness 0.15)
				)
			)
		)
		(property "Val" "2k2"
			(at 278.860773 -124.556447 0)
			(layer "F.Fab")
			(hide yes)
			(effects
				(font
					(size 1 1)
					(thickness 0.15)
				)
			)
		)
		(sheetname "Power")
		(sheetfile "power.kicad_sch")
		(attr smd)
		(fp_rect
			(start -0.925 -0.47)
			(end 0.925 0.47)
			(stroke
				(width 0.05)
				(type default)
			)
			(fill no)
			(layer "F.CrtYd")
		)
		(fp_rect
			(start -0.5 -0.25)
			(end 0.5 0.25)
			(stroke
				(width 0.15)
				(type solid)
			)
			(fill no)
			(layer "F.Fab")
		)
		(pad "1" smd roundrect
			(at -0.48 0 90)
			(size 0.59 0.64)
			(layers "F.Cu" "F.Mask" "F.Paste")
			(roundrect_rratio 0.25)
			(net 988 "Net-(Q13-C)")
			(pintype "passive")
			(teardrops
				(best_length_ratio 0.2)
				(max_length 1)
				(best_width_ratio 0.9)
				(max_width 2)
				(curved_edges yes)
				(filter_ratio 0.9)
				(enabled yes)
				(allow_two_segments yes)
				(prefer_zone_connections yes)
			)
		)
		(pad "2" smd roundrect
			(at 0.48 0 90)
			(size 0.59 0.64)
			(layers "F.Cu" "F.Mask" "F.Paste")
			(roundrect_rratio 0.25)
			(net 979 "Net-(D26-C)")
			(pintype "passive")
			(teardrops
				(best_length_ratio 0.2)
				(max_length 1)
				(best_width_ratio 0.9)
				(max_width 2)
				(curved_edges yes)
				(filter_ratio 0.9)
				(enabled yes)
				(allow_two_segments yes)
				(prefer_zone_connections yes)
			)
		)
	)
	(footprint "antmicro-footprints:R_0402_1005Metric"
		(layer "F.Cu")
		(at 199.70861 77.152163 90)
		(descr "Resistor SMD 0402")
		(tags "resistor SMD 0402")
		(property "Reference" "R319"
			(at -1.9 -0.5 90)
			(layer "F.SilkS")
			(effects
				(font
					(size 0.7 0.7)
					(thickness 0.15)
				)
				(justify left bottom)
			)
		)
		(property "Value" "R_2k2_0402"
			(at -1.011843 1.772047 90)
			(layer "F.Fab")
			(effects
				(font
					(size 0.7 0.7)
					(thickness 0.15)
				)
				(justify left bottom)
			)
		)
		(property "Datasheet" "https://www.bourns.com/docs/product-datasheets/cr.pdf"
			(at 0 0 90)
			(layer "F.Fab")
			(hide yes)
			(effects
				(font
					(size 1.27 1.27)
					(thickness 0.15)
				)
			)
		)
		(property "Author" "Antmicro"
			(at 276.860773 -122.556447 0)
			(layer "F.Fab")
			(hide yes)
			(effects
				(font
					(size 1 1)
					(thickness 0.15)
				)
			)
		)
		(property "License" "Apache-2.0"
			(at 276.860773 -122.556447 0)
			(layer "F.Fab")
			(hide yes)
			(effects
				(font
					(size 1 1)
					(thickness 0.15)
				)
			)
		)
		(property "MPN" "CR0402-FX-2201GLF"
			(at 276.860773 -122.556447 0)
			(layer "F.Fab")
			(hide yes)
			(effects
				(font
					(size 1 1)
					(thickness 0.15)
				)
			)
		)
		(property "Manufacturer" "Bourns"
			(at 276.860773 -122.556447 0)
			(layer "F.Fab")
			(hide yes)
			(effects
				(font
					(size 1 1)
					(thickness 0.15)
				)
			)
		)
		(property "Tolerance" "1%"
			(at 276.860773 -122.556447 0)
			(layer "F.Fab")
			(hide yes)
			(effects
				(font
					(size 1 1)
					(thickness 0.15)
				)
			)
		)
		(property "Val" "2k2"
			(at 276.860773 -122.556447 0)
			(layer "F.Fab")
			(hide yes)
			(effects
				(font
					(size 1 1)
					(thickness 0.15)
				)
			)
		)
		(sheetname "Power")
		(sheetfile "power.kicad_sch")
		(attr smd)
		(fp_rect
			(start -0.925 -0.47)
			(end 0.925 0.47)
			(stroke
				(width 0.05)
				(type default)
			)
			(fill no)
			(layer "F.CrtYd")
		)
		(fp_rect
			(start -0.5 -0.25)
			(end 0.5 0.25)
			(stroke
				(width 0.15)
				(type solid)
			)
			(fill no)
			(layer "F.Fab")
		)
		(pad "1" smd roundrect
			(at -0.48 0 90)
			(size 0.59 0.64)
			(layers "F.Cu" "F.Mask" "F.Paste")
			(roundrect_rratio 0.25)
			(net 990 "Net-(Q14-C)")
			(pintype "passive")
			(teardrops
				(best_length_ratio 0.2)
				(max_length 1)
				(best_width_ratio 0.9)
				(max_width 2)
				(curved_edges yes)
				(filter_ratio 0.9)
				(enabled yes)
				(allow_two_segments yes)
				(prefer_zone_connections yes)
			)
		)
		(pad "2" smd roundrect
			(at 0.48 0 90)
			(size 0.59 0.64)
			(layers "F.Cu" "F.Mask" "F.Paste")
			(roundrect_rratio 0.25)
			(net 980 "Net-(D27-C)")
			(pintype "passive")
			(teardrops
				(best_length_ratio 0.2)
				(max_length 1)
				(best_width_ratio 0.9)
				(max_width 2)
				(curved_edges yes)
				(filter_ratio 0.9)
				(enabled yes)
				(allow_two_segments yes)
				(prefer_zone_connections yes)
			)
		)
	)
	(footprint "antmicro-footprints:SOT-23-3"
		(layer "F.Cu")
		(at 199 80.75 90)
		(property "Reference" "Q14"
			(at -1.45 -1.75 90)
			(layer "F.SilkS")
			(effects
				(font
					(size 0.7 0.7)
					(thickness 0.15)
				)
				(justify left bottom)
			)
		)
		(property "Value" "MMBT3904LT1G"
			(at -1.9 2.7 90)
			(layer "F.Fab")
			(effects
				(font
					(size 0.7 0.7)
					(thickness 0.15)
				)
				(justify left bottom)
			)
		)
		(property "Datasheet" "https://eu.mouser.com/datasheet/2/308/1/MMBT3904LT1_D-2316262.pdf"
			(at 0 0 90)
			(layer "F.Fab")
			(hide yes)
			(effects
				(font
					(size 1.27 1.27)
					(thickness 0.15)
				)
			)
		)
		(property "Author" "Antmicro"
			(at 282.725773 -121.441447 0)
			(layer "F.Fab")
			(hide yes)
			(effects
				(font
					(size 1 1)
					(thickness 0.15)
				)
			)
		)
		(property "License" "Apache-2.0"
			(at 282.725773 -121.441447 0)
			(layer "F.Fab")
			(hide yes)
			(effects
				(font
					(size 1 1)
					(thickness 0.15)
				)
			)
		)
		(property "MPN" "MMBT3904LT1G"
			(at 282.725773 -121.441447 0)
			(layer "F.Fab")
			(hide yes)
			(effects
				(font
					(size 1 1)
					(thickness 0.15)
				)
			)
		)
		(property "Manufacturer" "Onsemi"
			(at 282.725773 -121.441447 0)
			(layer "F.Fab")
			(hide yes)
			(effects
				(font
					(size 1 1)
					(thickness 0.15)
				)
			)
		)
		(property "Public" "False"
			(at 282.725773 -121.441447 0)
			(layer "F.Fab")
			(hide yes)
			(effects
				(font
					(size 1 1)
					(thickness 0.15)
				)
			)
		)
		(property ki_fp_filters "SOT?323*")
		(sheetname "Power")
		(sheetfile "power.kicad_sch")
		(attr smd)
		(fp_line
			(start 0.7 -1.5)
			(end -0.7 -1.5)
			(stroke
				(width 0.15)
				(type solid)
			)
			(layer "F.SilkS")
		)
		(fp_line
			(start -0.85 -1.35)
			(end -0.7 -1.5)
			(stroke
				(width 0.15)
				(type solid)
			)
			(layer "F.SilkS")
		)
		(fp_line
			(start -1.45 -1.35)
			(end -0.85 -1.35)
			(stroke
				(width 0.15)
				(type solid)
			)
			(layer "F.SilkS")
		)
		(fp_line
			(start 0.7 -0.4)
			(end 0.7 -1.5)
			(stroke
				(width 0.15)
				(type solid)
			)
			(layer "F.SilkS")
		)
		(fp_line
			(start 0.7 0.4)
			(end 0.7 1.5)
			(stroke
				(width 0.15)
				(type solid)
			)
			(layer "F.SilkS")
		)
		(fp_line
			(start 0.7 1.5)
			(end -0.7 1.5)
			(stroke
				(width 0.15)
				(type solid)
			)
			(layer "F.SilkS")
		)
		(fp_line
			(start -0.7 1.5)
			(end -0.7 1.35)
			(stroke
				(width 0.15)
				(type solid)
			)
			(layer "F.SilkS")
		)
		(fp_line
			(start 0.825 -1.6)
			(end 0.825 -0.45)
			(stroke
				(width 0.05)
				(type solid)
			)
			(layer "F.CrtYd")
		)
		(fp_line
			(start -0.9 -1.6)
			(end 0.825 -1.6)
			(stroke
				(width 0.05)
				(type solid)
			)
			(layer "F.CrtYd")
		)
		(fp_line
			(start -0.9 -1.6)
			(end -0.9 -1.4)
			(stroke
				(width 0.05)
				(type solid)
			)
			(layer "F.CrtYd")
		)
		(fp_line
			(start -0.9 -1.4)
			(end -1.75 -1.4)
			(stroke
				(width 0.05)
				(type solid)
			)
			(layer "F.CrtYd")
		)
		(fp_line
			(start -0.85 -0.5)
			(end -1.75 -0.5)
			(stroke
				(width 0.05)
				(type solid)
			)
			(layer "F.CrtYd")
		)
		(fp_line
			(start -1.75 -0.5)
			(end -1.75 -1.4)
			(stroke
				(width 0.05)
				(type solid)
			)
			(layer "F.CrtYd")
		)
		(fp_line
			(start 1.75 -0.45)
			(end 1.75 0.45)
			(stroke
				(width 0.05)
				(type solid)
			)
			(layer "F.CrtYd")
		)
		(fp_line
			(start 0.825 -0.45)
			(end 1.75 -0.45)
			(stroke
				(width 0.05)
				(type solid)
			)
			(layer "F.CrtYd")
		)
		(fp_line
			(start 1.75 0.45)
			(end 0.85 0.45)
			(stroke
				(width 0.05)
				(type solid)
			)
			(layer "F.CrtYd")
		)
		(fp_line
			(start 0.85 0.45)
			(end 0.85 1.65)
			(stroke
				(width 0.05)
				(type solid)
			)
			(layer "F.CrtYd")
		)
		(fp_line
			(start -0.85 0.5)
			(end -0.85 -0.5)
			(stroke
				(width 0.05)
				(type solid)
			)
			(layer "F.CrtYd")
		)
		(fp_line
			(start -1.75 0.5)
			(end -0.85 0.5)
			(stroke
				(width 0.05)
				(type solid)
			)
			(layer "F.CrtYd")
		)
		(fp_line
			(start -0.85 1.4)
			(end -1.75 1.4)
			(stroke
				(width 0.05)
				(type solid)
			)
			(layer "F.CrtYd")
		)
		(fp_line
			(start -1.75 1.4)
			(end -1.75 0.5)
			(stroke
				(width 0.05)
				(type solid)
			)
			(layer "F.CrtYd")
		)
		(fp_line
			(start 0.85 1.65)
			(end -0.85 1.65)
			(stroke
				(width 0.05)
				(type solid)
			)
			(layer "F.CrtYd")
		)
		(fp_line
			(start -0.85 1.65)
			(end -0.85 1.4)
			(stroke
				(width 0.05)
				(type solid)
			)
			(layer "F.CrtYd")
		)
		(fp_line
			(start -0.437 -1.526)
			(end 0.688 -1.526)
			(stroke
				(width 0.15)
				(type solid)
			)
			(layer "F.Fab")
		)
		(fp_line
			(start -0.437 -1.526)
			(end -0.712 -1.325)
			(stroke
				(width 0.15)
				(type solid)
			)
			(layer "F.Fab")
		)
		(fp_line
			(start -0.712 -1.325)
			(end -0.712 1.523)
			(stroke
				(width 0.15)
				(type solid)
			)
			(layer "F.Fab")
		)
		(fp_line
			(start 0.688 1.519)
			(end 0.688 -1.52)
			(stroke
				(width 0.15)
				(type solid)
			)
			(layer "F.Fab")
		)
		(fp_line
			(start -0.712 1.519)
			(end 0.688 1.519)
			(stroke
				(width 0.15)
				(type solid)
			)
			(layer "F.Fab")
		)
		(pad "1" smd roundrect
			(at -1.1 -0.951 90)
			(size 1 0.6)
			(layers "F.Cu" "F.Mask" "F.Paste")
			(roundrect_rratio 0.15)
			(net 989 "Net-(Q14-B)")
			(pinfunction "B")
			(pintype "input")
			(teardrops
				(best_length_ratio 0.2)
				(max_length 1)
				(best_width_ratio 0.9)
				(max_width 2)
				(curved_edges yes)
				(filter_ratio 0.9)
				(enabled yes)
				(allow_two_segments yes)
				(prefer_zone_connections yes)
			)
		)
		(pad "2" smd roundrect
			(at -1.1 0.949 90)
			(size 1 0.6)
			(layers "F.Cu" "F.Mask" "F.Paste")
			(roundrect_rratio 0.15)
			(net 1 "GND")
			(pinfunction "E")
			(pintype "passive")
			(teardrops
				(best_length_ratio 0.2)
				(max_length 1)
				(best_width_ratio 0.9)
				(max_width 2)
				(curved_edges yes)
				(filter_ratio 0.9)
				(enabled yes)
				(allow_two_segments yes)
				(prefer_zone_connections yes)
			)
		)
		(pad "3" smd roundrect
			(at 1.1 -0.0005 90)
			(size 1 0.6)
			(layers "F.Cu" "F.Mask" "F.Paste")
			(roundrect_rratio 0.15)
			(net 990 "Net-(Q14-C)")
			(pinfunction "C")
			(pintype "passive")
			(teardrops
				(best_length_ratio 0.2)
				(max_length 1)
				(best_width_ratio 0.9)
				(max_width 2)
				(curved_edges yes)
				(filter_ratio 0.9)
				(enabled yes)
				(allow_two_segments yes)
				(prefer_zone_connections yes)
			)
		)
	)
	(footprint "antmicro-footprints:R_0402_1005Metric"
		(layer "F.Cu")
		(at 124.4 75.81 -90)
		(descr "Resistor SMD 0402")
		(tags "resistor SMD 0402")
		(property "Reference" "R74"
			(at -3 -0.45 90)
			(layer "F.SilkS")
			(effects
				(font
					(size 0.7 0.7)
					(thickness 0.15)
				)
				(justify right bottom)
			)
		)
		(property "Value" "R_0R_0402"
			(at -1.011843 1.772047 90)
			(layer "F.Fab")
			(effects
				(font
					(size 0.7 0.7)
					(thickness 0.15)
				)
				(justify right bottom)
			)
		)
		(property "Datasheet" "https://industrial.panasonic.com/cdbs/www-data/pdf/RDA0000/AOA0000C301.pdf"
			(at 0 0 270)
			(layer "F.Fab")
			(hide yes)
			(effects
				(font
					(size 1.27 1.27)
					(thickness 0.15)
				)
			)
		)
		(property "Author" "Antmicro"
			(at 48.59 200.21 0)
			(layer "F.Fab")
			(hide yes)
			(effects
				(font
					(size 1 1)
					(thickness 0.15)
				)
			)
		)
		(property "Current" "1A"
			(at 48.59 200.21 0)
			(layer "F.Fab")
			(hide yes)
			(effects
				(font
					(size 1 1)
					(thickness 0.15)
				)
			)
		)
		(property "License" "Apache-2.0"
			(at 48.59 200.21 0)
			(layer "F.Fab")
			(hide yes)
			(effects
				(font
					(size 1 1)
					(thickness 0.15)
				)
			)
		)
		(property "MPN" "ERJ2GE0R00X"
			(at 48.59 200.21 0)
			(layer "F.Fab")
			(hide yes)
			(effects
				(font
					(size 1 1)
					(thickness 0.15)
				)
			)
		)
		(property "Manufacturer" "Panasonic"
			(at 48.59 200.21 0)
			(layer "F.Fab")
			(hide yes)
			(effects
				(font
					(size 1 1)
					(thickness 0.15)
				)
			)
		)
		(property "Public" "False"
			(at 48.59 200.21 0)
			(layer "F.Fab")
			(hide yes)
			(effects
				(font
					(size 1 1)
					(thickness 0.15)
				)
			)
		)
		(property "Tolerance" ""
			(at 48.59 200.21 0)
			(layer "F.Fab")
			(hide yes)
			(effects
				(font
					(size 1 1)
					(thickness 0.15)
				)
			)
		)
		(property "Val" "0R"
			(at 48.59 200.21 0)
			(layer "F.Fab")
			(hide yes)
			(effects
				(font
					(size 1 1)
					(thickness 0.15)
				)
			)
		)
		(sheetname "USB-C console")
		(sheetfile "usb-c_console.kicad_sch")
		(attr smd)
		(fp_rect
			(start -0.925 -0.47)
			(end 0.925 0.47)
			(stroke
				(width 0.05)
				(type default)
			)
			(fill no)
			(layer "F.CrtYd")
		)
		(fp_rect
			(start -0.5 -0.25)
			(end 0.5 0.25)
			(stroke
				(width 0.15)
				(type solid)
			)
			(fill no)
			(layer "F.Fab")
		)
		(pad "1" smd roundrect
			(at -0.48 0 270)
			(size 0.59 0.64)
			(layers "F.Cu" "F.Mask" "F.Paste")
			(roundrect_rratio 0.25)
			(net 571 "Net-(U7-A_{1})")
			(pintype "passive")
			(teardrops
				(best_length_ratio 0.2)
				(max_length 1)
				(best_width_ratio 0.9)
				(max_width 2)
				(curved_edges yes)
				(filter_ratio 0.9)
				(enabled yes)
				(allow_two_segments yes)
				(prefer_zone_connections yes)
			)
		)
		(pad "2" smd roundrect
			(at 0.48 0 270)
			(size 0.59 0.64)
			(layers "F.Cu" "F.Mask" "F.Paste")
			(roundrect_rratio 0.25)
			(net 344 "/Com Express 7 MGMT/SER0.TX")
			(pintype "passive")
			(teardrops
				(best_length_ratio 0.2)
				(max_length 1)
				(best_width_ratio 0.9)
				(max_width 2)
				(curved_edges yes)
				(filter_ratio 0.9)
				(enabled yes)
				(allow_two_segments yes)
				(prefer_zone_connections yes)
			)
		)
	)
	(footprint "antmicro-footprints:C_0402_1005Metric"
		(layer "F.Cu")
		(at 304.14 126.79)
		(descr "Capacitor SMD 0402")
		(tags "capacitor SMD 0402")
		(property "Reference" "C55"
			(at 0.86 0.42 0)
			(layer "F.SilkS")
			(effects
				(font
					(size 0.7 0.7)
					(thickness 0.15)
				)
				(justify left bottom)
			)
		)
		(property "Value" "C_100n_0402"
			(at -1.022927 2.155213 0)
			(layer "F.Fab")
			(effects
				(font
					(size 0.7 0.7)
					(thickness 0.15)
				)
				(justify left bottom)
			)
		)
		(property "Datasheet" "https://www.murata.com/products/productdetail?partno=GRM155R61H104KE14%23"
			(at 0 0 0)
			(layer "F.Fab")
			(hide yes)
			(effects
				(font
					(size 1.27 1.27)
					(thickness 0.15)
				)
			)
		)
		(property "Author" "Antmicro"
			(at 0 0 0)
			(layer "F.Fab")
			(hide yes)
			(effects
				(font
					(size 1 1)
					(thickness 0.15)
				)
			)
		)
		(property "Dielectric" "X5R"
			(at 0 0 0)
			(layer "F.Fab")
			(hide yes)
			(effects
				(font
					(size 1 1)
					(thickness 0.15)
				)
			)
		)
		(property "License" "Apache-2.0"
			(at 0 0 0)
			(layer "F.Fab")
			(hide yes)
			(effects
				(font
					(size 1 1)
					(thickness 0.15)
				)
			)
		)
		(property "MPN" "GRM155R61H104KE14D"
			(at 0 0 0)
			(layer "F.Fab")
			(hide yes)
			(effects
				(font
					(size 1 1)
					(thickness 0.15)
				)
			)
		)
		(property "Manufacturer" "Murata"
			(at 0 0 0)
			(layer "F.Fab")
			(hide yes)
			(effects
				(font
					(size 1 1)
					(thickness 0.15)
				)
			)
		)
		(property "Public" "False"
			(at 0 0 0)
			(layer "F.Fab")
			(hide yes)
			(effects
				(font
					(size 1 1)
					(thickness 0.15)
				)
			)
		)
		(property "Val" "100n"
			(at 0 0 0)
			(layer "F.Fab")
			(hide yes)
			(effects
				(font
					(size 1 1)
					(thickness 0.15)
				)
			)
		)
		(property "Voltage" "50V"
			(at 0 0 0)
			(layer "F.Fab")
			(hide yes)
			(effects
				(font
					(size 1 1)
					(thickness 0.15)
				)
			)
		)
		(sheetname "Power")
		(sheetfile "power.kicad_sch")
		(attr smd)
		(fp_rect
			(start -0.925 -0.47)
			(end 0.925 0.47)
			(stroke
				(width 0.05)
				(type default)
			)
			(fill no)
			(layer "F.CrtYd")
		)
		(fp_line
			(start -0.494 -0.25)
			(end 0.504 -0.25)
			(stroke
				(width 0.15)
				(type solid)
			)
			(layer "F.Fab")
		)
		(fp_line
			(start -0.494 0.248)
			(end -0.494 -0.25)
			(stroke
				(width 0.15)
				(type solid)
			)
			(layer "F.Fab")
		)
		(fp_line
			(start 0.504 -0.25)
			(end 0.504 0.248)
			(stroke
				(width 0.15)
				(type solid)
			)
			(layer "F.Fab")
		)
		(fp_line
			(start 0.504 0.248)
			(end -0.494 0.248)
			(stroke
				(width 0.15)
				(type solid)
			)
			(layer "F.Fab")
		)
		(pad "1" smd roundrect
			(at -0.48 0)
			(size 0.59 0.64)
			(layers "F.Cu" "F.Mask" "F.Paste")
			(roundrect_rratio 0.25)
			(net 1 "GND")
			(pintype "passive")
			(teardrops
				(best_length_ratio 0.2)
				(max_length 1)
				(best_width_ratio 0.9)
				(max_width 2)
				(curved_edges yes)
				(filter_ratio 0.9)
				(enabled yes)
				(allow_two_segments yes)
				(prefer_zone_connections yes)
			)
		)
		(pad "2" smd roundrect
			(at 0.48 0)
			(size 0.59 0.64)
			(layers "F.Cu" "F.Mask" "F.Paste")
			(roundrect_rratio 0.25)
			(net 72 "Net-(U20-CT)")
			(pintype "passive")
			(teardrops
				(best_length_ratio 0.2)
				(max_length 1)
				(best_width_ratio 0.9)
				(max_width 2)
				(curved_edges yes)
				(filter_ratio 0.9)
				(enabled yes)
				(allow_two_segments yes)
				(prefer_zone_connections yes)
			)
		)
	)
	(footprint "antmicro-footprints:C_0402_1005Metric"
		(layer "F.Cu")
		(at 310.175 82.8 -90)
		(descr "Capacitor SMD 0402")
		(tags "capacitor SMD 0402")
		(property "Reference" "C110"
			(at -1.34 -1.325 90)
			(layer "F.SilkS")
			(effects
				(font
					(size 0.7 0.7)
					(thickness 0.15)
				)
				(justify right bottom)
			)
		)
		(property "Value" "C_100n_0402"
			(at -1.022927 2.155213 90)
			(layer "F.Fab")
			(effects
				(font
					(size 0.7 0.7)
					(thickness 0.15)
				)
				(justify right bottom)
			)
		)
		(property "Datasheet" "https://www.murata.com/products/productdetail?partno=GRM155R61H104KE14%23"
			(at 0 0 270)
			(layer "F.Fab")
			(hide yes)
			(effects
				(font
					(size 1.27 1.27)
					(thickness 0.15)
				)
			)
		)
		(property "Author" "Antmicro"
			(at 227.375 392.975 0)
			(layer "F.Fab")
			(hide yes)
			(effects
				(font
					(size 1 1)
					(thickness 0.15)
				)
			)
		)
		(property "Dielectric" "X5R"
			(at 227.375 392.975 0)
			(layer "F.Fab")
			(hide yes)
			(effects
				(font
					(size 1 1)
					(thickness 0.15)
				)
			)
		)
		(property "License" "Apache-2.0"
			(at 227.375 392.975 0)
			(layer "F.Fab")
			(hide yes)
			(effects
				(font
					(size 1 1)
					(thickness 0.15)
				)
			)
		)
		(property "MPN" "GRM155R61H104KE14D"
			(at 227.375 392.975 0)
			(layer "F.Fab")
			(hide yes)
			(effects
				(font
					(size 1 1)
					(thickness 0.15)
				)
			)
		)
		(property "Manufacturer" "Murata"
			(at 227.375 392.975 0)
			(layer "F.Fab")
			(hide yes)
			(effects
				(font
					(size 1 1)
					(thickness 0.15)
				)
			)
		)
		(property "Public" "False"
			(at 227.375 392.975 0)
			(layer "F.Fab")
			(hide yes)
			(effects
				(font
					(size 1 1)
					(thickness 0.15)
				)
			)
		)
		(property "Val" "100n"
			(at 227.375 392.975 0)
			(layer "F.Fab")
			(hide yes)
			(effects
				(font
					(size 1 1)
					(thickness 0.15)
				)
			)
		)
		(property "Voltage" "50V"
			(at 227.375 392.975 0)
			(layer "F.Fab")
			(hide yes)
			(effects
				(font
					(size 1 1)
					(thickness 0.15)
				)
			)
		)
		(sheetname "PCIe misc")
		(sheetfile "pcie_misc.kicad_sch")
		(attr smd)
		(fp_rect
			(start -0.925 -0.47)
			(end 0.925 0.47)
			(stroke
				(width 0.05)
				(type default)
			)
			(fill no)
			(layer "F.CrtYd")
		)
		(fp_line
			(start -0.494 0.248)
			(end -0.494 -0.25)
			(stroke
				(width 0.15)
				(type solid)
			)
			(layer "F.Fab")
		)
		(fp_line
			(start 0.504 0.248)
			(end -0.494 0.248)
			(stroke
				(width 0.15)
				(type solid)
			)
			(layer "F.Fab")
		)
		(fp_line
			(start -0.494 -0.25)
			(end 0.504 -0.25)
			(stroke
				(width 0.15)
				(type solid)
			)
			(layer "F.Fab")
		)
		(fp_line
			(start 0.504 -0.25)
			(end 0.504 0.248)
			(stroke
				(width 0.15)
				(type solid)
			)
			(layer "F.Fab")
		)
		(pad "1" smd roundrect
			(at -0.48 0 270)
			(size 0.59 0.64)
			(layers "F.Cu" "F.Mask" "F.Paste")
			(roundrect_rratio 0.25)
			(net 1 "GND")
			(pintype "passive")
			(teardrops
				(best_length_ratio 0.2)
				(max_length 1)
				(best_width_ratio 0.9)
				(max_width 2)
				(curved_edges yes)
				(filter_ratio 0.9)
				(enabled yes)
				(allow_two_segments yes)
				(prefer_zone_connections yes)
			)
		)
		(pad "2" smd roundrect
			(at 0.48 0 270)
			(size 0.59 0.64)
			(layers "F.Cu" "F.Mask" "F.Paste")
			(roundrect_rratio 0.25)
			(net 2 "+3V3")
			(pintype "passive")
			(teardrops
				(best_length_ratio 0.2)
				(max_length 1)
				(best_width_ratio 0.9)
				(max_width 2)
				(curved_edges yes)
				(filter_ratio 0.9)
				(enabled yes)
				(allow_two_segments yes)
				(prefer_zone_connections yes)
			)
		)
	)
	(footprint "antmicro-footprints:VSSOP-8_2.3x2mm_P0.5mm"
		(layer "F.Cu")
		(at 308.5 153.81 90)
		(property "Reference" "U30"
			(at -1.05 2.25 90)
			(layer "F.SilkS")
			(effects
				(font
					(size 0.7 0.7)
					(thickness 0.15)
				)
				(justify left bottom)
			)
		)
		(property "Value" "74AUP2G132"
			(at 0 2.258 90)
			(layer "F.Fab")
			(effects
				(font
					(size 0.7 0.7)
					(thickness 0.15)
				)
				(justify left bottom)
			)
		)
		(property "Datasheet" "https://assets.nexperia.com/documents/data-sheet/74AUP2G132.pdf"
			(at 0 0 90)
			(layer "F.Fab")
			(hide yes)
			(effects
				(font
					(size 1.27 1.27)
					(thickness 0.15)
				)
			)
		)
		(property "Author" "Antmicro"
			(at 462.31 -154.69 0)
			(layer "F.Fab")
			(hide yes)
			(effects
				(font
					(size 1 1)
					(thickness 0.15)
				)
			)
		)
		(property "License" "Apache-2.0"
			(at 462.31 -154.69 0)
			(layer "F.Fab")
			(hide yes)
			(effects
				(font
					(size 1 1)
					(thickness 0.15)
				)
			)
		)
		(property "MPN" "74AUP2G132"
			(at 462.31 -154.69 0)
			(layer "F.Fab")
			(hide yes)
			(effects
				(font
					(size 1 1)
					(thickness 0.15)
				)
			)
		)
		(property "Manufacturer" "Nexperia"
			(at 462.31 -154.69 0)
			(layer "F.Fab")
			(hide yes)
			(effects
				(font
					(size 1 1)
					(thickness 0.15)
				)
			)
		)
		(sheetname "Com Express 7 MGMT")
		(sheetfile "com_express_7_mgmt.kicad_sch")
		(attr smd)
		(fp_line
			(start -0.82 -0.992)
			(end 0.825 -0.992)
			(stroke
				(width 0.15)
				(type solid)
			)
			(layer "F.SilkS")
		)
		(fp_line
			(start 0.825 1.007)
			(end -0.82 1.007)
			(stroke
				(width 0.15)
				(type solid)
			)
			(layer "F.SilkS")
		)
		(fp_circle
			(center -1.402 -1.192)
			(end -1.352 -1.192)
			(stroke
				(width 0.15)
				(type solid)
			)
			(fill yes)
			(layer "F.SilkS")
		)
		(fp_rect
			(start 1.8 1.35)
			(end -1.8 -1.35)
			(stroke
				(width 0.05)
				(type solid)
			)
			(fill no)
			(layer "F.CrtYd")
		)
		(fp_line
			(start -0.7 -0.99)
			(end -1.14 -0.55)
			(stroke
				(width 0.15)
				(type solid)
			)
			(layer "F.Fab")
		)
		(fp_rect
			(start -1.147 -0.992)
			(end 1.151 1.007)
			(stroke
				(width 0.15)
				(type solid)
			)
			(fill no)
			(layer "F.Fab")
		)
		(pad "1" smd rect
			(at -1.372 -0.742 90)
			(size 0.75 0.4)
			(layers "F.Cu" "F.Mask" "F.Paste")
			(net 382 "Net-(J12D-~{CB_RESET})")
			(pinfunction "1A")
			(pintype "input")
			(teardrops
				(best_length_ratio 0.2)
				(max_length 1)
				(best_width_ratio 0.9)
				(max_width 2)
				(curved_edges yes)
				(filter_ratio 0.9)
				(enabled yes)
				(allow_two_segments yes)
				(prefer_zone_connections yes)
			)
		)
		(pad "2" smd rect
			(at -1.372 -0.244 90)
			(size 0.75 0.3)
			(layers "F.Cu" "F.Mask" "F.Paste")
			(net 382 "Net-(J12D-~{CB_RESET})")
			(pinfunction "1B")
			(pintype "input")
			(teardrops
				(best_length_ratio 0.2)
				(max_length 1)
				(best_width_ratio 0.9)
				(max_width 2)
				(curved_edges yes)
				(filter_ratio 0.9)
				(enabled yes)
				(allow_two_segments yes)
				(prefer_zone_connections yes)
			)
		)
		(pad "3" smd rect
			(at -1.372 0.256 90)
			(size 0.75 0.3)
			(layers "F.Cu" "F.Mask" "F.Paste")
			(net 528 "/Backplane/~{PERST}")
			(pinfunction "2Y")
			(pintype "output")
			(teardrops
				(best_length_ratio 0.2)
				(max_length 1)
				(best_width_ratio 0.9)
				(max_width 2)
				(curved_edges yes)
				(filter_ratio 0.9)
				(enabled yes)
				(allow_two_segments yes)
				(prefer_zone_connections yes)
			)
		)
		(pad "4" smd rect
			(at -1.372 0.757 90)
			(size 0.75 0.4)
			(layers "F.Cu" "F.Mask" "F.Paste")
			(net 1 "GND")
			(pinfunction "GND")
			(pintype "power_in")
			(teardrops
				(best_length_ratio 0.2)
				(max_length 1)
				(best_width_ratio 0.9)
				(max_width 2)
				(curved_edges yes)
				(filter_ratio 0.9)
				(enabled yes)
				(allow_two_segments yes)
				(prefer_zone_connections yes)
			)
		)
		(pad "5" smd rect
			(at 1.377 0.757 90)
			(size 0.75 0.4)
			(layers "F.Cu" "F.Mask" "F.Paste")
			(net 784 "Net-(U30-1Y)")
			(pinfunction "2A")
			(pintype "input")
			(teardrops
				(best_length_ratio 0.2)
				(max_length 1)
				(best_width_ratio 0.9)
				(max_width 2)
				(curved_edges yes)
				(filter_ratio 0.9)
				(enabled yes)
				(allow_two_segments yes)
				(prefer_zone_connections yes)
			)
		)
		(pad "6" smd rect
			(at 1.377 0.256 90)
			(size 0.75 0.3)
			(layers "F.Cu" "F.Mask" "F.Paste")
			(net 784 "Net-(U30-1Y)")
			(pinfunction "2B")
			(pintype "input")
			(teardrops
				(best_length_ratio 0.2)
				(max_length 1)
				(best_width_ratio 0.9)
				(max_width 2)
				(curved_edges yes)
				(filter_ratio 0.9)
				(enabled yes)
				(allow_two_segments yes)
				(prefer_zone_connections yes)
			)
		)
		(pad "7" smd rect
			(at 1.377 -0.244 90)
			(size 0.75 0.3)
			(layers "F.Cu" "F.Mask" "F.Paste")
			(net 784 "Net-(U30-1Y)")
			(pinfunction "1Y")
			(pintype "output")
			(teardrops
				(best_length_ratio 0.2)
				(max_length 1)
				(best_width_ratio 0.9)
				(max_width 2)
				(curved_edges yes)
				(filter_ratio 0.9)
				(enabled yes)
				(allow_two_segments yes)
				(prefer_zone_connections yes)
			)
		)
		(pad "8" smd rect
			(at 1.377 -0.742 90)
			(size 0.75 0.4)
			(layers "F.Cu" "F.Mask" "F.Paste")
			(net 73 "+3V3_AON")
			(pinfunction "VCC")
			(pintype "power_in")
			(teardrops
				(best_length_ratio 0.2)
				(max_length 1)
				(best_width_ratio 0.9)
				(max_width 2)
				(curved_edges yes)
				(filter_ratio 0.9)
				(enabled yes)
				(allow_two_segments yes)
				(prefer_zone_connections yes)
			)
		)
	)
	(footprint "antmicro-footprints:R_0402_1005Metric"
		(layer "F.Cu")
		(at 188.70861 77.152163 90)
		(descr "Resistor SMD 0402")
		(tags "resistor SMD 0402")
		(property "Reference" "R326"
			(at -1.9 -0.5 90)
			(layer "F.SilkS")
			(effects
				(font
					(size 0.7 0.7)
					(thickness 0.15)
				)
				(justify left bottom)
			)
		)
		(property "Value" "R_470R_0402"
			(at -1.011843 1.772047 90)
			(layer "F.Fab")
			(effects
				(font
					(size 0.7 0.7)
					(thickness 0.15)
				)
				(justify left bottom)
			)
		)
		(property "Datasheet" "https://www.bourns.com/docs/product-datasheets/cr.pdf"
			(at 0 0 90)
			(layer "F.Fab")
			(hide yes)
			(effects
				(font
					(size 1.27 1.27)
					(thickness 0.15)
				)
			)
		)
		(property "Author" "Antmicro"
			(at 265.860773 -111.556447 0)
			(layer "F.Fab")
			(hide yes)
			(effects
				(font
					(size 1 1)
					(thickness 0.15)
				)
			)
		)
		(property "License" "Apache-2.0"
			(at 265.860773 -111.556447 0)
			(layer "F.Fab")
			(hide yes)
			(effects
				(font
					(size 1 1)
					(thickness 0.15)
				)
			)
		)
		(property "MPN" "CR0402-FX-4700GLF"
			(at 265.860773 -111.556447 0)
			(layer "F.Fab")
			(hide yes)
			(effects
				(font
					(size 1 1)
					(thickness 0.15)
				)
			)
		)
		(property "Manufacturer" "Bourns"
			(at 265.860773 -111.556447 0)
			(layer "F.Fab")
			(hide yes)
			(effects
				(font
					(size 1 1)
					(thickness 0.15)
				)
			)
		)
		(property "Tolerance" "1%"
			(at 265.860773 -111.556447 0)
			(layer "F.Fab")
			(hide yes)
			(effects
				(font
					(size 1 1)
					(thickness 0.15)
				)
			)
		)
		(property "Val" "470R"
			(at 265.860773 -111.556447 0)
			(layer "F.Fab")
			(hide yes)
			(effects
				(font
					(size 1 1)
					(thickness 0.15)
				)
			)
		)
		(sheetname "Power")
		(sheetfile "power.kicad_sch")
		(attr smd)
		(fp_rect
			(start -0.925 -0.47)
			(end 0.925 0.47)
			(stroke
				(width 0.05)
				(type default)
			)
			(fill no)
			(layer "F.CrtYd")
		)
		(fp_rect
			(start -0.5 -0.25)
			(end 0.5 0.25)
			(stroke
				(width 0.15)
				(type solid)
			)
			(fill no)
			(layer "F.Fab")
		)
		(pad "1" smd roundrect
			(at -0.48 0 90)
			(size 0.59 0.64)
			(layers "F.Cu" "F.Mask" "F.Paste")
			(roundrect_rratio 0.25)
			(net 1 "GND")
			(pintype "passive")
			(teardrops
				(best_length_ratio 0.2)
				(max_length 1)
				(best_width_ratio 0.9)
				(max_width 2)
				(curved_edges yes)
				(filter_ratio 0.9)
				(enabled yes)
				(allow_two_segments yes)
				(prefer_zone_connections yes)
			)
		)
		(pad "2" smd roundrect
			(at 0.48 0 90)
			(size 0.59 0.64)
			(layers "F.Cu" "F.Mask" "F.Paste")
			(roundrect_rratio 0.25)
			(net 985 "Net-(D33-C)")
			(pintype "passive")
			(teardrops
				(best_length_ratio 0.2)
				(max_length 1)
				(best_width_ratio 0.9)
				(max_width 2)
				(curved_edges yes)
				(filter_ratio 0.9)
				(enabled yes)
				(allow_two_segments yes)
				(prefer_zone_connections yes)
			)
		)
	)
	(footprint "antmicro-footprints:R_0402_1005Metric"
		(layer "F.Cu")
		(at 132.9 81.760001 -90)
		(descr "Resistor SMD 0402")
		(tags "resistor SMD 0402")
		(property "Reference" "R234"
			(at -3.650001 -0.45 90)
			(layer "F.SilkS")
			(effects
				(font
					(size 0.7 0.7)
					(thickness 0.15)
				)
				(justify right bottom)
			)
		)
		(property "Value" "R_0R_0402"
			(at -1.011843 1.772047 90)
			(layer "F.Fab")
			(effects
				(font
					(size 0.7 0.7)
					(thickness 0.15)
				)
				(justify right bottom)
			)
		)
		(property "Datasheet" "https://industrial.panasonic.com/cdbs/www-data/pdf/RDA0000/AOA0000C301.pdf"
			(at 0 0 270)
			(layer "F.Fab")
			(hide yes)
			(effects
				(font
					(size 1.27 1.27)
					(thickness 0.15)
				)
			)
		)
		(property "Author" "Antmicro"
			(at 51.139999 214.660001 0)
			(layer "F.Fab")
			(hide yes)
			(effects
				(font
					(size 1 1)
					(thickness 0.15)
				)
			)
		)
		(property "Current" "1A"
			(at 51.139999 214.660001 0)
			(layer "F.Fab")
			(hide yes)
			(effects
				(font
					(size 1 1)
					(thickness 0.15)
				)
			)
		)
		(property "License" "Apache-2.0"
			(at 51.139999 214.660001 0)
			(layer "F.Fab")
			(hide yes)
			(effects
				(font
					(size 1 1)
					(thickness 0.15)
				)
			)
		)
		(property "MPN" "ERJ2GE0R00X"
			(at 51.139999 214.660001 0)
			(layer "F.Fab")
			(hide yes)
			(effects
				(font
					(size 1 1)
					(thickness 0.15)
				)
			)
		)
		(property "Manufacturer" "Panasonic"
			(at 51.139999 214.660001 0)
			(layer "F.Fab")
			(hide yes)
			(effects
				(font
					(size 1 1)
					(thickness 0.15)
				)
			)
		)
		(property "Public" "False"
			(at 51.139999 214.660001 0)
			(layer "F.Fab")
			(hide yes)
			(effects
				(font
					(size 1 1)
					(thickness 0.15)
				)
			)
		)
		(property "Tolerance" ""
			(at 51.139999 214.660001 0)
			(layer "F.Fab")
			(hide yes)
			(effects
				(font
					(size 1 1)
					(thickness 0.15)
				)
			)
		)
		(property "Val" "0R"
			(at 51.139999 214.660001 0)
			(layer "F.Fab")
			(hide yes)
			(effects
				(font
					(size 1 1)
					(thickness 0.15)
				)
			)
		)
		(sheetname "GPIO expander")
		(sheetfile "gpio_exp.kicad_sch")
		(attr smd)
		(fp_rect
			(start -0.925 -0.47)
			(end 0.925 0.47)
			(stroke
				(width 0.05)
				(type default)
			)
			(fill no)
			(layer "F.CrtYd")
		)
		(fp_rect
			(start -0.5 -0.25)
			(end 0.5 0.25)
			(stroke
				(width 0.15)
				(type solid)
			)
			(fill no)
			(layer "F.Fab")
		)
		(pad "1" smd roundrect
			(at -0.48 0 270)
			(size 0.59 0.64)
			(layers "F.Cu" "F.Mask" "F.Paste")
			(roundrect_rratio 0.25)
			(net 357 "/Com Express 7 MGMT/SMBus.SCL")
			(pintype "passive")
			(teardrops
				(best_length_ratio 0.2)
				(max_length 1)
				(best_width_ratio 0.9)
				(max_width 2)
				(curved_edges yes)
				(filter_ratio 0.9)
				(enabled yes)
				(allow_two_segments yes)
				(prefer_zone_connections yes)
			)
		)
		(pad "2" smd roundrect
			(at 0.48 0 270)
			(size 0.59 0.64)
			(layers "F.Cu" "F.Mask" "F.Paste")
			(roundrect_rratio 0.25)
			(net 635 "Net-(U41-SCL)")
			(pintype "passive")
			(teardrops
				(best_length_ratio 0.2)
				(max_length 1)
				(best_width_ratio 0.9)
				(max_width 2)
				(curved_edges yes)
				(filter_ratio 0.9)
				(enabled yes)
				(allow_two_segments yes)
				(prefer_zone_connections yes)
			)
		)
	)
	(footprint "antmicro-footprints:R_0402_1005Metric"
		(layer "F.Cu")
		(at 251.625 132.36 90)
		(descr "Resistor SMD 0402")
		(tags "resistor SMD 0402")
		(property "Reference" "R167"
			(at -6.75 0.475 90)
			(layer "F.SilkS")
			(effects
				(font
					(size 0.7 0.7)
					(thickness 0.15)
				)
				(justify left bottom)
			)
		)
		(property "Value" "R_10k_0402"
			(at -1.011843 1.772047 90)
			(layer "F.Fab")
			(effects
				(font
					(size 0.7 0.7)
					(thickness 0.15)
				)
				(justify left bottom)
			)
		)
		(property "Datasheet" "https://www.bourns.com/docs/product-datasheets/cr.pdf"
			(at 0 0 90)
			(layer "F.Fab")
			(hide yes)
			(effects
				(font
					(size 1.27 1.27)
					(thickness 0.15)
				)
			)
		)
		(property "Author" "Antmicro"
			(at 383.985 -119.265 0)
			(layer "F.Fab")
			(hide yes)
			(effects
				(font
					(size 1 1)
					(thickness 0.15)
				)
			)
		)
		(property "License" "Apache-2.0"
			(at 383.985 -119.265 0)
			(layer "F.Fab")
			(hide yes)
			(effects
				(font
					(size 1 1)
					(thickness 0.15)
				)
			)
		)
		(property "MPN" "CR0402-FX-1002GLF"
			(at 383.985 -119.265 0)
			(layer "F.Fab")
			(hide yes)
			(effects
				(font
					(size 1 1)
					(thickness 0.15)
				)
			)
		)
		(property "Manufacturer" "Bourns"
			(at 383.985 -119.265 0)
			(layer "F.Fab")
			(hide yes)
			(effects
				(font
					(size 1 1)
					(thickness 0.15)
				)
			)
		)
		(property "Public" "False"
			(at 383.985 -119.265 0)
			(layer "F.Fab")
			(hide yes)
			(effects
				(font
					(size 1 1)
					(thickness 0.15)
				)
			)
		)
		(property "Tolerance" "1%"
			(at 383.985 -119.265 0)
			(layer "F.Fab")
			(hide yes)
			(effects
				(font
					(size 1 1)
					(thickness 0.15)
				)
			)
		)
		(property "Val" "10k"
			(at 383.985 -119.265 0)
			(layer "F.Fab")
			(hide yes)
			(effects
				(font
					(size 1 1)
					(thickness 0.15)
				)
			)
		)
		(sheetname "Com Express 7 MGMT")
		(sheetfile "com_express_7_mgmt.kicad_sch")
		(attr smd)
		(fp_rect
			(start -0.925 -0.47)
			(end 0.925 0.47)
			(stroke
				(width 0.05)
				(type default)
			)
			(fill no)
			(layer "F.CrtYd")
		)
		(fp_rect
			(start -0.5 -0.25)
			(end 0.5 0.25)
			(stroke
				(width 0.15)
				(type solid)
			)
			(fill no)
			(layer "F.Fab")
		)
		(pad "1" smd roundrect
			(at -0.48 0 90)
			(size 0.59 0.64)
			(layers "F.Cu" "F.Mask" "F.Paste")
			(roundrect_rratio 0.25)
			(net 136 "/Com Express 7 MGMT/~{TYPE0}")
			(pintype "passive")
			(teardrops
				(best_length_ratio 0.2)
				(max_length 1)
				(best_width_ratio 0.9)
				(max_width 2)
				(curved_edges yes)
				(filter_ratio 0.9)
				(enabled yes)
				(allow_two_segments yes)
				(prefer_zone_connections yes)
			)
		)
		(pad "2" smd roundrect
			(at 0.48 0 90)
			(size 0.59 0.64)
			(layers "F.Cu" "F.Mask" "F.Paste")
			(roundrect_rratio 0.25)
			(net 73 "+3V3_AON")
			(pintype "passive")
			(teardrops
				(best_length_ratio 0.2)
				(max_length 1)
				(best_width_ratio 0.9)
				(max_width 2)
				(curved_edges yes)
				(filter_ratio 0.9)
				(enabled yes)
				(allow_two_segments yes)
				(prefer_zone_connections yes)
			)
		)
	)
	(footprint "antmicro-footprints:R_0402_1005Metric"
		(layer "F.Cu")
		(at 247.825 132.36 90)
		(descr "Resistor SMD 0402")
		(tags "resistor SMD 0402")
		(property "Reference" "R168"
			(at -3.7 0.425 90)
			(layer "F.SilkS")
			(effects
				(font
					(size 0.7 0.7)
					(thickness 0.15)
				)
				(justify left bottom)
			)
		)
		(property "Value" "R_10k_0402"
			(at -1.011843 1.772047 90)
			(layer "F.Fab")
			(effects
				(font
					(size 0.7 0.7)
					(thickness 0.15)
				)
				(justify left bottom)
			)
		)
		(property "Datasheet" "https://www.bourns.com/docs/product-datasheets/cr.pdf"
			(at 0 0 90)
			(layer "F.Fab")
			(hide yes)
			(effects
				(font
					(size 1.27 1.27)
					(thickness 0.15)
				)
			)
		)
		(property "Author" "Antmicro"
			(at 380.185 -115.465 0)
			(layer "F.Fab")
			(hide yes)
			(effects
				(font
					(size 1 1)
					(thickness 0.15)
				)
			)
		)
		(property "License" "Apache-2.0"
			(at 380.185 -115.465 0)
			(layer "F.Fab")
			(hide yes)
			(effects
				(font
					(size 1 1)
					(thickness 0.15)
				)
			)
		)
		(property "MPN" "CR0402-FX-1002GLF"
			(at 380.185 -115.465 0)
			(layer "F.Fab")
			(hide yes)
			(effects
				(font
					(size 1 1)
					(thickness 0.15)
				)
			)
		)
		(property "Manufacturer" "Bourns"
			(at 380.185 -115.465 0)
			(layer "F.Fab")
			(hide yes)
			(effects
				(font
					(size 1 1)
					(thickness 0.15)
				)
			)
		)
		(property "Public" "False"
			(at 380.185 -115.465 0)
			(layer "F.Fab")
			(hide yes)
			(effects
				(font
					(size 1 1)
					(thickness 0.15)
				)
			)
		)
		(property "Tolerance" "1%"
			(at 380.185 -115.465 0)
			(layer "F.Fab")
			(hide yes)
			(effects
				(font
					(size 1 1)
					(thickness 0.15)
				)
			)
		)
		(property "Val" "10k"
			(at 380.185 -115.465 0)
			(layer "F.Fab")
			(hide yes)
			(effects
				(font
					(size 1 1)
					(thickness 0.15)
				)
			)
		)
		(sheetname "Com Express 7 MGMT")
		(sheetfile "com_express_7_mgmt.kicad_sch")
		(attr smd)
		(fp_rect
			(start -0.925 -0.47)
			(end 0.925 0.47)
			(stroke
				(width 0.05)
				(type default)
			)
			(fill no)
			(layer "F.CrtYd")
		)
		(fp_rect
			(start -0.5 -0.25)
			(end 0.5 0.25)
			(stroke
				(width 0.15)
				(type solid)
			)
			(fill no)
			(layer "F.Fab")
		)
		(pad "1" smd roundrect
			(at -0.48 0 90)
			(size 0.59 0.64)
			(layers "F.Cu" "F.Mask" "F.Paste")
			(roundrect_rratio 0.25)
			(net 434 "/Com Express 7 MGMT/~{TYPE1}")
			(pintype "passive")
			(teardrops
				(best_length_ratio 0.2)
				(max_length 1)
				(best_width_ratio 0.9)
				(max_width 2)
				(curved_edges yes)
				(filter_ratio 0.9)
				(enabled yes)
				(allow_two_segments yes)
				(prefer_zone_connections yes)
			)
		)
		(pad "2" smd roundrect
			(at 0.48 0 90)
			(size 0.59 0.64)
			(layers "F.Cu" "F.Mask" "F.Paste")
			(roundrect_rratio 0.25)
			(net 73 "+3V3_AON")
			(pintype "passive")
			(teardrops
				(best_length_ratio 0.2)
				(max_length 1)
				(best_width_ratio 0.9)
				(max_width 2)
				(curved_edges yes)
				(filter_ratio 0.9)
				(enabled yes)
				(allow_two_segments yes)
				(prefer_zone_connections yes)
			)
		)
	)
	(footprint "antmicro-footprints:TP_SMD_0.75mm"
		(layer "F.Cu")
		(at 151.8 128.71)
		(property "Reference" "TP60"
			(at 0.4 -3.3 90)
			(layer "F.SilkS")
			(effects
				(font
					(size 0.7 0.7)
					(thickness 0.15)
				)
				(justify left bottom)
			)
		)
		(property "Value" "TP_0.75mm_SMD"
			(at 0 1.2 0)
			(layer "F.Fab")
			(effects
				(font
					(size 0.7 0.7)
					(thickness 0.15)
				)
				(justify left bottom)
			)
		)
		(property "Author" "Antmicro"
			(at 0 0 0)
			(layer "F.Fab")
			(hide yes)
			(effects
				(font
					(size 1 1)
					(thickness 0.15)
				)
			)
		)
		(property "License" "Apache-2.0"
			(at 0 0 0)
			(layer "F.Fab")
			(hide yes)
			(effects
				(font
					(size 1 1)
					(thickness 0.15)
				)
			)
		)
		(property "MPN" ""
			(at 0 0 0)
			(layer "F.Fab")
			(hide yes)
			(effects
				(font
					(size 1 1)
					(thickness 0.15)
				)
			)
		)
		(property "Manufacturer" ""
			(at 0 0 0)
			(layer "F.Fab")
			(hide yes)
			(effects
				(font
					(size 1 1)
					(thickness 0.15)
				)
			)
		)
		(property "Public" "False"
			(at 0 0 0)
			(layer "F.Fab")
			(hide yes)
			(effects
				(font
					(size 1 1)
					(thickness 0.15)
				)
			)
		)
		(sheetname "KR to SFI #1")
		(sheetfile "kr_sfi.kicad_sch")
		(attr exclude_from_pos_files exclude_from_bom)
		(fp_circle
			(center 0 0)
			(end 0.475 0)
			(stroke
				(width 0.05)
				(type default)
			)
			(fill no)
			(layer "F.CrtYd")
		)
		(pad "1" smd circle
			(at 0 0)
			(size 0.75 0.75)
			(layers "F.Cu" "F.Mask")
			(net 723 "/2xSFP+/KR to SFI #1/TDO")
			(pinfunction "1")
			(pintype "passive")
			(teardrops
				(best_length_ratio 0.4)
				(max_length 1)
				(best_width_ratio 0.9)
				(max_width 2)
				(curved_edges yes)
				(filter_ratio 0.9)
				(enabled yes)
				(allow_two_segments yes)
				(prefer_zone_connections yes)
			)
		)
	)
	(footprint "antmicro-footprints:VSSOP-8_2.3x2mm_P0.5mm"
		(layer "F.Cu")
		(at 308.275 81.91 -90)
		(property "Reference" "U38"
			(at 2.8 -1.125 180)
			(layer "F.SilkS")
			(effects
				(font
					(size 0.7 0.7)
					(thickness 0.15)
				)
				(justify right bottom)
			)
		)
		(property "Value" "74AUP2G132"
			(at 0 2.258 90)
			(layer "F.Fab")
			(effects
				(font
					(size 0.7 0.7)
					(thickness 0.15)
				)
				(justify right bottom)
			)
		)
		(property "Datasheet" "https://assets.nexperia.com/documents/data-sheet/74AUP2G132.pdf"
			(at 0 0 270)
			(layer "F.Fab")
			(hide yes)
			(effects
				(font
					(size 1.27 1.27)
					(thickness 0.15)
				)
			)
		)
		(property "Author" "Antmicro"
			(at 226.365 390.185 0)
			(layer "F.Fab")
			(hide yes)
			(effects
				(font
					(size 1 1)
					(thickness 0.15)
				)
			)
		)
		(property "License" "Apache-2.0"
			(at 226.365 390.185 0)
			(layer "F.Fab")
			(hide yes)
			(effects
				(font
					(size 1 1)
					(thickness 0.15)
				)
			)
		)
		(property "MPN" "74AUP2G132"
			(at 226.365 390.185 0)
			(layer "F.Fab")
			(hide yes)
			(effects
				(font
					(size 1 1)
					(thickness 0.15)
				)
			)
		)
		(property "Manufacturer" "Nexperia"
			(at 226.365 390.185 0)
			(layer "F.Fab")
			(hide yes)
			(effects
				(font
					(size 1 1)
					(thickness 0.15)
				)
			)
		)
		(sheetname "PCIe misc")
		(sheetfile "pcie_misc.kicad_sch")
		(attr smd)
		(fp_line
			(start 0.825 1.007)
			(end -0.82 1.007)
			(stroke
				(width 0.15)
				(type solid)
			)
			(layer "F.SilkS")
		)
		(fp_line
			(start -0.82 -0.992)
			(end 0.825 -0.992)
			(stroke
				(width 0.15)
				(type solid)
			)
			(layer "F.SilkS")
		)
		(fp_circle
			(center -1.402 -1.192)
			(end -1.352 -1.192)
			(stroke
				(width 0.15)
				(type solid)
			)
			(fill yes)
			(layer "F.SilkS")
		)
		(fp_rect
			(start 1.8 1.35)
			(end -1.8 -1.35)
			(stroke
				(width 0.05)
				(type solid)
			)
			(fill no)
			(layer "F.CrtYd")
		)
		(fp_line
			(start -0.7 -0.99)
			(end -1.14 -0.55)
			(stroke
				(width 0.15)
				(type solid)
			)
			(layer "F.Fab")
		)
		(fp_rect
			(start -1.147 -0.992)
			(end 1.151 1.007)
			(stroke
				(width 0.15)
				(type solid)
			)
			(fill no)
			(layer "F.Fab")
		)
		(pad "1" smd rect
			(at -1.372 -0.742 270)
			(size 0.75 0.4)
			(layers "F.Cu" "F.Mask" "F.Paste")
			(net 790 "Net-(U38-1A)")
			(pinfunction "1A")
			(pintype "input")
			(teardrops
				(best_length_ratio 0.2)
				(max_length 1)
				(best_width_ratio 0.9)
				(max_width 2)
				(curved_edges yes)
				(filter_ratio 0.9)
				(enabled yes)
				(allow_two_segments yes)
				(prefer_zone_connections yes)
			)
		)
		(pad "2" smd rect
			(at -1.372 -0.244 270)
			(size 0.75 0.3)
			(layers "F.Cu" "F.Mask" "F.Paste")
			(net 790 "Net-(U38-1A)")
			(pinfunction "1B")
			(pintype "input")
			(teardrops
				(best_length_ratio 0.2)
				(max_length 1)
				(best_width_ratio 0.9)
				(max_width 2)
				(curved_edges yes)
				(filter_ratio 0.9)
				(enabled yes)
				(allow_two_segments yes)
				(prefer_zone_connections yes)
			)
		)
		(pad "3" smd rect
			(at -1.372 0.256 270)
			(size 0.75 0.3)
			(layers "F.Cu" "F.Mask" "F.Paste")
			(net 791 "unconnected-(U38-2Y-Pad3)")
			(pinfunction "2Y")
			(pintype "output+no_connect")
			(teardrops
				(best_length_ratio 0.2)
				(max_length 1)
				(best_width_ratio 0.9)
				(max_width 2)
				(curved_edges yes)
				(filter_ratio 0.9)
				(enabled yes)
				(allow_two_segments yes)
				(prefer_zone_connections yes)
			)
		)
		(pad "4" smd rect
			(at -1.372 0.757 270)
			(size 0.75 0.4)
			(layers "F.Cu" "F.Mask" "F.Paste")
			(net 1 "GND")
			(pinfunction "GND")
			(pintype "power_in")
			(teardrops
				(best_length_ratio 0.2)
				(max_length 1)
				(best_width_ratio 0.9)
				(max_width 2)
				(curved_edges yes)
				(filter_ratio 0.9)
				(enabled yes)
				(allow_two_segments yes)
				(prefer_zone_connections yes)
			)
		)
		(pad "5" smd rect
			(at 1.377 0.757 270)
			(size 0.75 0.4)
			(layers "F.Cu" "F.Mask" "F.Paste")
			(net 1 "GND")
			(pinfunction "2A")
			(pintype "input")
			(teardrops
				(best_length_ratio 0.2)
				(max_length 1)
				(best_width_ratio 0.9)
				(max_width 2)
				(curved_edges yes)
				(filter_ratio 0.9)
				(enabled yes)
				(allow_two_segments yes)
				(prefer_zone_connections yes)
			)
		)
		(pad "6" smd rect
			(at 1.377 0.256 270)
			(size 0.75 0.3)
			(layers "F.Cu" "F.Mask" "F.Paste")
			(net 1 "GND")
			(pinfunction "2B")
			(pintype "input")
			(teardrops
				(best_length_ratio 0.2)
				(max_length 1)
				(best_width_ratio 0.9)
				(max_width 2)
				(curved_edges yes)
				(filter_ratio 0.9)
				(enabled yes)
				(allow_two_segments yes)
				(prefer_zone_connections yes)
			)
		)
		(pad "7" smd rect
			(at 1.377 -0.244 270)
			(size 0.75 0.3)
			(layers "F.Cu" "F.Mask" "F.Paste")
			(net 587 "/M.2 key E/SUSCLK")
			(pinfunction "1Y")
			(pintype "output")
			(teardrops
				(best_length_ratio 0.2)
				(max_length 1)
				(best_width_ratio 0.9)
				(max_width 2)
				(curved_edges yes)
				(filter_ratio 0.9)
				(enabled yes)
				(allow_two_segments yes)
				(prefer_zone_connections yes)
			)
		)
		(pad "8" smd rect
			(at 1.377 -0.742 270)
			(size 0.75 0.4)
			(layers "F.Cu" "F.Mask" "F.Paste")
			(net 2 "+3V3")
			(pinfunction "VCC")
			(pintype "power_in")
			(teardrops
				(best_length_ratio 0.2)
				(max_length 1)
				(best_width_ratio 0.9)
				(max_width 2)
				(curved_edges yes)
				(filter_ratio 0.9)
				(enabled yes)
				(allow_two_segments yes)
				(prefer_zone_connections yes)
			)
		)
	)
	(footprint "antmicro-footprints:TP_SMD_0.75mm"
		(layer "F.Cu")
		(at 201.70861 72.802163 -90)
		(property "Reference" "TP100"
			(at 0 -0.6 90)
			(layer "F.SilkS")
			(hide yes)
			(effects
				(font
					(size 0.7 0.7)
					(thickness 0.15)
				)
				(justify right bottom)
			)
		)
		(property "Value" "TP_0.75mm_SMD"
			(at 0 1.2 90)
			(layer "F.Fab")
			(effects
				(font
					(size 0.7 0.7)
					(thickness 0.15)
				)
				(justify right bottom)
			)
		)
		(property "Author" "Antmicro"
			(at 128.906447 274.510773 0)
			(layer "F.Fab")
			(hide yes)
			(effects
				(font
					(size 1 1)
					(thickness 0.15)
				)
			)
		)
		(property "License" "Apache-2.0"
			(at 128.906447 274.510773 0)
			(layer "F.Fab")
			(hide yes)
			(effects
				(font
					(size 1 1)
					(thickness 0.15)
				)
			)
		)
		(property "MPN" ""
			(at 128.906447 274.510773 0)
			(layer "F.Fab")
			(hide yes)
			(effects
				(font
					(size 1 1)
					(thickness 0.15)
				)
			)
		)
		(property "Manufacturer" ""
			(at 128.906447 274.510773 0)
			(layer "F.Fab")
			(hide yes)
			(effects
				(font
					(size 1 1)
					(thickness 0.15)
				)
			)
		)
		(property "Public" "False"
			(at 128.906447 274.510773 0)
			(layer "F.Fab")
			(hide yes)
			(effects
				(font
					(size 1 1)
					(thickness 0.15)
				)
			)
		)
		(sheetname "Power")
		(sheetfile "power.kicad_sch")
		(attr exclude_from_pos_files exclude_from_bom)
		(fp_circle
			(center 0 0)
			(end 0.475 0)
			(stroke
				(width 0.05)
				(type default)
			)
			(fill no)
			(layer "F.CrtYd")
		)
		(pad "1" smd circle
			(at 0 0 270)
			(size 0.75 0.75)
			(layers "F.Cu" "F.Mask")
			(net 74 "+1V0")
			(pinfunction "1")
			(pintype "passive")
			(teardrops
				(best_length_ratio 0.4)
				(max_length 1)
				(best_width_ratio 0.9)
				(max_width 2)
				(curved_edges yes)
				(filter_ratio 0.9)
				(enabled yes)
				(allow_two_segments yes)
				(prefer_zone_connections yes)
			)
		)
	)
	(footprint "antmicro-footprints:SOT-563"
		(layer "F.Cu")
		(at 312.425499 134.21 -90)
		(property "Reference" "U22"
			(at -3.65 -3.674501 180)
			(layer "F.SilkS")
			(effects
				(font
					(size 0.7 0.7)
					(thickness 0.15)
				)
				(justify right bottom)
			)
		)
		(property "Value" "TPS564247DRLR"
			(at 0 2.000001 90)
			(layer "F.Fab")
			(effects
				(font
					(size 0.7 0.7)
					(thickness 0.15)
				)
				(justify right bottom)
			)
		)
		(property "Datasheet" "https://www.ti.com/lit/ds/symlink/tps564247.pdf?ts=1713526387938&ref_url=https%253A%252F%252Fwww.mouser.pl%252F"
			(at 0 0 270)
			(layer "F.Fab")
			(hide yes)
			(effects
				(font
					(size 1.27 1.27)
					(thickness 0.15)
				)
			)
		)
		(property "Author" "Antmicro"
			(at 178.215499 446.635499 0)
			(layer "F.Fab")
			(hide yes)
			(effects
				(font
					(size 1 1)
					(thickness 0.15)
				)
			)
		)
		(property "License" "Apache-2.0"
			(at 178.215499 446.635499 0)
			(layer "F.Fab")
			(hide yes)
			(effects
				(font
					(size 1 1)
					(thickness 0.15)
				)
			)
		)
		(property "MPN" "TPS564247DRLR"
			(at 178.215499 446.635499 0)
			(layer "F.Fab")
			(hide yes)
			(effects
				(font
					(size 1 1)
					(thickness 0.15)
				)
			)
		)
		(property "Manufacturer" "Texas Instruments"
			(at 178.215499 446.635499 0)
			(layer "F.Fab")
			(hide yes)
			(effects
				(font
					(size 1 1)
					(thickness 0.15)
				)
			)
		)
		(sheetname "Power")
		(sheetfile "power.kicad_sch")
		(attr smd)
		(fp_line
			(start 0.776 0.972)
			(end 0.526 0.972)
			(stroke
				(width 0.15)
				(type solid)
			)
			(layer "F.SilkS")
		)
		(fp_line
			(start -0.778 0.949)
			(end -0.424 0.949)
			(stroke
				(width 0.15)
				(type solid)
			)
			(layer "F.SilkS")
		)
		(fp_line
			(start -0.778 0.776)
			(end -0.778 0.949)
			(stroke
				(width 0.15)
				(type solid)
			)
			(layer "F.SilkS")
		)
		(fp_line
			(start 0.776 0.776)
			(end 0.776 0.972)
			(stroke
				(width 0.15)
				(type solid)
			)
			(layer "F.SilkS")
		)
		(fp_line
			(start -0.499 -0.974)
			(end -0.724 -0.778)
			(stroke
				(width 0.15)
				(type solid)
			)
			(layer "F.SilkS")
		)
		(fp_line
			(start 0.776 -0.974)
			(end 0.776 -0.778)
			(stroke
				(width 0.15)
				(type solid)
			)
			(layer "F.SilkS")
		)
		(fp_line
			(start 0.776 -0.974)
			(end 0.526 -0.974)
			(stroke
				(width 0.15)
				(type solid)
			)
			(layer "F.SilkS")
		)
		(fp_circle
			(center -0.903 -0.999)
			(end -0.952 -0.95)
			(stroke
				(width 0.15)
				(type solid)
			)
			(fill yes)
			(layer "F.SilkS")
		)
		(fp_rect
			(start 1.19 -1.12)
			(end -1.2 1.1)
			(stroke
				(width 0.05)
				(type solid)
			)
			(fill no)
			(layer "F.CrtYd")
		)
		(fp_line
			(start 0.651 0.847)
			(end -0.653 0.847)
			(stroke
				(width 0.15)
				(type solid)
			)
			(layer "F.Fab")
		)
		(fp_line
			(start -0.653 -0.678)
			(end -0.653 0.847)
			(stroke
				(width 0.15)
				(type solid)
			)
			(layer "F.Fab")
		)
		(fp_line
			(start -0.453 -0.849)
			(end -0.653 -0.678)
			(stroke
				(width 0.15)
				(type solid)
			)
			(layer "F.Fab")
		)
		(fp_line
			(start -0.453 -0.849)
			(end 0.651 -0.849)
			(stroke
				(width 0.15)
				(type solid)
			)
			(layer "F.Fab")
		)
		(fp_line
			(start 0.651 -0.849)
			(end 0.651 0.847)
			(stroke
				(width 0.15)
				(type solid)
			)
			(layer "F.Fab")
		)
		(pad "1" smd roundrect
			(at -0.749 -0.499 180)
			(size 0.3 0.6)
			(layers "F.Cu" "F.Mask" "F.Paste")
			(roundrect_rratio 0.25)
			(net 62 "+12V_AON")
			(pinfunction "V_{IN}")
			(pintype "power_in")
			(teardrops
				(best_length_ratio 0.2)
				(max_length 1)
				(best_width_ratio 0.9)
				(max_width 2)
				(curved_edges yes)
				(filter_ratio 0.9)
				(enabled yes)
				(allow_two_segments yes)
				(prefer_zone_connections yes)
			)
		)
		(pad "2" smd roundrect
			(at -0.749 0.001 180)
			(size 0.3 0.6)
			(layers "F.Cu" "F.Mask" "F.Paste")
			(roundrect_rratio 0.25)
			(net 871 "Net-(U22-SW)")
			(pinfunction "SW")
			(pintype "passive")
			(teardrops
				(best_length_ratio 0.2)
				(max_length 1)
				(best_width_ratio 0.9)
				(max_width 2)
				(curved_edges yes)
				(filter_ratio 0.9)
				(enabled yes)
				(allow_two_segments yes)
				(prefer_zone_connections yes)
			)
		)
		(pad "3" smd roundrect
			(at -0.749 0.497 180)
			(size 0.3 0.6)
			(layers "F.Cu" "F.Mask" "F.Paste")
			(roundrect_rratio 0.25)
			(net 1 "GND")
			(pinfunction "GND")
			(pintype "power_in")
			(teardrops
				(best_length_ratio 0.2)
				(max_length 1)
				(best_width_ratio 0.9)
				(max_width 2)
				(curved_edges yes)
				(filter_ratio 0.9)
				(enabled yes)
				(allow_two_segments yes)
				(prefer_zone_connections yes)
			)
		)
		(pad "4" smd roundrect
			(at 0.747 0.497 180)
			(size 0.3 0.6)
			(layers "F.Cu" "F.Mask" "F.Paste")
			(roundrect_rratio 0.25)
			(net 1 "GND")
			(pinfunction "AGND")
			(pintype "power_in")
			(teardrops
				(best_length_ratio 0.2)
				(max_length 1)
				(best_width_ratio 0.9)
				(max_width 2)
				(curved_edges yes)
				(filter_ratio 0.9)
				(enabled yes)
				(allow_two_segments yes)
				(prefer_zone_connections yes)
			)
		)
		(pad "5" smd roundrect
			(at 0.747 0.001 180)
			(size 0.3 0.6)
			(layers "F.Cu" "F.Mask" "F.Paste")
			(roundrect_rratio 0.25)
			(net 583 "Net-(U22-EN)")
			(pinfunction "EN")
			(pintype "passive")
			(teardrops
				(best_length_ratio 0.2)
				(max_length 1)
				(best_width_ratio 0.9)
				(max_width 2)
				(curved_edges yes)
				(filter_ratio 0.9)
				(enabled yes)
				(allow_two_segments yes)
				(prefer_zone_connections yes)
			)
		)
		(pad "6" smd roundrect
			(at 0.747 -0.499 180)
			(size 0.3 0.6)
			(layers "F.Cu" "F.Mask" "F.Paste")
			(roundrect_rratio 0.25)
			(net 586 "Net-(U22-FB)")
			(pinfunction "FB")
			(pintype "passive")
			(teardrops
				(best_length_ratio 0.2)
				(max_length 1)
				(best_width_ratio 0.9)
				(max_width 2)
				(curved_edges yes)
				(filter_ratio 0.9)
				(enabled yes)
				(allow_two_segments yes)
				(prefer_zone_connections yes)
			)
		)
	)
	(footprint "antmicro-footprints:R_0402_1005Metric"
		(layer "F.Cu")
		(at 302.575 138.285 90)
		(descr "Resistor SMD 0402")
		(tags "resistor SMD 0402")
		(property "Reference" "R90"
			(at -0.825 -0.525 90)
			(layer "F.SilkS")
			(effects
				(font
					(size 0.7 0.7)
					(thickness 0.15)
				)
				(justify left bottom)
			)
		)
		(property "Value" "R_100k_0402"
			(at -1.011843 1.772047 90)
			(layer "F.Fab")
			(effects
				(font
					(size 0.7 0.7)
					(thickness 0.15)
				)
				(justify left bottom)
			)
		)
		(property "Datasheet" "https://www.bourns.com/docs/product-datasheets/cr.pdf"
			(at 0 0 90)
			(layer "F.Fab")
			(hide yes)
			(effects
				(font
					(size 1.27 1.27)
					(thickness 0.15)
				)
			)
		)
		(property "Author" "Antmicro"
			(at 440.86 -164.29 0)
			(layer "F.Fab")
			(hide yes)
			(effects
				(font
					(size 1 1)
					(thickness 0.15)
				)
			)
		)
		(property "License" "Apache-2.0"
			(at 440.86 -164.29 0)
			(layer "F.Fab")
			(hide yes)
			(effects
				(font
					(size 1 1)
					(thickness 0.15)
				)
			)
		)
		(property "MPN" "CR0402-FX-1003GLF"
			(at 440.86 -164.29 0)
			(layer "F.Fab")
			(hide yes)
			(effects
				(font
					(size 1 1)
					(thickness 0.15)
				)
			)
		)
		(property "Manufacturer" "Bourns"
			(at 440.86 -164.29 0)
			(layer "F.Fab")
			(hide yes)
			(effects
				(font
					(size 1 1)
					(thickness 0.15)
				)
			)
		)
		(property "Public" "False"
			(at 440.86 -164.29 0)
			(layer "F.Fab")
			(hide yes)
			(effects
				(font
					(size 1 1)
					(thickness 0.15)
				)
			)
		)
		(property "Tolerance" "1%"
			(at 440.86 -164.29 0)
			(layer "F.Fab")
			(hide yes)
			(effects
				(font
					(size 1 1)
					(thickness 0.15)
				)
			)
		)
		(property "Val" "100k"
			(at 440.86 -164.29 0)
			(layer "F.Fab")
			(hide yes)
			(effects
				(font
					(size 1 1)
					(thickness 0.15)
				)
			)
		)
		(sheetname "Power")
		(sheetfile "power.kicad_sch")
		(attr smd)
		(fp_rect
			(start -0.925 -0.47)
			(end 0.925 0.47)
			(stroke
				(width 0.05)
				(type default)
			)
			(fill no)
			(layer "F.CrtYd")
		)
		(fp_rect
			(start -0.5 -0.25)
			(end 0.5 0.25)
			(stroke
				(width 0.15)
				(type solid)
			)
			(fill no)
			(layer "F.Fab")
		)
		(pad "1" smd roundrect
			(at -0.48 0 90)
			(size 0.59 0.64)
			(layers "F.Cu" "F.Mask" "F.Paste")
			(roundrect_rratio 0.25)
			(net 1 "GND")
			(pintype "passive")
			(teardrops
				(best_length_ratio 0.2)
				(max_length 1)
				(best_width_ratio 0.9)
				(max_width 2)
				(curved_edges yes)
				(filter_ratio 0.9)
				(enabled yes)
				(allow_two_segments yes)
				(prefer_zone_connections yes)
			)
		)
		(pad "2" smd roundrect
			(at 0.48 0 90)
			(size 0.59 0.64)
			(layers "F.Cu" "F.Mask" "F.Paste")
			(roundrect_rratio 0.25)
			(net 533 "/Com Express 7 MGMT/PSON")
			(pintype "passive")
			(teardrops
				(best_length_ratio 0.2)
				(max_length 1)
				(best_width_ratio 0.9)
				(max_width 2)
				(curved_edges yes)
				(filter_ratio 0.9)
				(enabled yes)
				(allow_two_segments yes)
				(prefer_zone_connections yes)
			)
		)
	)
	(footprint "antmicro-footprints:R_0402_1005Metric"
		(layer "F.Cu")
		(at 155.299 167.36 180)
		(descr "Resistor SMD 0402")
		(tags "resistor SMD 0402")
		(property "Reference" "R62"
			(at -4.551 18.1 0)
			(layer "F.SilkS")
			(effects
				(font
					(size 0.7 0.7)
					(thickness 0.15)
				)
				(justify left bottom)
			)
		)
		(property "Value" "R_220R_0402"
			(at -1.011843 1.772047 0)
			(layer "F.Fab")
			(effects
				(font
					(size 0.7 0.7)
					(thickness 0.15)
				)
				(justify right bottom)
			)
		)
		(property "Datasheet" "https://www.bourns.com/docs/product-datasheets/cr.pdf"
			(at 0 0 180)
			(layer "F.Fab")
			(hide yes)
			(effects
				(font
					(size 1.27 1.27)
					(thickness 0.15)
				)
			)
		)
		(property "Author" "Antmicro"
			(at 310.598 334.72 0)
			(layer "F.Fab")
			(hide yes)
			(effects
				(font
					(size 1 1)
					(thickness 0.15)
				)
			)
		)
		(property "License" "Apache-2.0"
			(at 310.598 334.72 0)
			(layer "F.Fab")
			(hide yes)
			(effects
				(font
					(size 1 1)
					(thickness 0.15)
				)
			)
		)
		(property "MPN" "CR0402-FX-2200GLF"
			(at 310.598 334.72 0)
			(layer "F.Fab")
			(hide yes)
			(effects
				(font
					(size 1 1)
					(thickness 0.15)
				)
			)
		)
		(property "Manufacturer" "Bourns"
			(at 310.598 334.72 0)
			(layer "F.Fab")
			(hide yes)
			(effects
				(font
					(size 1 1)
					(thickness 0.15)
				)
			)
		)
		(property "Public" "False"
			(at 310.598 334.72 0)
			(layer "F.Fab")
			(hide yes)
			(effects
				(font
					(size 1 1)
					(thickness 0.15)
				)
			)
		)
		(property "Tolerance" "1%"
			(at 310.598 334.72 0)
			(layer "F.Fab")
			(hide yes)
			(effects
				(font
					(size 1 1)
					(thickness 0.15)
				)
			)
		)
		(property "Val" "220R"
			(at 310.598 334.72 0)
			(layer "F.Fab")
			(hide yes)
			(effects
				(font
					(size 1 1)
					(thickness 0.15)
				)
			)
		)
		(sheetname "2xSFP+")
		(sheetfile "2xSFP+.kicad_sch")
		(attr smd)
		(fp_rect
			(start -0.925 -0.47)
			(end 0.925 0.47)
			(stroke
				(width 0.05)
				(type default)
			)
			(fill no)
			(layer "F.CrtYd")
		)
		(fp_rect
			(start -0.5 -0.25)
			(end 0.5 0.25)
			(stroke
				(width 0.15)
				(type solid)
			)
			(fill no)
			(layer "F.Fab")
		)
		(pad "1" smd roundrect
			(at -0.48 0 180)
			(size 0.59 0.64)
			(layers "F.Cu" "F.Mask" "F.Paste")
			(roundrect_rratio 0.25)
			(net 898 "/2xSFP+/SFP1_LEDY")
			(pintype "passive")
			(teardrops
				(best_length_ratio 0.2)
				(max_length 1)
				(best_width_ratio 0.9)
				(max_width 2)
				(curved_edges yes)
				(filter_ratio 0.9)
				(enabled yes)
				(allow_two_segments yes)
				(prefer_zone_connections yes)
			)
		)
		(pad "2" smd roundrect
			(at 0.48 0 180)
			(size 0.59 0.64)
			(layers "F.Cu" "F.Mask" "F.Paste")
			(roundrect_rratio 0.25)
			(net 930 "Net-(D5-C)")
			(pintype "passive")
			(teardrops
				(best_length_ratio 0.2)
				(max_length 1)
				(best_width_ratio 0.9)
				(max_width 2)
				(curved_edges yes)
				(filter_ratio 0.9)
				(enabled yes)
				(allow_two_segments yes)
				(prefer_zone_connections yes)
			)
		)
	)
	(footprint "antmicro-footprints:R_0402_1005Metric"
		(layer "F.Cu")
		(at 127.9 81.760001 -90)
		(descr "Resistor SMD 0402")
		(tags "resistor SMD 0402")
		(property "Reference" "R236"
			(at -3.650001 -0.45 90)
			(layer "F.SilkS")
			(effects
				(font
					(size 0.7 0.7)
					(thickness 0.15)
				)
				(justify right bottom)
			)
		)
		(property "Value" "R_0R_0402"
			(at -1.011843 1.772047 90)
			(layer "F.Fab")
			(effects
				(font
					(size 0.7 0.7)
					(thickness 0.15)
				)
				(justify right bottom)
			)
		)
		(property "Datasheet" "https://industrial.panasonic.com/cdbs/www-data/pdf/RDA0000/AOA0000C301.pdf"
			(at 0 0 270)
			(layer "F.Fab")
			(hide yes)
			(effects
				(font
					(size 1.27 1.27)
					(thickness 0.15)
				)
			)
		)
		(property "Author" "Antmicro"
			(at 46.139999 209.660001 0)
			(layer "F.Fab")
			(hide yes)
			(effects
				(font
					(size 1 1)
					(thickness 0.15)
				)
			)
		)
		(property "Current" "1A"
			(at 46.139999 209.660001 0)
			(layer "F.Fab")
			(hide yes)
			(effects
				(font
					(size 1 1)
					(thickness 0.15)
				)
			)
		)
		(property "License" "Apache-2.0"
			(at 46.139999 209.660001 0)
			(layer "F.Fab")
			(hide yes)
			(effects
				(font
					(size 1 1)
					(thickness 0.15)
				)
			)
		)
		(property "MPN" "ERJ2GE0R00X"
			(at 46.139999 209.660001 0)
			(layer "F.Fab")
			(hide yes)
			(effects
				(font
					(size 1 1)
					(thickness 0.15)
				)
			)
		)
		(property "Manufacturer" "Panasonic"
			(at 46.139999 209.660001 0)
			(layer "F.Fab")
			(hide yes)
			(effects
				(font
					(size 1 1)
					(thickness 0.15)
				)
			)
		)
		(property "Public" "False"
			(at 46.139999 209.660001 0)
			(layer "F.Fab")
			(hide yes)
			(effects
				(font
					(size 1 1)
					(thickness 0.15)
				)
			)
		)
		(property "Tolerance" ""
			(at 46.139999 209.660001 0)
			(layer "F.Fab")
			(hide yes)
			(effects
				(font
					(size 1 1)
					(thickness 0.15)
				)
			)
		)
		(property "Val" "0R"
			(at 46.139999 209.660001 0)
			(layer "F.Fab")
			(hide yes)
			(effects
				(font
					(size 1 1)
					(thickness 0.15)
				)
			)
		)
		(sheetname "GPIO expander")
		(sheetfile "gpio_exp.kicad_sch")
		(attr smd)
		(fp_rect
			(start -0.925 -0.47)
			(end 0.925 0.47)
			(stroke
				(width 0.05)
				(type default)
			)
			(fill no)
			(layer "F.CrtYd")
		)
		(fp_rect
			(start -0.5 -0.25)
			(end 0.5 0.25)
			(stroke
				(width 0.15)
				(type solid)
			)
			(fill no)
			(layer "F.Fab")
		)
		(pad "1" smd roundrect
			(at -0.48 0 270)
			(size 0.59 0.64)
			(layers "F.Cu" "F.Mask" "F.Paste")
			(roundrect_rratio 0.25)
			(net 528 "/Backplane/~{PERST}")
			(pintype "passive")
			(teardrops
				(best_length_ratio 0.2)
				(max_length 1)
				(best_width_ratio 0.9)
				(max_width 2)
				(curved_edges yes)
				(filter_ratio 0.9)
				(enabled yes)
				(allow_two_segments yes)
				(prefer_zone_connections yes)
			)
		)
		(pad "2" smd roundrect
			(at 0.48 0 270)
			(size 0.59 0.64)
			(layers "F.Cu" "F.Mask" "F.Paste")
			(roundrect_rratio 0.25)
			(net 637 "Net-(U41-~{RESET})")
			(pintype "passive")
			(teardrops
				(best_length_ratio 0.2)
				(max_length 1)
				(best_width_ratio 0.9)
				(max_width 2)
				(curved_edges yes)
				(filter_ratio 0.9)
				(enabled yes)
				(allow_two_segments yes)
				(prefer_zone_connections yes)
			)
		)
	)
	(footprint "antmicro-footprints:R_0402_1005Metric"
		(layer "F.Cu")
		(at 155.299 163.11 180)
		(descr "Resistor SMD 0402")
		(tags "resistor SMD 0402")
		(property "Reference" "R48"
			(at -6.701 17.5 0)
			(layer "F.SilkS")
			(effects
				(font
					(size 0.7 0.7)
					(thickness 0.15)
				)
				(justify right bottom)
			)
		)
		(property "Value" "R_0R_0402"
			(at -1.011843 1.772047 0)
			(layer "F.Fab")
			(effects
				(font
					(size 0.7 0.7)
					(thickness 0.15)
				)
				(justify right bottom)
			)
		)
		(property "Datasheet" "https://industrial.panasonic.com/cdbs/www-data/pdf/RDA0000/AOA0000C301.pdf"
			(at 0 0 180)
			(layer "F.Fab")
			(hide yes)
			(effects
				(font
					(size 1.27 1.27)
					(thickness 0.15)
				)
			)
		)
		(property "Author" "Antmicro"
			(at 310.598 326.22 0)
			(layer "F.Fab")
			(hide yes)
			(effects
				(font
					(size 1 1)
					(thickness 0.15)
				)
			)
		)
		(property "Current" "1A"
			(at 310.598 326.22 0)
			(layer "F.Fab")
			(hide yes)
			(effects
				(font
					(size 1 1)
					(thickness 0.15)
				)
			)
		)
		(property "License" "Apache-2.0"
			(at 310.598 326.22 0)
			(layer "F.Fab")
			(hide yes)
			(effects
				(font
					(size 1 1)
					(thickness 0.15)
				)
			)
		)
		(property "MPN" "ERJ2GE0R00X"
			(at 310.598 326.22 0)
			(layer "F.Fab")
			(hide yes)
			(effects
				(font
					(size 1 1)
					(thickness 0.15)
				)
			)
		)
		(property "Manufacturer" "Panasonic"
			(at 310.598 326.22 0)
			(layer "F.Fab")
			(hide yes)
			(effects
				(font
					(size 1 1)
					(thickness 0.15)
				)
			)
		)
		(property "Public" "False"
			(at 310.598 326.22 0)
			(layer "F.Fab")
			(hide yes)
			(effects
				(font
					(size 1 1)
					(thickness 0.15)
				)
			)
		)
		(property "Tolerance" ""
			(at 310.598 326.22 0)
			(layer "F.Fab")
			(hide yes)
			(effects
				(font
					(size 1 1)
					(thickness 0.15)
				)
			)
		)
		(property "Val" "0R"
			(at 310.598 326.22 0)
			(layer "F.Fab")
			(hide yes)
			(effects
				(font
					(size 1 1)
					(thickness 0.15)
				)
			)
		)
		(sheetname "2xSFP+")
		(sheetfile "2xSFP+.kicad_sch")
		(attr smd dnp)
		(fp_rect
			(start -0.925 -0.47)
			(end 0.925 0.47)
			(stroke
				(width 0.05)
				(type default)
			)
			(fill no)
			(layer "F.CrtYd")
		)
		(fp_rect
			(start -0.5 -0.25)
			(end 0.5 0.25)
			(stroke
				(width 0.15)
				(type solid)
			)
			(fill no)
			(layer "F.Fab")
		)
		(pad "1" smd roundrect
			(at -0.48 0 180)
			(size 0.59 0.64)
			(layers "F.Cu" "F.Mask" "F.Paste")
			(roundrect_rratio 0.25)
			(net 567 "/2xSFP+/~{LED1_2}")
			(pintype "passive")
			(teardrops
				(best_length_ratio 0.2)
				(max_length 1)
				(best_width_ratio 0.9)
				(max_width 2)
				(curved_edges yes)
				(filter_ratio 0.9)
				(enabled yes)
				(allow_two_segments yes)
				(prefer_zone_connections yes)
			)
		)
		(pad "2" smd roundrect
			(at 0.48 0 180)
			(size 0.59 0.64)
			(layers "F.Cu" "F.Mask" "F.Paste")
			(roundrect_rratio 0.25)
			(net 929 "/2xSFP+/SFP1_LEDG")
			(pintype "passive")
			(teardrops
				(best_length_ratio 0.2)
				(max_length 1)
				(best_width_ratio 0.9)
				(max_width 2)
				(curved_edges yes)
				(filter_ratio 0.9)
				(enabled yes)
				(allow_two_segments yes)
				(prefer_zone_connections yes)
			)
		)
	)
	(footprint "antmicro-footprints:R_0402_1005Metric"
		(layer "F.Cu")
		(at 283.36 78.06 -90)
		(descr "Resistor SMD 0402")
		(tags "resistor SMD 0402")
		(property "Reference" "R129"
			(at -1.2 0.51 90)
			(layer "F.SilkS")
			(effects
				(font
					(size 0.7 0.7)
					(thickness 0.15)
				)
				(justify right bottom)
			)
		)
		(property "Value" "R_220R_0402"
			(at -1.011843 1.772047 90)
			(layer "F.Fab")
			(effects
				(font
					(size 0.7 0.7)
					(thickness 0.15)
				)
				(justify right bottom)
			)
		)
		(property "Datasheet" "https://www.bourns.com/docs/product-datasheets/cr.pdf"
			(at 0 0 270)
			(layer "F.Fab")
			(hide yes)
			(effects
				(font
					(size 1.27 1.27)
					(thickness 0.15)
				)
			)
		)
		(property "Author" "Antmicro"
			(at 205.3 361.42 0)
			(layer "F.Fab")
			(hide yes)
			(effects
				(font
					(size 1 1)
					(thickness 0.15)
				)
			)
		)
		(property "License" "Apache-2.0"
			(at 205.3 361.42 0)
			(layer "F.Fab")
			(hide yes)
			(effects
				(font
					(size 1 1)
					(thickness 0.15)
				)
			)
		)
		(property "MPN" "CR0402-FX-2200GLF"
			(at 205.3 361.42 0)
			(layer "F.Fab")
			(hide yes)
			(effects
				(font
					(size 1 1)
					(thickness 0.15)
				)
			)
		)
		(property "Manufacturer" "Bourns"
			(at 205.3 361.42 0)
			(layer "F.Fab")
			(hide yes)
			(effects
				(font
					(size 1 1)
					(thickness 0.15)
				)
			)
		)
		(property "Public" "False"
			(at 205.3 361.42 0)
			(layer "F.Fab")
			(hide yes)
			(effects
				(font
					(size 1 1)
					(thickness 0.15)
				)
			)
		)
		(property "Tolerance" "1%"
			(at 205.3 361.42 0)
			(layer "F.Fab")
			(hide yes)
			(effects
				(font
					(size 1 1)
					(thickness 0.15)
				)
			)
		)
		(property "Val" "220R"
			(at 205.3 361.42 0)
			(layer "F.Fab")
			(hide yes)
			(effects
				(font
					(size 1 1)
					(thickness 0.15)
				)
			)
		)
		(sheetname "M.2 key M #2")
		(sheetfile "m2keym.kicad_sch")
		(attr smd)
		(fp_rect
			(start -0.925 -0.47)
			(end 0.925 0.47)
			(stroke
				(width 0.05)
				(type default)
			)
			(fill no)
			(layer "F.CrtYd")
		)
		(fp_rect
			(start -0.5 -0.25)
			(end 0.5 0.25)
			(stroke
				(width 0.15)
				(type solid)
			)
			(fill no)
			(layer "F.Fab")
		)
		(pad "1" smd roundrect
			(at -0.48 0 270)
			(size 0.59 0.64)
			(layers "F.Cu" "F.Mask" "F.Paste")
			(roundrect_rratio 0.25)
			(net 892 "Net-(D14-A)")
			(pintype "passive")
			(teardrops
				(best_length_ratio 0.2)
				(max_length 1)
				(best_width_ratio 0.9)
				(max_width 2)
				(curved_edges yes)
				(filter_ratio 0.9)
				(enabled yes)
				(allow_two_segments yes)
				(prefer_zone_connections yes)
			)
		)
		(pad "2" smd roundrect
			(at 0.48 0 270)
			(size 0.59 0.64)
			(layers "F.Cu" "F.Mask" "F.Paste")
			(roundrect_rratio 0.25)
			(net 2 "+3V3")
			(pintype "passive")
			(teardrops
				(best_length_ratio 0.2)
				(max_length 1)
				(best_width_ratio 0.9)
				(max_width 2)
				(curved_edges yes)
				(filter_ratio 0.9)
				(enabled yes)
				(allow_two_segments yes)
				(prefer_zone_connections yes)
			)
		)
	)
	(footprint "antmicro-footprints:C_Pol_EIA-B"
		(layer "F.Cu")
		(at 110.8 86.96 -90)
		(property "Reference" "C3"
			(at -3.85 -0.55 90)
			(layer "F.SilkS")
			(effects
				(font
					(size 0.7 0.7)
					(thickness 0.15)
				)
				(justify right bottom)
			)
		)
		(property "Value" "C_Pol_100u_10V_KEMET-T520-B"
			(at 0 2.85 90)
			(layer "F.Fab")
			(effects
				(font
					(size 0.7 0.7)
					(thickness 0.15)
				)
				(justify right bottom)
			)
		)
		(property "Datasheet" "https://www.kemet.com/en/us/capacitors/product/T520B107M010ATE070.html"
			(at 0 0 270)
			(layer "F.Fab")
			(hide yes)
			(effects
				(font
					(size 1.27 1.27)
					(thickness 0.15)
				)
			)
		)
		(property "Author" "Antmicro"
			(at 23.84 197.76 0)
			(layer "F.Fab")
			(hide yes)
			(effects
				(font
					(size 1 1)
					(thickness 0.15)
				)
			)
		)
		(property "Dielectric" "template_dielectric"
			(at 23.84 197.76 0)
			(layer "F.Fab")
			(hide yes)
			(effects
				(font
					(size 1 1)
					(thickness 0.15)
				)
			)
		)
		(property "License" "Apache-2.0"
			(at 23.84 197.76 0)
			(layer "F.Fab")
			(hide yes)
			(effects
				(font
					(size 1 1)
					(thickness 0.15)
				)
			)
		)
		(property "MPN" "T520B107M010ATE070"
			(at 23.84 197.76 0)
			(layer "F.Fab")
			(hide yes)
			(effects
				(font
					(size 1 1)
					(thickness 0.15)
				)
			)
		)
		(property "Manufacturer" "KEMET"
			(at 23.84 197.76 0)
			(layer "F.Fab")
			(hide yes)
			(effects
				(font
					(size 1 1)
					(thickness 0.15)
				)
			)
		)
		(property "Public" "False"
			(at 23.84 197.76 0)
			(layer "F.Fab")
			(hide yes)
			(effects
				(font
					(size 1 1)
					(thickness 0.15)
				)
			)
		)
		(property "Val" "100u"
			(at 23.84 197.76 0)
			(layer "F.Fab")
			(hide yes)
			(effects
				(font
					(size 1 1)
					(thickness 0.15)
				)
			)
		)
		(property "Voltage" "10V"
			(at 23.84 197.76 0)
			(layer "F.Fab")
			(hide yes)
			(effects
				(font
					(size 1 1)
					(thickness 0.15)
				)
			)
		)
		(sheetname "2xUSB3.0+RJ45")
		(sheetfile "usb3+rj45.kicad_sch")
		(attr smd)
		(fp_line
			(start 1.8 1.6)
			(end -1.8 1.6)
			(stroke
				(width 0.15)
				(type solid)
			)
			(layer "F.SilkS")
		)
		(fp_line
			(start -1.8 1.3)
			(end -1.8 1.6)
			(stroke
				(width 0.15)
				(type solid)
			)
			(layer "F.SilkS")
		)
		(fp_line
			(start 1.8 1.3)
			(end 1.8 1.6)
			(stroke
				(width 0.15)
				(type solid)
			)
			(layer "F.SilkS")
		)
		(fp_line
			(start -1.8 -1.3)
			(end -1.8 -1.6)
			(stroke
				(width 0.15)
				(type solid)
			)
			(layer "F.SilkS")
		)
		(fp_line
			(start 1.8 -1.3)
			(end 1.8 -1.6)
			(stroke
				(width 0.15)
				(type solid)
			)
			(layer "F.SilkS")
		)
		(fp_line
			(start -2.325 -1.475)
			(end -2.325 -1.878)
			(stroke
				(width 0.15)
				(type solid)
			)
			(layer "F.SilkS")
		)
		(fp_line
			(start -1.8 -1.6)
			(end 1.8 -1.6)
			(stroke
				(width 0.15)
				(type solid)
			)
			(layer "F.SilkS")
		)
		(fp_line
			(start -2.521 -1.676)
			(end -2.123 -1.676)
			(stroke
				(width 0.15)
				(type solid)
			)
			(layer "F.SilkS")
		)
		(fp_line
			(start 1.96 1.75)
			(end -1.97 1.75)
			(stroke
				(width 0.05)
				(type solid)
			)
			(layer "F.CrtYd")
		)
		(fp_line
			(start -1.97 1.35)
			(end -1.97 1.75)
			(stroke
				(width 0.05)
				(type solid)
			)
			(layer "F.CrtYd")
		)
		(fp_line
			(start -1.97 1.35)
			(end -2.41 1.35)
			(stroke
				(width 0.05)
				(type solid)
			)
			(layer "F.CrtYd")
		)
		(fp_line
			(start 1.96 1.35)
			(end 1.96 1.75)
			(stroke
				(width 0.05)
				(type solid)
			)
			(layer "F.CrtYd")
		)
		(fp_line
			(start 2.4 1.35)
			(end 1.96 1.35)
			(stroke
				(width 0.05)
				(type solid)
			)
			(layer "F.CrtYd")
		)
		(fp_line
			(start -2.411 -1.35)
			(end -2.41 1.35)
			(stroke
				(width 0.05)
				(type solid)
			)
			(layer "F.CrtYd")
		)
		(fp_line
			(start -1.97 -1.35)
			(end -2.41 -1.35)
			(stroke
				(width 0.05)
				(type solid)
			)
			(layer "F.CrtYd")
		)
		(fp_line
			(start 2.399 -1.35)
			(end 2.4 1.35)
			(stroke
				(width 0.05)
				(type solid)
			)
			(layer "F.CrtYd")
		)
		(fp_line
			(start 2.399 -1.35)
			(end 1.959 -1.35)
			(stroke
				(width 0.05)
				(type solid)
			)
			(layer "F.CrtYd")
		)
		(fp_line
			(start -1.97 -1.75)
			(end -1.97 -1.35)
			(stroke
				(width 0.05)
				(type solid)
			)
			(layer "F.CrtYd")
		)
		(fp_line
			(start 1.959 -1.75)
			(end 1.959 -1.35)
			(stroke
				(width 0.05)
				(type solid)
			)
			(layer "F.CrtYd")
		)
		(fp_line
			(start 1.959 -1.75)
			(end -1.97 -1.75)
			(stroke
				(width 0.05)
				(type solid)
			)
			(layer "F.CrtYd")
		)
		(fp_line
			(start -1.7 1.324)
			(end -1.551 1.475)
			(stroke
				(width 0.15)
				(type solid)
			)
			(layer "F.Fab")
		)
		(fp_rect
			(start -1.72 -1.5)
			(end 1.719 1.499)
			(stroke
				(width 0.15)
				(type solid)
			)
			(fill no)
			(layer "F.Fab")
		)
		(pad "1" smd roundrect
			(at -1.551 0 270)
			(size 1.2 2.2)
			(layers "F.Cu" "F.Mask" "F.Paste")
			(roundrect_rratio 0.1)
			(net 42 "/2xUSB3.0+RJ45/P1_VBUS")
			(pintype "passive")
			(teardrops
				(best_length_ratio 0.2)
				(max_length 1)
				(best_width_ratio 0.9)
				(max_width 2)
				(curved_edges yes)
				(filter_ratio 0.9)
				(enabled yes)
				(allow_two_segments yes)
				(prefer_zone_connections yes)
			)
		)
		(pad "2" smd roundrect
			(at 1.55 0 270)
			(size 1.2 2.2)
			(layers "F.Cu" "F.Mask" "F.Paste")
			(roundrect_rratio 0.1)
			(net 1 "GND")
			(pintype "passive")
			(teardrops
				(best_length_ratio 0.2)
				(max_length 1)
				(best_width_ratio 0.9)
				(max_width 2)
				(curved_edges yes)
				(filter_ratio 0.9)
				(enabled yes)
				(allow_two_segments yes)
				(prefer_zone_connections yes)
			)
		)
	)
	(footprint "antmicro-footprints:C_0402_1005Metric"
		(layer "F.Cu")
		(at 115.9 148.421 -90)
		(descr "Capacitor SMD 0402")
		(tags "capacitor SMD 0402")
		(property "Reference" "C113"
			(at -12.611 -2.1 90)
			(layer "F.SilkS")
			(effects
				(font
					(size 0.7 0.7)
					(thickness 0.15)
				)
				(justify right bottom)
			)
		)
		(property "Value" "C_100n_0402"
			(at -1.022927 2.155213 90)
			(layer "F.Fab")
			(effects
				(font
					(size 0.7 0.7)
					(thickness 0.15)
				)
				(justify right bottom)
			)
		)
		(property "Datasheet" "https://www.murata.com/products/productdetail?partno=GRM155R61H104KE14%23"
			(at 0 0 270)
			(layer "F.Fab")
			(hide yes)
			(effects
				(font
					(size 1.27 1.27)
					(thickness 0.15)
				)
			)
		)
		(property "Author" "Antmicro"
			(at -32.521 264.321 0)
			(layer "F.Fab")
			(hide yes)
			(effects
				(font
					(size 1 1)
					(thickness 0.15)
				)
			)
		)
		(property "Dielectric" "X5R"
			(at -32.521 264.321 0)
			(layer "F.Fab")
			(hide yes)
			(effects
				(font
					(size 1 1)
					(thickness 0.15)
				)
			)
		)
		(property "License" "Apache-2.0"
			(at -32.521 264.321 0)
			(layer "F.Fab")
			(hide yes)
			(effects
				(font
					(size 1 1)
					(thickness 0.15)
				)
			)
		)
		(property "MPN" "GRM155R61H104KE14D"
			(at -32.521 264.321 0)
			(layer "F.Fab")
			(hide yes)
			(effects
				(font
					(size 1 1)
					(thickness 0.15)
				)
			)
		)
		(property "Manufacturer" "Murata"
			(at -32.521 264.321 0)
			(layer "F.Fab")
			(hide yes)
			(effects
				(font
					(size 1 1)
					(thickness 0.15)
				)
			)
		)
		(property "Public" "False"
			(at -32.521 264.321 0)
			(layer "F.Fab")
			(hide yes)
			(effects
				(font
					(size 1 1)
					(thickness 0.15)
				)
			)
		)
		(property "Val" "100n"
			(at -32.521 264.321 0)
			(layer "F.Fab")
			(hide yes)
			(effects
				(font
					(size 1 1)
					(thickness 0.15)
				)
			)
		)
		(property "Voltage" "50V"
			(at -32.521 264.321 0)
			(layer "F.Fab")
			(hide yes)
			(effects
				(font
					(size 1 1)
					(thickness 0.15)
				)
			)
		)
		(sheetname "PCIe redriver")
		(sheetfile "pcie_redriver.kicad_sch")
		(attr smd)
		(fp_rect
			(start -0.925 -0.47)
			(end 0.925 0.47)
			(stroke
				(width 0.05)
				(type default)
			)
			(fill no)
			(layer "F.CrtYd")
		)
		(fp_line
			(start -0.494 0.248)
			(end -0.494 -0.25)
			(stroke
				(width 0.15)
				(type solid)
			)
			(layer "F.Fab")
		)
		(fp_line
			(start 0.504 0.248)
			(end -0.494 0.248)
			(stroke
				(width 0.15)
				(type solid)
			)
			(layer "F.Fab")
		)
		(fp_line
			(start -0.494 -0.25)
			(end 0.504 -0.25)
			(stroke
				(width 0.15)
				(type solid)
			)
			(layer "F.Fab")
		)
		(fp_line
			(start 0.504 -0.25)
			(end 0.504 0.248)
			(stroke
				(width 0.15)
				(type solid)
			)
			(layer "F.Fab")
		)
		(pad "1" smd roundrect
			(at -0.48 0 270)
			(size 0.59 0.64)
			(layers "F.Cu" "F.Mask" "F.Paste")
			(roundrect_rratio 0.25)
			(net 1 "GND")
			(pintype "passive")
			(teardrops
				(best_length_ratio 0.2)
				(max_length 1)
				(best_width_ratio 0.9)
				(max_width 2)
				(curved_edges yes)
				(filter_ratio 0.9)
				(enabled yes)
				(allow_two_segments yes)
				(prefer_zone_connections yes)
			)
		)
		(pad "2" smd roundrect
			(at 0.48 0 270)
			(size 0.59 0.64)
			(layers "F.Cu" "F.Mask" "F.Paste")
			(roundrect_rratio 0.25)
			(net 2 "+3V3")
			(pintype "passive")
			(teardrops
				(best_length_ratio 0.2)
				(max_length 1)
				(best_width_ratio 0.9)
				(max_width 2)
				(curved_edges yes)
				(filter_ratio 0.9)
				(enabled yes)
				(allow_two_segments yes)
				(prefer_zone_connections yes)
			)
		)
	)
	(footprint "antmicro-footprints:Bus_M.2_Socket_Key_M_TE_1-2199230-6"
		(layer "F.Cu")
		(at 295.45 77.81)
		(property "Reference" "J8"
			(at -11.35 -5.076 0)
			(layer "F.SilkS")
			(effects
				(font
					(size 0.7 0.7)
					(thickness 0.15)
				)
				(justify left bottom)
			)
		)
		(property "Value" "Bus_M.2_1-2199230-6"
			(at -11.25 6.124 0)
			(layer "F.Fab")
			(effects
				(font
					(size 0.7 0.7)
					(thickness 0.15)
				)
				(justify left bottom)
			)
		)
		(property "Datasheet" "https://www.te.com/commerce/DocumentDelivery/DDEController?Action=srchrtrv&DocNm=2199230&DocType=Customer+Drawing&DocLang=English"
			(at 0 0 0)
			(layer "F.Fab")
			(hide yes)
			(effects
				(font
					(size 1.27 1.27)
					(thickness 0.15)
				)
			)
		)
		(property "Author" "Antmicro"
			(at 0 0 0)
			(layer "F.Fab")
			(hide yes)
			(effects
				(font
					(size 1 1)
					(thickness 0.15)
				)
			)
		)
		(property "License" "Apache-2.0"
			(at 0 0 0)
			(layer "F.Fab")
			(hide yes)
			(effects
				(font
					(size 1 1)
					(thickness 0.15)
				)
			)
		)
		(property "MPN" "1-2199230-6"
			(at 0 0 0)
			(layer "F.Fab")
			(hide yes)
			(effects
				(font
					(size 1 1)
					(thickness 0.15)
				)
			)
		)
		(property "Manufacturer" "TE Connectivity"
			(at 0 0 0)
			(layer "F.Fab")
			(hide yes)
			(effects
				(font
					(size 1 1)
					(thickness 0.15)
				)
			)
		)
		(sheetname "M.2 key M #2")
		(sheetfile "m2keym.kicad_sch")
		(attr smd)
		(fp_line
			(start -10.951 -1.401)
			(end -10.951 0.55)
			(stroke
				(width 0.15)
				(type solid)
			)
			(layer "F.SilkS")
		)
		(fp_line
			(start -10.951 2.7)
			(end -10.951 3.999)
			(stroke
				(width 0.15)
				(type solid)
			)
			(layer "F.SilkS")
		)
		(fp_line
			(start -10.951 3.999)
			(end -9.352 3.999)
			(stroke
				(width 0.15)
				(type solid)
			)
			(layer "F.SilkS")
		)
		(fp_line
			(start 5.097 -3.75)
			(end 6.898 -3.75)
			(stroke
				(width 0.15)
				(type solid)
			)
			(layer "F.SilkS")
		)
		(fp_line
			(start 5.347 3.999)
			(end 7.148 3.999)
			(stroke
				(width 0.15)
				(type solid)
			)
			(layer "F.SilkS")
		)
		(fp_line
			(start 9.448 3.999)
			(end 10.948 3.999)
			(stroke
				(width 0.15)
				(type solid)
			)
			(layer "F.SilkS")
		)
		(fp_line
			(start 10.948 0.449)
			(end 10.948 -1.301)
			(stroke
				(width 0.15)
				(type solid)
			)
			(layer "F.SilkS")
		)
		(fp_line
			(start 10.948 3.999)
			(end 10.948 2.3)
			(stroke
				(width 0.15)
				(type solid)
			)
			(layer "F.SilkS")
		)
		(fp_circle
			(center -9.25 -5.651)
			(end -9.2 -5.651)
			(stroke
				(width 0.15)
				(type solid)
			)
			(fill yes)
			(layer "F.SilkS")
		)
		(fp_circle
			(center -9.25 -4.875)
			(end -9.201 -4.826)
			(stroke
				(width 0.15)
				(type solid)
			)
			(fill yes)
			(layer "F.SilkS")
		)
		(fp_line
			(start -11.16 -4.83)
			(end -11.16 4.78)
			(stroke
				(width 0.05)
				(type solid)
			)
			(layer "F.CrtYd")
		)
		(fp_line
			(start -11.16 4.78)
			(end 11.15 4.78)
			(stroke
				(width 0.05)
				(type solid)
			)
			(layer "F.CrtYd")
		)
		(fp_line
			(start 11.15 -4.83)
			(end -11.16 -4.83)
			(stroke
				(width 0.05)
				(type solid)
			)
			(layer "F.CrtYd")
		)
		(fp_line
			(start 11.15 4.78)
			(end 11.15 -4.83)
			(stroke
				(width 0.05)
				(type solid)
			)
			(layer "F.CrtYd")
		)
		(fp_line
			(start -10.949 -3.55)
			(end -10.4 -4.1)
			(stroke
				(width 0.15)
				(type solid)
			)
			(layer "F.Fab")
		)
		(fp_line
			(start -10.949 4.2)
			(end -10.949 -3.55)
			(stroke
				(width 0.15)
				(type solid)
			)
			(layer "F.Fab")
		)
		(fp_line
			(start -10.4 -4.1)
			(end 10.95 -4.1)
			(stroke
				(width 0.15)
				(type solid)
			)
			(layer "F.Fab")
		)
		(fp_line
			(start 10.95 -4.1)
			(end 10.95 4.2)
			(stroke
				(width 0.15)
				(type solid)
			)
			(layer "F.Fab")
		)
		(fp_line
			(start 10.95 4.2)
			(end -10.949 4.2)
			(stroke
				(width 0.15)
				(type solid)
			)
			(layer "F.Fab")
		)
		(pad "" np_thru_hole circle
			(at -10 1.499)
			(size 1.1 1.1)
			(drill 1.1)
			(layers "*.Mask")
		)
		(pad "" np_thru_hole circle
			(at 9.997 1.499)
			(size 1.6 1.6)
			(drill 1.6)
			(layers "*.Mask")
		)
		(pad "1" smd rect
			(at -9.25 -3.775)
			(size 0.3 1.55)
			(layers "F.Cu" "F.Mask" "F.Paste")
			(net 1 "GND")
			(pinfunction "GND")
			(pintype "power_in")
			(teardrops
				(best_length_ratio 0.2)
				(max_length 1)
				(best_width_ratio 0.9)
				(max_width 2)
				(curved_edges yes)
				(filter_ratio 0.9)
				(enabled yes)
				(allow_two_segments yes)
				(prefer_zone_connections yes)
			)
		)
		(pad "2" smd rect
			(at -9.003 3.773)
			(size 0.3 1.55)
			(layers "F.Cu" "F.Mask" "F.Paste")
			(net 970 "/M.2 key M #2/M2_3V3")
			(pinfunction "3V3")
			(pintype "passive")
			(teardrops
				(best_length_ratio 0.2)
				(max_length 1)
				(best_width_ratio 0.9)
				(max_width 2)
				(curved_edges yes)
				(filter_ratio 0.9)
				(enabled yes)
				(allow_two_segments yes)
				(prefer_zone_connections yes)
			)
		)
		(pad "3" smd rect
			(at -8.753 -3.775)
			(size 0.3 1.55)
			(layers "F.Cu" "F.Mask" "F.Paste")
			(net 1 "GND")
			(pinfunction "GND")
			(pintype "passive")
			(teardrops
				(best_length_ratio 0.2)
				(max_length 1)
				(best_width_ratio 0.9)
				(max_width 2)
				(curved_edges yes)
				(filter_ratio 0.9)
				(enabled yes)
				(allow_two_segments yes)
				(prefer_zone_connections yes)
			)
		)
		(pad "4" smd rect
			(at -8.503 3.773)
			(size 0.3 1.55)
			(layers "F.Cu" "F.Mask" "F.Paste")
			(net 970 "/M.2 key M #2/M2_3V3")
			(pinfunction "3V3")
			(pintype "passive")
			(teardrops
				(best_length_ratio 0.2)
				(max_length 1)
				(best_width_ratio 0.9)
				(max_width 2)
				(curved_edges yes)
				(filter_ratio 0.9)
				(enabled yes)
				(allow_two_segments yes)
				(prefer_zone_connections yes)
			)
		)
		(pad "5" smd rect
			(at -8.253 -3.775)
			(size 0.3 1.55)
			(layers "F.Cu" "F.Mask" "F.Paste")
			(net 93 "/Com Express 7 Interfaces/PCIe_{B2Ax4}.RX3+")
			(pinfunction "PER3_N")
			(pintype "output")
			(teardrops
				(best_length_ratio 0.2)
				(max_length 1)
				(best_width_ratio 0.9)
				(max_width 2)
				(curved_edges yes)
				(filter_ratio 0.9)
				(enabled yes)
				(allow_two_segments yes)
				(prefer_zone_connections yes)
			)
		)
		(pad "6" smd rect
			(at -8.001 3.773)
			(size 0.3 1.55)
			(layers "F.Cu" "F.Mask" "F.Paste")
			(net 238 "unconnected-(J8-NC-Pad6)")
			(pinfunction "NC")
			(pintype "no_connect")
			(teardrops
				(best_length_ratio 0.2)
				(max_length 1)
				(best_width_ratio 0.9)
				(max_width 2)
				(curved_edges yes)
				(filter_ratio 0.9)
				(enabled yes)
				(allow_two_segments yes)
				(prefer_zone_connections yes)
			)
		)
		(pad "7" smd rect
			(at -7.752 -3.775)
			(size 0.3 1.55)
			(layers "F.Cu" "F.Mask" "F.Paste")
			(net 89 "/Com Express 7 Interfaces/PCIe_{B2Ax4}.RX3-")
			(pinfunction "PER3_P")
			(pintype "output")
			(teardrops
				(best_length_ratio 0.2)
				(max_length 1)
				(best_width_ratio 0.9)
				(max_width 2)
				(curved_edges yes)
				(filter_ratio 0.9)
				(enabled yes)
				(allow_two_segments yes)
				(prefer_zone_connections yes)
			)
		)
		(pad "8" smd rect
			(at -7.502 3.773)
			(size 0.3 1.55)
			(layers "F.Cu" "F.Mask" "F.Paste")
			(net 240 "unconnected-(J8-NC-Pad8)")
			(pinfunction "NC")
			(pintype "no_connect")
			(teardrops
				(best_length_ratio 0.2)
				(max_length 1)
				(best_width_ratio 0.9)
				(max_width 2)
				(curved_edges yes)
				(filter_ratio 0.9)
				(enabled yes)
				(allow_two_segments yes)
				(prefer_zone_connections yes)
			)
		)
		(pad "9" smd rect
			(at -7.252 -3.775)
			(size 0.3 1.55)
			(layers "F.Cu" "F.Mask" "F.Paste")
			(net 1 "GND")
			(pinfunction "GND")
			(pintype "passive")
			(teardrops
				(best_length_ratio 0.2)
				(max_length 1)
				(best_width_ratio 0.9)
				(max_width 2)
				(curved_edges yes)
				(filter_ratio 0.9)
				(enabled yes)
				(allow_two_segments yes)
				(prefer_zone_connections yes)
			)
		)
		(pad "10" smd rect
			(at -7.002 3.773)
			(size 0.3 1.55)
			(layers "F.Cu" "F.Mask" "F.Paste")
			(net 936 "Net-(D14-C)")
			(pinfunction "LED")
			(pintype "passive")
			(teardrops
				(best_length_ratio 0.2)
				(max_length 1)
				(best_width_ratio 0.9)
				(max_width 2)
				(curved_edges yes)
				(filter_ratio 0.9)
				(enabled yes)
				(allow_two_segments yes)
				(prefer_zone_connections yes)
			)
		)
		(pad "11" smd rect
			(at -6.752 -3.775)
			(size 0.3 1.55)
			(layers "F.Cu" "F.Mask" "F.Paste")
			(net 330 "/Com Express 7 Interfaces/PCIe_{B2Ax4}.TX3+")
			(pinfunction "PET3_N")
			(pintype "input")
			(teardrops
				(best_length_ratio 0.2)
				(max_length 1)
				(best_width_ratio 0.9)
				(max_width 2)
				(curved_edges yes)
				(filter_ratio 0.9)
				(enabled yes)
				(allow_two_segments yes)
				(prefer_zone_connections yes)
			)
		)
		(pad "12" smd rect
			(at -6.502 3.773)
			(size 0.3 1.55)
			(layers "F.Cu" "F.Mask" "F.Paste")
			(net 970 "/M.2 key M #2/M2_3V3")
			(pinfunction "3V3")
			(pintype "passive")
			(teardrops
				(best_length_ratio 0.2)
				(max_length 1)
				(best_width_ratio 0.9)
				(max_width 2)
				(curved_edges yes)
				(filter_ratio 0.9)
				(enabled yes)
				(allow_two_segments yes)
				(prefer_zone_connections yes)
			)
		)
		(pad "13" smd rect
			(at -6.252 -3.775)
			(size 0.3 1.55)
			(layers "F.Cu" "F.Mask" "F.Paste")
			(net 331 "/Com Express 7 Interfaces/PCIe_{B2Ax4}.TX3-")
			(pinfunction "PET3_P")
			(pintype "input")
			(teardrops
				(best_length_ratio 0.2)
				(max_length 1)
				(best_width_ratio 0.9)
				(max_width 2)
				(curved_edges yes)
				(filter_ratio 0.9)
				(enabled yes)
				(allow_two_segments yes)
				(prefer_zone_connections yes)
			)
		)
		(pad "14" smd rect
			(at -6.002 3.773)
			(size 0.3 1.55)
			(layers "F.Cu" "F.Mask" "F.Paste")
			(net 970 "/M.2 key M #2/M2_3V3")
			(pinfunction "3V3")
			(pintype "passive")
			(teardrops
				(best_length_ratio 0.2)
				(max_length 1)
				(best_width_ratio 0.9)
				(max_width 2)
				(curved_edges yes)
				(filter_ratio 0.9)
				(enabled yes)
				(allow_two_segments yes)
				(prefer_zone_connections yes)
			)
		)
		(pad "15" smd rect
			(at -5.752 -3.775)
			(size 0.3 1.55)
			(layers "F.Cu" "F.Mask" "F.Paste")
			(net 1 "GND")
			(pinfunction "GND")
			(pintype "passive")
			(teardrops
				(best_length_ratio 0.2)
				(max_length 1)
				(best_width_ratio 0.9)
				(max_width 2)
				(curved_edges yes)
				(filter_ratio 0.9)
				(enabled yes)
				(allow_two_segments yes)
				(prefer_zone_connections yes)
			)
		)
		(pad "16" smd rect
			(at -5.502 3.773)
			(size 0.3 1.55)
			(layers "F.Cu" "F.Mask" "F.Paste")
			(net 970 "/M.2 key M #2/M2_3V3")
			(pinfunction "3V3")
			(pintype "passive")
			(teardrops
				(best_length_ratio 0.2)
				(max_length 1)
				(best_width_ratio 0.9)
				(max_width 2)
				(curved_edges yes)
				(filter_ratio 0.9)
				(enabled yes)
				(allow_two_segments yes)
				(prefer_zone_connections yes)
			)
		)
		(pad "17" smd rect
			(at -5.252 -3.775)
			(size 0.3 1.55)
			(layers "F.Cu" "F.Mask" "F.Paste")
			(net 92 "/Com Express 7 Interfaces/PCIe_{B2Ax4}.RX2+")
			(pinfunction "PER2_N")
			(pintype "output")
			(teardrops
				(best_length_ratio 0.2)
				(max_length 1)
				(best_width_ratio 0.9)
				(max_width 2)
				(curved_edges yes)
				(filter_ratio 0.9)
				(enabled yes)
				(allow_two_segments yes)
				(prefer_zone_connections yes)
			)
		)
		(pad "18" smd rect
			(at -5.002 3.773)
			(size 0.3 1.55)
			(layers "F.Cu" "F.Mask" "F.Paste")
			(net 970 "/M.2 key M #2/M2_3V3")
			(pinfunction "3V3")
			(pintype "passive")
			(teardrops
				(best_length_ratio 0.2)
				(max_length 1)
				(best_width_ratio 0.9)
				(max_width 2)
				(curved_edges yes)
				(filter_ratio 0.9)
				(enabled yes)
				(allow_two_segments yes)
				(prefer_zone_connections yes)
			)
		)
		(pad "19" smd rect
			(at -4.752 -3.775)
			(size 0.3 1.55)
			(layers "F.Cu" "F.Mask" "F.Paste")
			(net 88 "/Com Express 7 Interfaces/PCIe_{B2Ax4}.RX2-")
			(pinfunction "PER2_P")
			(pintype "output")
			(teardrops
				(best_length_ratio 0.2)
				(max_length 1)
				(best_width_ratio 0.9)
				(max_width 2)
				(curved_edges yes)
				(filter_ratio 0.9)
				(enabled yes)
				(allow_two_segments yes)
				(prefer_zone_connections yes)
			)
		)
		(pad "20" smd rect
			(at -4.502 3.773)
			(size 0.3 1.55)
			(layers "F.Cu" "F.Mask" "F.Paste")
			(net 245 "unconnected-(J8-NC-Pad20)")
			(pinfunction "NC")
			(pintype "no_connect")
			(teardrops
				(best_length_ratio 0.2)
				(max_length 1)
				(best_width_ratio 0.9)
				(max_width 2)
				(curved_edges yes)
				(filter_ratio 0.9)
				(enabled yes)
				(allow_two_segments yes)
				(prefer_zone_connections yes)
			)
		)
		(pad "21" smd rect
			(at -4.252 -3.775)
			(size 0.3 1.55)
			(layers "F.Cu" "F.Mask" "F.Paste")
			(net 1 "GND")
			(pinfunction "GND")
			(pintype "passive")
			(teardrops
				(best_length_ratio 0.2)
				(max_length 1)
				(best_width_ratio 0.9)
				(max_width 2)
				(curved_edges yes)
				(filter_ratio 0.9)
				(enabled yes)
				(allow_two_segments yes)
				(prefer_zone_connections yes)
			)
		)
		(pad "22" smd rect
			(at -4.002 3.773)
			(size 0.3 1.55)
			(layers "F.Cu" "F.Mask" "F.Paste")
			(net 246 "unconnected-(J8-NC-Pad22)")
			(pinfunction "NC")
			(pintype "no_connect")
			(teardrops
				(best_length_ratio 0.2)
				(max_length 1)
				(best_width_ratio 0.9)
				(max_width 2)
				(curved_edges yes)
				(filter_ratio 0.9)
				(enabled yes)
				(allow_two_segments yes)
				(prefer_zone_connections yes)
			)
		)
		(pad "23" smd rect
			(at -3.751 -3.775)
			(size 0.3 1.55)
			(layers "F.Cu" "F.Mask" "F.Paste")
			(net 328 "/Com Express 7 Interfaces/PCIe_{B2Ax4}.TX2+")
			(pinfunction "PET2_N")
			(pintype "input")
			(teardrops
				(best_length_ratio 0.2)
				(max_length 1)
				(best_width_ratio 0.9)
				(max_width 2)
				(curved_edges yes)
				(filter_ratio 0.9)
				(enabled yes)
				(allow_two_segments yes)
				(prefer_zone_connections yes)
			)
		)
		(pad "24" smd rect
			(at -3.501 3.773)
			(size 0.3 1.55)
			(layers "F.Cu" "F.Mask" "F.Paste")
			(net 248 "unconnected-(J8-NC-Pad24)")
			(pinfunction "NC")
			(pintype "no_connect")
			(teardrops
				(best_length_ratio 0.2)
				(max_length 1)
				(best_width_ratio 0.9)
				(max_width 2)
				(curved_edges yes)
				(filter_ratio 0.9)
				(enabled yes)
				(allow_two_segments yes)
				(prefer_zone_connections yes)
			)
		)
		(pad "25" smd rect
			(at -3.251 -3.775)
			(size 0.3 1.55)
			(layers "F.Cu" "F.Mask" "F.Paste")
			(net 329 "/Com Express 7 Interfaces/PCIe_{B2Ax4}.TX2-")
			(pinfunction "PET2_P")
			(pintype "input")
			(teardrops
				(best_length_ratio 0.2)
				(max_length 1)
				(best_width_ratio 0.9)
				(max_width 2)
				(curved_edges yes)
				(filter_ratio 0.9)
				(enabled yes)
				(allow_two_segments yes)
				(prefer_zone_connections yes)
			)
		)
		(pad "26" smd rect
			(at -3.001 3.773)
			(size 0.3 1.55)
			(layers "F.Cu" "F.Mask" "F.Paste")
			(net 250 "unconnected-(J8-NC-Pad26)")
			(pinfunction "NC")
			(pintype "no_connect")
			(teardrops
				(best_length_ratio 0.2)
				(max_length 1)
				(best_width_ratio 0.9)
				(max_width 2)
				(curved_edges yes)
				(filter_ratio 0.9)
				(enabled yes)
				(allow_two_segments yes)
				(prefer_zone_connections yes)
			)
		)
		(pad "27" smd rect
			(at -2.751 -3.775)
			(size 0.3 1.55)
			(layers "F.Cu" "F.Mask" "F.Paste")
			(net 1 "GND")
			(pinfunction "GND")
			(pintype "passive")
			(teardrops
				(best_length_ratio 0.2)
				(max_length 1)
				(best_width_ratio 0.9)
				(max_width 2)
				(curved_edges yes)
				(filter_ratio 0.9)
				(enabled yes)
				(allow_two_segments yes)
				(prefer_zone_connections yes)
			)
		)
		(pad "28" smd rect
			(at -2.501 3.773)
			(size 0.3 1.55)
			(layers "F.Cu" "F.Mask" "F.Paste")
			(net 251 "unconnected-(J8-NC-Pad28)")
			(pinfunction "NC")
			(pintype "no_connect")
			(teardrops
				(best_length_ratio 0.2)
				(max_length 1)
				(best_width_ratio 0.9)
				(max_width 2)
				(curved_edges yes)
				(filter_ratio 0.9)
				(enabled yes)
				(allow_two_segments yes)
				(prefer_zone_connections yes)
			)
		)
		(pad "29" smd rect
			(at -2.251 -3.775)
			(size 0.3 1.55)
			(layers "F.Cu" "F.Mask" "F.Paste")
			(net 91 "/Com Express 7 Interfaces/PCIe_{B2Ax4}.RX1+")
			(pinfunction "PER1_N")
			(pintype "output")
			(teardrops
				(best_length_ratio 0.2)
				(max_length 1)
				(best_width_ratio 0.9)
				(max_width 2)
				(curved_edges yes)
				(filter_ratio 0.9)
				(enabled yes)
				(allow_two_segments yes)
				(prefer_zone_connections yes)
			)
		)
		(pad "30" smd rect
			(at -2.001 3.773)
			(size 0.3 1.55)
			(layers "F.Cu" "F.Mask" "F.Paste")
			(net 253 "unconnected-(J8-NC-Pad30)")
			(pinfunction "NC")
			(pintype "no_connect")
			(teardrops
				(best_length_ratio 0.2)
				(max_length 1)
				(best_width_ratio 0.9)
				(max_width 2)
				(curved_edges yes)
				(filter_ratio 0.9)
				(enabled yes)
				(allow_two_segments yes)
				(prefer_zone_connections yes)
			)
		)
		(pad "31" smd rect
			(at -1.752 -3.775)
			(size 0.3 1.55)
			(layers "F.Cu" "F.Mask" "F.Paste")
			(net 87 "/Com Express 7 Interfaces/PCIe_{B2Ax4}.RX1-")
			(pinfunction "PER1_P")
			(pintype "output")
			(teardrops
				(best_length_ratio 0.2)
				(max_length 1)
				(best_width_ratio 0.9)
				(max_width 2)
				(curved_edges yes)
				(filter_ratio 0.9)
				(enabled yes)
				(allow_two_segments yes)
				(prefer_zone_connections yes)
			)
		)
		(pad "32" smd rect
			(at -1.502 3.773)
			(size 0.3 1.55)
			(layers "F.Cu" "F.Mask" "F.Paste")
			(net 255 "unconnected-(J8-NC-Pad32)")
			(pinfunction "NC")
			(pintype "no_connect")
			(teardrops
				(best_length_ratio 0.2)
				(max_length 1)
				(best_width_ratio 0.9)
				(max_width 2)
				(curved_edges yes)
				(filter_ratio 0.9)
				(enabled yes)
				(allow_two_segments yes)
				(prefer_zone_connections yes)
			)
		)
		(pad "33" smd rect
			(at -1.252 -3.775)
			(size 0.3 1.55)
			(layers "F.Cu" "F.Mask" "F.Paste")
			(net 1 "GND")
			(pinfunction "GND")
			(pintype "passive")
			(teardrops
				(best_length_ratio 0.2)
				(max_length 1)
				(best_width_ratio 0.9)
				(max_width 2)
				(curved_edges yes)
				(filter_ratio 0.9)
				(enabled yes)
				(allow_two_segments yes)
				(prefer_zone_connections yes)
			)
		)
		(pad "34" smd rect
			(at -1.002 3.773)
			(size 0.3 1.55)
			(layers "F.Cu" "F.Mask" "F.Paste")
			(net 256 "unconnected-(J8-NC-Pad34)")
			(pinfunction "NC")
			(pintype "no_connect")
			(teardrops
				(best_length_ratio 0.2)
				(max_length 1)
				(best_width_ratio 0.9)
				(max_width 2)
				(curved_edges yes)
				(filter_ratio 0.9)
				(enabled yes)
				(allow_two_segments yes)
				(prefer_zone_connections yes)
			)
		)
		(pad "35" smd rect
			(at -0.751 -3.775)
			(size 0.3 1.55)
			(layers "F.Cu" "F.Mask" "F.Paste")
			(net 326 "/Com Express 7 Interfaces/PCIe_{B2Ax4}.TX1+")
			(pinfunction "PET1_N")
			(pintype "input")
			(teardrops
				(best_length_ratio 0.2)
				(max_length 1)
				(best_width_ratio 0.9)
				(max_width 2)
				(curved_edges yes)
				(filter_ratio 0.9)
				(enabled yes)
				(allow_two_segments yes)
				(prefer_zone_connections yes)
			)
		)
		(pad "36" smd rect
			(at -0.501 3.773)
			(size 0.3 1.55)
			(layers "F.Cu" "F.Mask" "F.Paste")
			(net 258 "unconnected-(J8-NC-Pad36)")
			(pinfunction "NC")
			(pintype "no_connect")
			(teardrops
				(best_length_ratio 0.2)
				(max_length 1)
				(best_width_ratio 0.9)
				(max_width 2)
				(curved_edges yes)
				(filter_ratio 0.9)
				(enabled yes)
				(allow_two_segments yes)
				(prefer_zone_connections yes)
			)
		)
		(pad "37" smd rect
			(at -0.251 -3.775)
			(size 0.3 1.55)
			(layers "F.Cu" "F.Mask" "F.Paste")
			(net 327 "/Com Express 7 Interfaces/PCIe_{B2Ax4}.TX1-")
			(pinfunction "PET1_P")
			(pintype "input")
			(teardrops
				(best_length_ratio 0.2)
				(max_length 1)
				(best_width_ratio 0.9)
				(max_width 2)
				(curved_edges yes)
				(filter_ratio 0.9)
				(enabled yes)
				(allow_two_segments yes)
				(prefer_zone_connections yes)
			)
		)
		(pad "38" smd rect
			(at -0.001 3.773)
			(size 0.3 1.55)
			(layers "F.Cu" "F.Mask" "F.Paste")
			(net 260 "unconnected-(J8-NC-Pad38)")
			(pinfunction "NC")
			(pintype "no_connect")
			(teardrops
				(best_length_ratio 0.2)
				(max_length 1)
				(best_width_ratio 0.9)
				(max_width 2)
				(curved_edges yes)
				(filter_ratio 0.9)
				(enabled yes)
				(allow_two_segments yes)
				(prefer_zone_connections yes)
			)
		)
		(pad "39" smd rect
			(at 0.248 -3.775)
			(size 0.3 1.55)
			(layers "F.Cu" "F.Mask" "F.Paste")
			(net 1 "GND")
			(pinfunction "GND")
			(pintype "passive")
			(teardrops
				(best_length_ratio 0.2)
				(max_length 1)
				(best_width_ratio 0.9)
				(max_width 2)
				(curved_edges yes)
				(filter_ratio 0.9)
				(enabled yes)
				(allow_two_segments yes)
				(prefer_zone_connections yes)
			)
		)
		(pad "40" smd rect
			(at 0.498 3.773)
			(size 0.3 1.55)
			(layers "F.Cu" "F.Mask" "F.Paste")
			(net 261 "unconnected-(J8-SMB_CLK-Pad40)")
			(pinfunction "SMB_CLK")
			(pintype "input+no_connect")
			(teardrops
				(best_length_ratio 0.2)
				(max_length 1)
				(best_width_ratio 0.9)
				(max_width 2)
				(curved_edges yes)
				(filter_ratio 0.9)
				(enabled yes)
				(allow_two_segments yes)
				(prefer_zone_connections yes)
			)
		)
		(pad "41" smd rect
			(at 0.748 -3.775)
			(size 0.3 1.55)
			(layers "F.Cu" "F.Mask" "F.Paste")
			(net 90 "/Com Express 7 Interfaces/PCIe_{B2Ax4}.RX0+")
			(pinfunction "PER0_N")
			(pintype "output")
			(teardrops
				(best_length_ratio 0.2)
				(max_length 1)
				(best_width_ratio 0.9)
				(max_width 2)
				(curved_edges yes)
				(filter_ratio 0.9)
				(enabled yes)
				(allow_two_segments yes)
				(prefer_zone_connections yes)
			)
		)
		(pad "42" smd rect
			(at 0.998 3.773)
			(size 0.3 1.55)
			(layers "F.Cu" "F.Mask" "F.Paste")
			(net 263 "unconnected-(J8-SMB_DATA-Pad42)")
			(pinfunction "SMB_DATA")
			(pintype "bidirectional+no_connect")
			(teardrops
				(best_length_ratio 0.2)
				(max_length 1)
				(best_width_ratio 0.9)
				(max_width 2)
				(curved_edges yes)
				(filter_ratio 0.9)
				(enabled yes)
				(allow_two_segments yes)
				(prefer_zone_connections yes)
			)
		)
		(pad "43" smd rect
			(at 1.249 -3.775)
			(size 0.3 1.55)
			(layers "F.Cu" "F.Mask" "F.Paste")
			(net 86 "/Com Express 7 Interfaces/PCIe_{B2Ax4}.RX0-")
			(pinfunction "PER0_P")
			(pintype "output")
			(teardrops
				(best_length_ratio 0.2)
				(max_length 1)
				(best_width_ratio 0.9)
				(max_width 2)
				(curved_edges yes)
				(filter_ratio 0.9)
				(enabled yes)
				(allow_two_segments yes)
				(prefer_zone_connections yes)
			)
		)
		(pad "44" smd rect
			(at 1.499 3.773)
			(size 0.3 1.55)
			(layers "F.Cu" "F.Mask" "F.Paste")
			(net 265 "unconnected-(J8-ALERT-Pad44)")
			(pinfunction "ALERT")
			(pintype "output+no_connect")
			(teardrops
				(best_length_ratio 0.2)
				(max_length 1)
				(best_width_ratio 0.9)
				(max_width 2)
				(curved_edges yes)
				(filter_ratio 0.9)
				(enabled yes)
				(allow_two_segments yes)
				(prefer_zone_connections yes)
			)
		)
		(pad "45" smd rect
			(at 1.749 -3.775)
			(size 0.3 1.55)
			(layers "F.Cu" "F.Mask" "F.Paste")
			(net 1 "GND")
			(pinfunction "GND")
			(pintype "passive")
			(teardrops
				(best_length_ratio 0.2)
				(max_length 1)
				(best_width_ratio 0.9)
				(max_width 2)
				(curved_edges yes)
				(filter_ratio 0.9)
				(enabled yes)
				(allow_two_segments yes)
				(prefer_zone_connections yes)
			)
		)
		(pad "46" smd rect
			(at 1.999 3.773)
			(size 0.3 1.55)
			(layers "F.Cu" "F.Mask" "F.Paste")
			(net 266 "unconnected-(J8-NC-Pad46)")
			(pinfunction "NC")
			(pintype "no_connect")
			(teardrops
				(best_length_ratio 0.2)
				(max_length 1)
				(best_width_ratio 0.9)
				(max_width 2)
				(curved_edges yes)
				(filter_ratio 0.9)
				(enabled yes)
				(allow_two_segments yes)
				(prefer_zone_connections yes)
			)
		)
		(pad "47" smd rect
			(at 2.249 -3.775)
			(size 0.3 1.55)
			(layers "F.Cu" "F.Mask" "F.Paste")
			(net 324 "/Com Express 7 Interfaces/PCIe_{B2Ax4}.TX0+")
			(pinfunction "PET0_N")
			(pintype "input")
			(teardrops
				(best_length_ratio 0.2)
				(max_length 1)
				(best_width_ratio 0.9)
				(max_width 2)
				(curved_edges yes)
				(filter_ratio 0.9)
				(enabled yes)
				(allow_two_segments yes)
				(prefer_zone_connections yes)
			)
		)
		(pad "48" smd rect
			(at 2.499 3.773)
			(size 0.3 1.55)
			(layers "F.Cu" "F.Mask" "F.Paste")
			(net 268 "unconnected-(J8-NC-Pad48)")
			(pinfunction "NC")
			(pintype "no_connect")
			(teardrops
				(best_length_ratio 0.2)
				(max_length 1)
				(best_width_ratio 0.9)
				(max_width 2)
				(curved_edges yes)
				(filter_ratio 0.9)
				(enabled yes)
				(allow_two_segments yes)
				(prefer_zone_connections yes)
			)
		)
		(pad "49" smd rect
			(at 2.749 -3.775)
			(size 0.3 1.55)
			(layers "F.Cu" "F.Mask" "F.Paste")
			(net 325 "/Com Express 7 Interfaces/PCIe_{B2Ax4}.TX0-")
			(pinfunction "PET0_P")
			(pintype "input")
			(teardrops
				(best_length_ratio 0.2)
				(max_length 1)
				(best_width_ratio 0.9)
				(max_width 2)
				(curved_edges yes)
				(filter_ratio 0.9)
				(enabled yes)
				(allow_two_segments yes)
				(prefer_zone_connections yes)
			)
		)
		(pad "50" smd rect
			(at 2.999 3.773)
			(size 0.3 1.55)
			(layers "F.Cu" "F.Mask" "F.Paste")
			(net 270 "/M.2 key M #2/~{PERST_D}")
			(pinfunction "~{PERST}")
			(pintype "input")
			(teardrops
				(best_length_ratio 0.2)
				(max_length 1)
				(best_width_ratio 0.9)
				(max_width 2)
				(curved_edges yes)
				(filter_ratio 0.9)
				(enabled yes)
				(allow_two_segments yes)
				(prefer_zone_connections yes)
			)
		)
		(pad "51" smd rect
			(at 3.249 -3.775)
			(size 0.3 1.55)
			(layers "F.Cu" "F.Mask" "F.Paste")
			(net 1 "GND")
			(pinfunction "GND")
			(pintype "passive")
			(teardrops
				(best_length_ratio 0.2)
				(max_length 1)
				(best_width_ratio 0.9)
				(max_width 2)
				(curved_edges yes)
				(filter_ratio 0.9)
				(enabled yes)
				(allow_two_segments yes)
				(prefer_zone_connections yes)
			)
		)
		(pad "52" smd rect
			(at 3.499 3.773)
			(size 0.3 1.55)
			(layers "F.Cu" "F.Mask" "F.Paste")
			(net 530 "/M.2 key M #2/~{CLKREQ}")
			(pinfunction "~{CLKREQ}")
			(pintype "output")
			(teardrops
				(best_length_ratio 0.2)
				(max_length 1)
				(best_width_ratio 0.9)
				(max_width 2)
				(curved_edges yes)
				(filter_ratio 0.9)
				(enabled yes)
				(allow_two_segments yes)
				(prefer_zone_connections yes)
			)
		)
		(pad "53" smd rect
			(at 3.749 -3.775)
			(size 0.3 1.55)
			(layers "F.Cu" "F.Mask" "F.Paste")
			(net 271 "/M.2 key M #2/PCIE_{REF}.CK-")
			(pinfunction "REFCLK_N")
			(pintype "input")
			(teardrops
				(best_length_ratio 0.2)
				(max_length 1)
				(best_width_ratio 0.9)
				(max_width 2)
				(curved_edges yes)
				(filter_ratio 0.9)
				(enabled yes)
				(allow_two_segments yes)
				(prefer_zone_connections yes)
			)
		)
		(pad "54" smd rect
			(at 3.999 3.773)
			(size 0.3 1.55)
			(layers "F.Cu" "F.Mask" "F.Paste")
			(net 272 "unconnected-(J8-~{PEWAKE}-Pad54)")
			(pinfunction "~{PEWAKE}")
			(pintype "input+no_connect")
			(teardrops
				(best_length_ratio 0.2)
				(max_length 1)
				(best_width_ratio 0.9)
				(max_width 2)
				(curved_edges yes)
				(filter_ratio 0.9)
				(enabled yes)
				(allow_two_segments yes)
				(prefer_zone_connections yes)
			)
		)
		(pad "55" smd rect
			(at 4.248 -3.775)
			(size 0.3 1.55)
			(layers "F.Cu" "F.Mask" "F.Paste")
			(net 273 "/M.2 key M #2/PCIE_{REF}.CK+")
			(pinfunction "REFCLK_P")
			(pintype "input")
			(teardrops
				(best_length_ratio 0.2)
				(max_length 1)
				(best_width_ratio 0.9)
				(max_width 2)
				(curved_edges yes)
				(filter_ratio 0.9)
				(enabled yes)
				(allow_two_segments yes)
				(prefer_zone_connections yes)
			)
		)
		(pad "56" smd rect
			(at 4.498 3.773)
			(size 0.3 1.55)
			(layers "F.Cu" "F.Mask" "F.Paste")
			(net 274 "unconnected-(J8-NC-Pad56)")
			(pinfunction "NC")
			(pintype "no_connect")
			(teardrops
				(best_length_ratio 0.2)
				(max_length 1)
				(best_width_ratio 0.9)
				(max_width 2)
				(curved_edges yes)
				(filter_ratio 0.9)
				(enabled yes)
				(allow_two_segments yes)
				(prefer_zone_connections yes)
			)
		)
		(pad "57" smd rect
			(at 4.748 -3.775)
			(size 0.3 1.55)
			(layers "F.Cu" "F.Mask" "F.Paste")
			(net 1 "GND")
			(pinfunction "GND")
			(pintype "passive")
			(teardrops
				(best_length_ratio 0.2)
				(max_length 1)
				(best_width_ratio 0.9)
				(max_width 2)
				(curved_edges yes)
				(filter_ratio 0.9)
				(enabled yes)
				(allow_two_segments yes)
				(prefer_zone_connections yes)
			)
		)
		(pad "58" smd rect
			(at 4.998 3.773)
			(size 0.3 1.55)
			(layers "F.Cu" "F.Mask" "F.Paste")
			(net 275 "unconnected-(J8-NC-Pad58)")
			(pinfunction "NC")
			(pintype "no_connect")
			(teardrops
				(best_length_ratio 0.2)
				(max_length 1)
				(best_width_ratio 0.9)
				(max_width 2)
				(curved_edges yes)
				(filter_ratio 0.9)
				(enabled yes)
				(allow_two_segments yes)
				(prefer_zone_connections yes)
			)
		)
		(pad "67" smd rect
			(at 7.248 -3.775)
			(size 0.3 1.55)
			(layers "F.Cu" "F.Mask" "F.Paste")
			(net 276 "unconnected-(J8-NC-Pad67)")
			(pinfunction "NC")
			(pintype "no_connect")
			(teardrops
				(best_length_ratio 0.2)
				(max_length 1)
				(best_width_ratio 0.9)
				(max_width 2)
				(curved_edges yes)
				(filter_ratio 0.9)
				(enabled yes)
				(allow_two_segments yes)
				(prefer_zone_connections yes)
			)
		)
		(pad "68" smd rect
			(at 7.498 3.773)
			(size 0.3 1.55)
			(layers "F.Cu" "F.Mask" "F.Paste")
			(net 277 "Net-(J8-SUSCLK)")
			(pinfunction "SUSCLK")
			(pintype "input")
			(teardrops
				(best_length_ratio 0.2)
				(max_length 1)
				(best_width_ratio 0.9)
				(max_width 2)
				(curved_edges yes)
				(filter_ratio 0.9)
				(enabled yes)
				(allow_two_segments yes)
				(prefer_zone_connections yes)
			)
		)
		(pad "69" smd rect
			(at 7.748 -3.775)
			(size 0.3 1.55)
			(layers "F.Cu" "F.Mask" "F.Paste")
			(net 278 "unconnected-(J8-NC-Pad69)")
			(pinfunction "NC")
			(pintype "no_connect")
			(teardrops
				(best_length_ratio 0.2)
				(max_length 1)
				(best_width_ratio 0.9)
				(max_width 2)
				(curved_edges yes)
				(filter_ratio 0.9)
				(enabled yes)
				(allow_two_segments yes)
				(prefer_zone_connections yes)
			)
		)
		(pad "70" smd rect
			(at 7.998 3.773)
			(size 0.3 1.55)
			(layers "F.Cu" "F.Mask" "F.Paste")
			(net 970 "/M.2 key M #2/M2_3V3")
			(pinfunction "3V3")
			(pintype "passive")
			(teardrops
				(best_length_ratio 0.2)
				(max_length 1)
				(best_width_ratio 0.9)
				(max_width 2)
				(curved_edges yes)
				(filter_ratio 0.9)
				(enabled yes)
				(allow_two_segments yes)
				(prefer_zone_connections yes)
			)
		)
		(pad "71" smd rect
			(at 8.247 -3.775)
			(size 0.3 1.55)
			(layers "F.Cu" "F.Mask" "F.Paste")
			(net 1 "GND")
			(pinfunction "GND")
			(pintype "passive")
			(teardrops
				(best_length_ratio 0.2)
				(max_length 1)
				(best_width_ratio 0.9)
				(max_width 2)
				(curved_edges yes)
				(filter_ratio 0.9)
				(enabled yes)
				(allow_two_segments yes)
				(prefer_zone_connections yes)
			)
		)
		(pad "72" smd rect
			(at 8.497 3.773)
			(size 0.3 1.55)
			(layers "F.Cu" "F.Mask" "F.Paste")
			(net 970 "/M.2 key M #2/M2_3V3")
			(pinfunction "3V3")
			(pintype "passive")
			(teardrops
				(best_length_ratio 0.2)
				(max_length 1)
				(best_width_ratio 0.9)
				(max_width 2)
				(curved_edges yes)
				(filter_ratio 0.9)
				(enabled yes)
				(allow_two_segments yes)
				(prefer_zone_connections yes)
			)
		)
		(pad "73" smd rect
			(at 8.747 -3.775)
			(size 0.3 1.55)
			(layers "F.Cu" "F.Mask" "F.Paste")
			(net 1 "GND")
			(pinfunction "GND")
			(pintype "passive")
			(teardrops
				(best_length_ratio 0.2)
				(max_length 1)
				(best_width_ratio 0.9)
				(max_width 2)
				(curved_edges yes)
				(filter_ratio 0.9)
				(enabled yes)
				(allow_two_segments yes)
				(prefer_zone_connections yes)
			)
		)
		(pad "74" smd rect
			(at 8.997 3.773)
			(size 0.3 1.55)
			(layers "F.Cu" "F.Mask" "F.Paste")
			(net 970 "/M.2 key M #2/M2_3V3")
			(pinfunction "3V3")
			(pintype "passive")
			(teardrops
				(best_length_ratio 0.2)
				(max_length 1)
				(best_width_ratio 0.9)
				(max_width 2)
				(curved_edges yes)
				(filter_ratio 0.9)
				(enabled yes)
				(allow_two_segments yes)
				(prefer_zone_connections yes)
			)
		)
		(pad "75" smd rect
			(at 9.247 -3.775)
			(size 0.3 1.55)
			(layers "F.Cu" "F.Mask" "F.Paste")
			(net 1 "GND")
			(pinfunction "GND")
			(pintype "passive")
			(teardrops
				(best_length_ratio 0.2)
				(max_length 1)
				(best_width_ratio 0.9)
				(max_width 2)
				(curved_edges yes)
				(filter_ratio 0.9)
				(enabled yes)
				(allow_two_segments yes)
				(prefer_zone_connections yes)
			)
		)
		(pad "MP1" smd rect
			(at -10.352 -3)
			(size 1.2 2.75)
			(layers "F.Cu" "F.Mask" "F.Paste")
			(net 1 "GND")
			(pinfunction "MP")
			(pintype "passive")
			(teardrops
				(best_length_ratio 0.2)
				(max_length 1)
				(best_width_ratio 0.9)
				(max_width 2)
				(curved_edges yes)
				(filter_ratio 0.9)
				(enabled yes)
				(allow_two_segments yes)
				(prefer_zone_connections yes)
			)
		)
		(pad "MP2" smd rect
			(at 10.349 -3)
			(size 1.2 2.75)
			(layers "F.Cu" "F.Mask" "F.Paste")
			(net 1 "GND")
			(pinfunction "MP")
			(pintype "passive")
			(teardrops
				(best_length_ratio 0.2)
				(max_length 1)
				(best_width_ratio 0.9)
				(max_width 2)
				(curved_edges yes)
				(filter_ratio 0.9)
				(enabled yes)
				(allow_two_segments yes)
				(prefer_zone_connections yes)
			)
		)
	)
	(footprint "antmicro-footprints:R_0402_1005Metric"
		(layer "F.Cu")
		(at 143 135.88 180)
		(descr "Resistor SMD 0402")
		(tags "resistor SMD 0402")
		(property "Reference" "R246"
			(at 0.75 -0.43 0)
			(layer "F.SilkS")
			(effects
				(font
					(size 0.7 0.7)
					(thickness 0.15)
				)
				(justify right bottom)
			)
		)
		(property "Value" "R_100k_0402"
			(at -1.011843 1.772047 0)
			(layer "F.Fab")
			(effects
				(font
					(size 0.7 0.7)
					(thickness 0.15)
				)
				(justify right bottom)
			)
		)
		(property "Datasheet" "https://www.bourns.com/docs/product-datasheets/cr.pdf"
			(at 0 0 180)
			(layer "F.Fab")
			(hide yes)
			(effects
				(font
					(size 1.27 1.27)
					(thickness 0.15)
				)
			)
		)
		(property "Author" "Antmicro"
			(at 286 271.76 0)
			(layer "F.Fab")
			(hide yes)
			(effects
				(font
					(size 1 1)
					(thickness 0.15)
				)
			)
		)
		(property "License" "Apache-2.0"
			(at 286 271.76 0)
			(layer "F.Fab")
			(hide yes)
			(effects
				(font
					(size 1 1)
					(thickness 0.15)
				)
			)
		)
		(property "MPN" "CR0402-FX-1003GLF"
			(at 286 271.76 0)
			(layer "F.Fab")
			(hide yes)
			(effects
				(font
					(size 1 1)
					(thickness 0.15)
				)
			)
		)
		(property "Manufacturer" "Bourns"
			(at 286 271.76 0)
			(layer "F.Fab")
			(hide yes)
			(effects
				(font
					(size 1 1)
					(thickness 0.15)
				)
			)
		)
		(property "Public" "False"
			(at 286 271.76 0)
			(layer "F.Fab")
			(hide yes)
			(effects
				(font
					(size 1 1)
					(thickness 0.15)
				)
			)
		)
		(property "Tolerance" "1%"
			(at 286 271.76 0)
			(layer "F.Fab")
			(hide yes)
			(effects
				(font
					(size 1 1)
					(thickness 0.15)
				)
			)
		)
		(property "Val" "100k"
			(at 286 271.76 0)
			(layer "F.Fab")
			(hide yes)
			(effects
				(font
					(size 1 1)
					(thickness 0.15)
				)
			)
		)
		(sheetname "KR to SFI #1")
		(sheetfile "kr_sfi.kicad_sch")
		(attr smd)
		(fp_rect
			(start -0.925 -0.47)
			(end 0.925 0.47)
			(stroke
				(width 0.05)
				(type default)
			)
			(fill no)
			(layer "F.CrtYd")
		)
		(fp_rect
			(start -0.5 -0.25)
			(end 0.5 0.25)
			(stroke
				(width 0.15)
				(type solid)
			)
			(fill no)
			(layer "F.Fab")
		)
		(pad "1" smd roundrect
			(at -0.48 0 180)
			(size 0.59 0.64)
			(layers "F.Cu" "F.Mask" "F.Paste")
			(roundrect_rratio 0.25)
			(net 2 "+3V3")
			(pintype "passive")
			(teardrops
				(best_length_ratio 0.2)
				(max_length 1)
				(best_width_ratio 0.9)
				(max_width 2)
				(curved_edges yes)
				(filter_ratio 0.9)
				(enabled yes)
				(allow_two_segments yes)
				(prefer_zone_connections yes)
			)
		)
		(pad "2" smd roundrect
			(at 0.48 0 180)
			(size 0.59 0.64)
			(layers "F.Cu" "F.Mask" "F.Paste")
			(roundrect_rratio 0.25)
			(net 647 "Net-(Y2-EN)")
			(pintype "passive")
			(teardrops
				(best_length_ratio 0.2)
				(max_length 1)
				(best_width_ratio 0.9)
				(max_width 2)
				(curved_edges yes)
				(filter_ratio 0.9)
				(enabled yes)
				(allow_two_segments yes)
				(prefer_zone_connections yes)
			)
		)
	)
	(footprint "antmicro-footprints:LED_0603_1608Metric_G"
		(layer "F.Cu")
		(at 114.95 69.86 90)
		(descr "LED SMD 0603 Green")
		(tags "LED SMD 0603 Green")
		(property "Reference" "D16"
			(at -3.4 0.45 90)
			(layer "F.SilkS")
			(effects
				(font
					(size 0.7 0.7)
					(thickness 0.15)
				)
				(justify left bottom)
			)
		)
		(property "Value" "LED_G_0603_LTST-C190GKT"
			(at -0.001 1.599 90)
			(layer "F.Fab")
			(effects
				(font
					(size 0.7 0.7)
					(thickness 0.15)
				)
				(justify left bottom)
			)
		)
		(property "Datasheet" "https://media.digikey.com/pdf/Data%20Sheets/Lite-On%20PDFs/LTST-C190GKT.pdf"
			(at 0 0 90)
			(layer "F.Fab")
			(hide yes)
			(effects
				(font
					(size 1.27 1.27)
					(thickness 0.15)
				)
			)
		)
		(property "Author" "Antmicro"
			(at 184.81 -45.09 0)
			(layer "F.Fab")
			(hide yes)
			(effects
				(font
					(size 1 1)
					(thickness 0.15)
				)
			)
		)
		(property "Color" "Green"
			(at 184.81 -45.09 0)
			(layer "F.Fab")
			(hide yes)
			(effects
				(font
					(size 1 1)
					(thickness 0.15)
				)
			)
		)
		(property "License" "Apache-2.0"
			(at 184.81 -45.09 0)
			(layer "F.Fab")
			(hide yes)
			(effects
				(font
					(size 1 1)
					(thickness 0.15)
				)
			)
		)
		(property "MPN" "LTST-C190GKT"
			(at 184.81 -45.09 0)
			(layer "F.Fab")
			(hide yes)
			(effects
				(font
					(size 1 1)
					(thickness 0.15)
				)
			)
		)
		(property "Manufacturer" "Lite-On"
			(at 184.81 -45.09 0)
			(layer "F.Fab")
			(hide yes)
			(effects
				(font
					(size 1 1)
					(thickness 0.15)
				)
			)
		)
		(property "Public" "False"
			(at 184.81 -45.09 0)
			(layer "F.Fab")
			(hide yes)
			(effects
				(font
					(size 1 1)
					(thickness 0.15)
				)
			)
		)
		(sheetname "M.2 key E")
		(sheetfile "m2keye.kicad_sch")
		(attr smd)
		(fp_line
			(start 0.22 -0.35)
			(end -0.22 -0.35)
			(stroke
				(width 0.15)
				(type solid)
			)
			(layer "F.SilkS")
		)
		(fp_line
			(start -1.18 -0.319)
			(end -1.18 0.321)
			(stroke
				(width 0.15)
				(type solid)
			)
			(layer "F.SilkS")
		)
		(fp_line
			(start 0.105328 0.001008)
			(end 0.24 0.001)
			(stroke
				(width 0.1)
				(type solid)
			)
			(layer "F.SilkS")
		)
		(fp_line
			(start -0.094672 0.001008)
			(end 0.105328 -0.198992)
			(stroke
				(width 0.1)
				(type solid)
			)
			(layer "F.SilkS")
		)
		(fp_line
			(start -0.094672 0.001008)
			(end -0.24 0.001008)
			(stroke
				(width 0.1)
				(type solid)
			)
			(layer "F.SilkS")
		)
		(fp_line
			(start 0.105328 0.201008)
			(end 0.105328 -0.198992)
			(stroke
				(width 0.1)
				(type solid)
			)
			(layer "F.SilkS")
		)
		(fp_line
			(start 0.105328 0.201008)
			(end -0.094672 0.001008)
			(stroke
				(width 0.1)
				(type solid)
			)
			(layer "F.SilkS")
		)
		(fp_line
			(start -0.094672 0.201008)
			(end -0.094672 -0.198992)
			(stroke
				(width 0.1)
				(type solid)
			)
			(layer "F.SilkS")
		)
		(fp_line
			(start 0.22 0.35)
			(end -0.22 0.35)
			(stroke
				(width 0.15)
				(type solid)
			)
			(layer "F.SilkS")
		)
		(fp_rect
			(start 1.25 0.65)
			(end -1.25 -0.65)
			(stroke
				(width 0.05)
				(type solid)
			)
			(fill no)
			(layer "F.CrtYd")
		)
		(fp_line
			(start 0.201 -0.202)
			(end -0.101 0)
			(stroke
				(width 0.15)
				(type solid)
			)
			(layer "F.Fab")
		)
		(fp_line
			(start -0.199 -0.202)
			(end -0.199 0.1)
			(stroke
				(width 0.15)
				(type solid)
			)
			(layer "F.Fab")
		)
		(fp_line
			(start 0.599 0)
			(end 0.201 0)
			(stroke
				(width 0.15)
				(type solid)
			)
			(layer "F.Fab")
		)
		(fp_line
			(start 0.201 0)
			(end 0.201 -0.202)
			(stroke
				(width 0.15)
				(type solid)
			)
			(layer "F.Fab")
		)
		(fp_line
			(start -0.101 0)
			(end 0.201 0.2)
			(stroke
				(width 0.15)
				(type solid)
			)
			(layer "F.Fab")
		)
		(fp_line
			(start -0.199 0)
			(end -0.597 0)
			(stroke
				(width 0.15)
				(type solid)
			)
			(layer "F.Fab")
		)
		(fp_line
			(start 0.201 0.2)
			(end 0.201 0)
			(stroke
				(width 0.15)
				(type solid)
			)
			(layer "F.Fab")
		)
		(fp_line
			(start -0.199 0.2)
			(end -0.199 0.1)
			(stroke
				(width 0.15)
				(type solid)
			)
			(layer "F.Fab")
		)
		(fp_rect
			(start 0.848 0.4)
			(end -0.85 -0.402)
			(stroke
				(width 0.15)
				(type solid)
			)
			(fill no)
			(layer "F.Fab")
		)
		(pad "1" smd roundrect
			(at -0.7 0 270)
			(size 0.8 1)
			(layers "F.Cu" "F.Mask" "F.Paste")
			(roundrect_rratio 0.2)
			(net 6 "/M.2 key E/~{LED_2}")
			(pinfunction "C")
			(pintype "passive")
			(teardrops
				(best_length_ratio 0.2)
				(max_length 1)
				(best_width_ratio 0.9)
				(max_width 2)
				(curved_edges yes)
				(filter_ratio 0.9)
				(enabled yes)
				(allow_two_segments yes)
				(prefer_zone_connections yes)
			)
		)
		(pad "2" smd roundrect
			(at 0.7 0 270)
			(size 0.8 1)
			(layers "F.Cu" "F.Mask" "F.Paste")
			(roundrect_rratio 0.2)
			(net 938 "Net-(D16-A)")
			(pinfunction "A")
			(pintype "passive")
			(teardrops
				(best_length_ratio 0.2)
				(max_length 1)
				(best_width_ratio 0.9)
				(max_width 2)
				(curved_edges yes)
				(filter_ratio 0.9)
				(enabled yes)
				(allow_two_segments yes)
				(prefer_zone_connections yes)
			)
		)
	)
	(footprint "antmicro-footprints:R_0402_1005Metric"
		(layer "F.Cu")
		(at 124.84 132.88)
		(descr "Resistor SMD 0402")
		(tags "resistor SMD 0402")
		(property "Reference" "R302"
			(at -3.69 0.43 0)
			(layer "F.SilkS")
			(effects
				(font
					(size 0.7 0.7)
					(thickness 0.15)
				)
				(justify left bottom)
			)
		)
		(property "Value" "R_10k_0402"
			(at -1.011843 1.772047 0)
			(layer "F.Fab")
			(effects
				(font
					(size 0.7 0.7)
					(thickness 0.15)
				)
				(justify left bottom)
			)
		)
		(property "Datasheet" "https://www.bourns.com/docs/product-datasheets/cr.pdf"
			(at 0 0 0)
			(layer "F.Fab")
			(hide yes)
			(effects
				(font
					(size 1.27 1.27)
					(thickness 0.15)
				)
			)
		)
		(property "Author" "Antmicro"
			(at 0 0 0)
			(layer "F.Fab")
			(hide yes)
			(effects
				(font
					(size 1 1)
					(thickness 0.15)
				)
			)
		)
		(property "License" "Apache-2.0"
			(at 0 0 0)
			(layer "F.Fab")
			(hide yes)
			(effects
				(font
					(size 1 1)
					(thickness 0.15)
				)
			)
		)
		(property "MPN" "CR0402-FX-1002GLF"
			(at 0 0 0)
			(layer "F.Fab")
			(hide yes)
			(effects
				(font
					(size 1 1)
					(thickness 0.15)
				)
			)
		)
		(property "Manufacturer" "Bourns"
			(at 0 0 0)
			(layer "F.Fab")
			(hide yes)
			(effects
				(font
					(size 1 1)
					(thickness 0.15)
				)
			)
		)
		(property "Public" "False"
			(at 0 0 0)
			(layer "F.Fab")
			(hide yes)
			(effects
				(font
					(size 1 1)
					(thickness 0.15)
				)
			)
		)
		(property "Tolerance" "1%"
			(at 0 0 0)
			(layer "F.Fab")
			(hide yes)
			(effects
				(font
					(size 1 1)
					(thickness 0.15)
				)
			)
		)
		(property "Val" "10k"
			(at 0 0 0)
			(layer "F.Fab")
			(hide yes)
			(effects
				(font
					(size 1 1)
					(thickness 0.15)
				)
			)
		)
		(sheetname "KR to SFI #2")
		(sheetfile "kr_sfi.kicad_sch")
		(attr smd)
		(fp_rect
			(start -0.925 -0.47)
			(end 0.925 0.47)
			(stroke
				(width 0.05)
				(type default)
			)
			(fill no)
			(layer "F.CrtYd")
		)
		(fp_rect
			(start -0.5 -0.25)
			(end 0.5 0.25)
			(stroke
				(width 0.15)
				(type solid)
			)
			(fill no)
			(layer "F.Fab")
		)
		(pad "1" smd roundrect
			(at -0.48 0)
			(size 0.59 0.64)
			(layers "F.Cu" "F.Mask" "F.Paste")
			(roundrect_rratio 0.25)
			(net 1 "GND")
			(pintype "passive")
			(teardrops
				(best_length_ratio 0.2)
				(max_length 1)
				(best_width_ratio 0.9)
				(max_width 2)
				(curved_edges yes)
				(filter_ratio 0.9)
				(enabled yes)
				(allow_two_segments yes)
				(prefer_zone_connections yes)
			)
		)
		(pad "2" smd roundrect
			(at 0.48 0)
			(size 0.59 0.64)
			(layers "F.Cu" "F.Mask" "F.Paste")
			(roundrect_rratio 0.25)
			(net 682 "Net-(U45C-PRTAD4)")
			(pintype "passive")
			(teardrops
				(best_length_ratio 0.2)
				(max_length 1)
				(best_width_ratio 0.9)
				(max_width 2)
				(curved_edges yes)
				(filter_ratio 0.9)
				(enabled yes)
				(allow_two_segments yes)
				(prefer_zone_connections yes)
			)
		)
	)
	(footprint "antmicro-footprints:SOT-23-3"
		(layer "F.Cu")
		(at 289.4 99.41 90)
		(property "Reference" "Q3"
			(at -0.55 -3.15 180)
			(layer "F.SilkS")
			(effects
				(font
					(size 0.7 0.7)
					(thickness 0.15)
				)
				(justify left bottom)
			)
		)
		(property "Value" "BSS138-7-F"
			(at -1.9 2.7 90)
			(layer "F.Fab")
			(effects
				(font
					(size 0.7 0.7)
					(thickness 0.15)
				)
				(justify left bottom)
			)
		)
		(property "Datasheet" "https://www.diodes.com/assets/Datasheets/ds30144.pdf"
			(at 0 0 90)
			(layer "F.Fab")
			(hide yes)
			(effects
				(font
					(size 1.27 1.27)
					(thickness 0.15)
				)
			)
		)
		(property "Author" "Antmicro"
			(at 388.81 -189.99 0)
			(layer "F.Fab")
			(hide yes)
			(effects
				(font
					(size 1 1)
					(thickness 0.15)
				)
			)
		)
		(property "License" "Apache-2.0"
			(at 388.81 -189.99 0)
			(layer "F.Fab")
			(hide yes)
			(effects
				(font
					(size 1 1)
					(thickness 0.15)
				)
			)
		)
		(property "MPN" "BSS138-7-F"
			(at 388.81 -189.99 0)
			(layer "F.Fab")
			(hide yes)
			(effects
				(font
					(size 1 1)
					(thickness 0.15)
				)
			)
		)
		(property "Manufacturer" "Diodes Incorporated"
			(at 388.81 -189.99 0)
			(layer "F.Fab")
			(hide yes)
			(effects
				(font
					(size 1 1)
					(thickness 0.15)
				)
			)
		)
		(sheetname "Power")
		(sheetfile "power.kicad_sch")
		(attr smd)
		(fp_line
			(start 0.7 -1.5)
			(end -0.7 -1.5)
			(stroke
				(width 0.15)
				(type solid)
			)
			(layer "F.SilkS")
		)
		(fp_line
			(start -0.85 -1.35)
			(end -0.7 -1.5)
			(stroke
				(width 0.15)
				(type solid)
			)
			(layer "F.SilkS")
		)
		(fp_line
			(start -1.45 -1.35)
			(end -0.85 -1.35)
			(stroke
				(width 0.15)
				(type solid)
			)
			(layer "F.SilkS")
		)
		(fp_line
			(start 0.7 -0.4)
			(end 0.7 -1.5)
			(stroke
				(width 0.15)
				(type solid)
			)
			(layer "F.SilkS")
		)
		(fp_line
			(start 0.7 0.4)
			(end 0.7 1.5)
			(stroke
				(width 0.15)
				(type solid)
			)
			(layer "F.SilkS")
		)
		(fp_line
			(start 0.7 1.5)
			(end -0.7 1.5)
			(stroke
				(width 0.15)
				(type solid)
			)
			(layer "F.SilkS")
		)
		(fp_line
			(start -0.7 1.5)
			(end -0.7 1.35)
			(stroke
				(width 0.15)
				(type solid)
			)
			(layer "F.SilkS")
		)
		(fp_line
			(start 0.825 -1.6)
			(end 0.825 -0.45)
			(stroke
				(width 0.05)
				(type solid)
			)
			(layer "F.CrtYd")
		)
		(fp_line
			(start -0.9 -1.6)
			(end 0.825 -1.6)
			(stroke
				(width 0.05)
				(type solid)
			)
			(layer "F.CrtYd")
		)
		(fp_line
			(start -0.9 -1.6)
			(end -0.9 -1.4)
			(stroke
				(width 0.05)
				(type solid)
			)
			(layer "F.CrtYd")
		)
		(fp_line
			(start -0.9 -1.4)
			(end -1.75 -1.4)
			(stroke
				(width 0.05)
				(type solid)
			)
			(layer "F.CrtYd")
		)
		(fp_line
			(start -0.85 -0.5)
			(end -1.75 -0.5)
			(stroke
				(width 0.05)
				(type solid)
			)
			(layer "F.CrtYd")
		)
		(fp_line
			(start -1.75 -0.5)
			(end -1.75 -1.4)
			(stroke
				(width 0.05)
				(type solid)
			)
			(layer "F.CrtYd")
		)
		(fp_line
			(start 1.75 -0.45)
			(end 1.75 0.45)
			(stroke
				(width 0.05)
				(type solid)
			)
			(layer "F.CrtYd")
		)
		(fp_line
			(start 0.825 -0.45)
			(end 1.75 -0.45)
			(stroke
				(width 0.05)
				(type solid)
			)
			(layer "F.CrtYd")
		)
		(fp_line
			(start 1.75 0.45)
			(end 0.85 0.45)
			(stroke
				(width 0.05)
				(type solid)
			)
			(layer "F.CrtYd")
		)
		(fp_line
			(start 0.85 0.45)
			(end 0.85 1.65)
			(stroke
				(width 0.05)
				(type solid)
			)
			(layer "F.CrtYd")
		)
		(fp_line
			(start -0.85 0.5)
			(end -0.85 -0.5)
			(stroke
				(width 0.05)
				(type solid)
			)
			(layer "F.CrtYd")
		)
		(fp_line
			(start -1.75 0.5)
			(end -0.85 0.5)
			(stroke
				(width 0.05)
				(type solid)
			)
			(layer "F.CrtYd")
		)
		(fp_line
			(start -0.85 1.4)
			(end -1.75 1.4)
			(stroke
				(width 0.05)
				(type solid)
			)
			(layer "F.CrtYd")
		)
		(fp_line
			(start -1.75 1.4)
			(end -1.75 0.5)
			(stroke
				(width 0.05)
				(type solid)
			)
			(layer "F.CrtYd")
		)
		(fp_line
			(start 0.85 1.65)
			(end -0.85 1.65)
			(stroke
				(width 0.05)
				(type solid)
			)
			(layer "F.CrtYd")
		)
		(fp_line
			(start -0.85 1.65)
			(end -0.85 1.4)
			(stroke
				(width 0.05)
				(type solid)
			)
			(layer "F.CrtYd")
		)
		(fp_line
			(start -0.437 -1.526)
			(end 0.688 -1.526)
			(stroke
				(width 0.15)
				(type solid)
			)
			(layer "F.Fab")
		)
		(fp_line
			(start -0.437 -1.526)
			(end -0.712 -1.325)
			(stroke
				(width 0.15)
				(type solid)
			)
			(layer "F.Fab")
		)
		(fp_line
			(start -0.712 -1.325)
			(end -0.712 1.523)
			(stroke
				(width 0.15)
				(type solid)
			)
			(layer "F.Fab")
		)
		(fp_line
			(start 0.688 1.519)
			(end 0.688 -1.52)
			(stroke
				(width 0.15)
				(type solid)
			)
			(layer "F.Fab")
		)
		(fp_line
			(start -0.712 1.519)
			(end 0.688 1.519)
			(stroke
				(width 0.15)
				(type solid)
			)
			(layer "F.Fab")
		)
		(pad "1" smd roundrect
			(at -1.1 -0.951 90)
			(size 1 0.6)
			(layers "F.Cu" "F.Mask" "F.Paste")
			(roundrect_rratio 0.15)
			(net 535 "Net-(Q3-G)")
			(pinfunction "G")
			(pintype "bidirectional")
			(teardrops
				(best_length_ratio 0.2)
				(max_length 1)
				(best_width_ratio 0.9)
				(max_width 2)
				(curved_edges yes)
				(filter_ratio 0.9)
				(enabled yes)
				(allow_two_segments yes)
				(prefer_zone_connections yes)
			)
		)
		(pad "2" smd roundrect
			(at -1.1 0.949 90)
			(size 1 0.6)
			(layers "F.Cu" "F.Mask" "F.Paste")
			(roundrect_rratio 0.15)
			(net 1 "GND")
			(pinfunction "S")
			(pintype "bidirectional")
			(teardrops
				(best_length_ratio 0.2)
				(max_length 1)
				(best_width_ratio 0.9)
				(max_width 2)
				(curved_edges yes)
				(filter_ratio 0.9)
				(enabled yes)
				(allow_two_segments yes)
				(prefer_zone_connections yes)
			)
		)
		(pad "3" smd roundrect
			(at 1.1 -0.0005 90)
			(size 1 0.6)
			(layers "F.Cu" "F.Mask" "F.Paste")
			(roundrect_rratio 0.15)
			(net 536 "Net-(Q3-D)")
			(pinfunction "D")
			(pintype "bidirectional")
			(teardrops
				(best_length_ratio 0.2)
				(max_length 1)
				(best_width_ratio 0.9)
				(max_width 2)
				(curved_edges yes)
				(filter_ratio 0.9)
				(enabled yes)
				(allow_two_segments yes)
				(prefer_zone_connections yes)
			)
		)
	)
	(footprint "antmicro-footprints:R_0402_1005Metric"
		(layer "F.Cu")
		(at 202 160)
		(descr "Resistor SMD 0402")
		(tags "resistor SMD 0402")
		(property "Reference" "R158"
			(at 1 0.4 0)
			(layer "F.SilkS")
			(effects
				(font
					(size 0.7 0.7)
					(thickness 0.15)
				)
				(justify left bottom)
			)
		)
		(property "Value" "R_10k_0402"
			(at -4.236843 54.437047 0)
			(layer "F.Fab")
			(hide yes)
			(effects
				(font
					(size 0.7 0.7)
					(thickness 0.15)
				)
				(justify left bottom)
			)
		)
		(property "Datasheet" "https://www.bourns.com/docs/product-datasheets/cr.pdf"
			(at 0 0 0)
			(layer "F.Fab")
			(hide yes)
			(effects
				(font
					(size 1.27 1.27)
					(thickness 0.15)
				)
			)
		)
		(property "Author" "Antmicro"
			(at 0 0 0)
			(layer "F.Fab")
			(hide yes)
			(effects
				(font
					(size 1 1)
					(thickness 0.15)
				)
			)
		)
		(property "License" "Apache-2.0"
			(at 0 0 0)
			(layer "F.Fab")
			(hide yes)
			(effects
				(font
					(size 1 1)
					(thickness 0.15)
				)
			)
		)
		(property "MPN" "CR0402-FX-1002GLF"
			(at 0 0 0)
			(layer "F.Fab")
			(hide yes)
			(effects
				(font
					(size 1 1)
					(thickness 0.15)
				)
			)
		)
		(property "Manufacturer" "Bourns"
			(at 0 0 0)
			(layer "F.Fab")
			(hide yes)
			(effects
				(font
					(size 1 1)
					(thickness 0.15)
				)
			)
		)
		(property "Public" "False"
			(at 0 0 0)
			(layer "F.Fab")
			(hide yes)
			(effects
				(font
					(size 1 1)
					(thickness 0.15)
				)
			)
		)
		(property "Tolerance" "1%"
			(at 0 0 0)
			(layer "F.Fab")
			(hide yes)
			(effects
				(font
					(size 1 1)
					(thickness 0.15)
				)
			)
		)
		(property "Val" "10k"
			(at 0 0 0)
			(layer "F.Fab")
			(hide yes)
			(effects
				(font
					(size 1 1)
					(thickness 0.15)
				)
			)
		)
		(sheetname "Com Express 7 Interfaces")
		(sheetfile "com_express_7_interfaces.kicad_sch")
		(attr smd)
		(fp_rect
			(start -0.925 -0.47)
			(end 0.925 0.47)
			(stroke
				(width 0.05)
				(type default)
			)
			(fill no)
			(layer "F.CrtYd")
		)
		(fp_rect
			(start -0.5 -0.25)
			(end 0.5 0.25)
			(stroke
				(width 0.15)
				(type solid)
			)
			(fill no)
			(layer "F.Fab")
		)
		(pad "1" smd roundrect
			(at -0.48 0)
			(size 0.59 0.64)
			(layers "F.Cu" "F.Mask" "F.Paste")
			(roundrect_rratio 0.25)
			(net 1 "GND")
			(pintype "passive")
			(teardrops
				(best_length_ratio 0.2)
				(max_length 1)
				(best_width_ratio 0.9)
				(max_width 2)
				(curved_edges yes)
				(filter_ratio 0.9)
				(enabled yes)
				(allow_two_segments yes)
				(prefer_zone_connections yes)
			)
		)
		(pad "2" smd roundrect
			(at 0.48 0)
			(size 0.59 0.64)
			(layers "F.Cu" "F.Mask" "F.Paste")
			(roundrect_rratio 0.25)
			(net 386 "/Com Express 7 Interfaces/SD_WP")
			(pintype "passive")
			(teardrops
				(best_length_ratio 0.2)
				(max_length 1)
				(best_width_ratio 0.9)
				(max_width 2)
				(curved_edges yes)
				(filter_ratio 0.9)
				(enabled yes)
				(allow_two_segments yes)
				(prefer_zone_connections yes)
			)
		)
	)
	(footprint "antmicro-footprints:R_0402_1005Metric"
		(layer "F.Cu")
		(at 255.975 132.36 90)
		(descr "Resistor SMD 0402")
		(tags "resistor SMD 0402")
		(property "Reference" "R169"
			(at -3.65 0.425 90)
			(layer "F.SilkS")
			(effects
				(font
					(size 0.7 0.7)
					(thickness 0.15)
				)
				(justify left bottom)
			)
		)
		(property "Value" "R_10k_0402"
			(at -1.011843 1.772047 90)
			(layer "F.Fab")
			(effects
				(font
					(size 0.7 0.7)
					(thickness 0.15)
				)
				(justify left bottom)
			)
		)
		(property "Datasheet" "https://www.bourns.com/docs/product-datasheets/cr.pdf"
			(at 0 0 90)
			(layer "F.Fab")
			(hide yes)
			(effects
				(font
					(size 1.27 1.27)
					(thickness 0.15)
				)
			)
		)
		(property "Author" "Antmicro"
			(at 388.335 -123.615 0)
			(layer "F.Fab")
			(hide yes)
			(effects
				(font
					(size 1 1)
					(thickness 0.15)
				)
			)
		)
		(property "License" "Apache-2.0"
			(at 388.335 -123.615 0)
			(layer "F.Fab")
			(hide yes)
			(effects
				(font
					(size 1 1)
					(thickness 0.15)
				)
			)
		)
		(property "MPN" "CR0402-FX-1002GLF"
			(at 388.335 -123.615 0)
			(layer "F.Fab")
			(hide yes)
			(effects
				(font
					(size 1 1)
					(thickness 0.15)
				)
			)
		)
		(property "Manufacturer" "Bourns"
			(at 388.335 -123.615 0)
			(layer "F.Fab")
			(hide yes)
			(effects
				(font
					(size 1 1)
					(thickness 0.15)
				)
			)
		)
		(property "Public" "False"
			(at 388.335 -123.615 0)
			(layer "F.Fab")
			(hide yes)
			(effects
				(font
					(size 1 1)
					(thickness 0.15)
				)
			)
		)
		(property "Tolerance" "1%"
			(at 388.335 -123.615 0)
			(layer "F.Fab")
			(hide yes)
			(effects
				(font
					(size 1 1)
					(thickness 0.15)
				)
			)
		)
		(property "Val" "10k"
			(at 388.335 -123.615 0)
			(layer "F.Fab")
			(hide yes)
			(effects
				(font
					(size 1 1)
					(thickness 0.15)
				)
			)
		)
		(sheetname "Com Express 7 MGMT")
		(sheetfile "com_express_7_mgmt.kicad_sch")
		(attr smd)
		(fp_rect
			(start -0.925 -0.47)
			(end 0.925 0.47)
			(stroke
				(width 0.05)
				(type default)
			)
			(fill no)
			(layer "F.CrtYd")
		)
		(fp_rect
			(start -0.5 -0.25)
			(end 0.5 0.25)
			(stroke
				(width 0.15)
				(type solid)
			)
			(fill no)
			(layer "F.Fab")
		)
		(pad "1" smd roundrect
			(at -0.48 0 90)
			(size 0.59 0.64)
			(layers "F.Cu" "F.Mask" "F.Paste")
			(roundrect_rratio 0.25)
			(net 137 "/Com Express 7 MGMT/~{TYPE2}")
			(pintype "passive")
			(teardrops
				(best_length_ratio 0.2)
				(max_length 1)
				(best_width_ratio 0.9)
				(max_width 2)
				(curved_edges yes)
				(filter_ratio 0.9)
				(enabled yes)
				(allow_two_segments yes)
				(prefer_zone_connections yes)
			)
		)
		(pad "2" smd roundrect
			(at 0.48 0 90)
			(size 0.59 0.64)
			(layers "F.Cu" "F.Mask" "F.Paste")
			(roundrect_rratio 0.25)
			(net 73 "+3V3_AON")
			(pintype "passive")
			(teardrops
				(best_length_ratio 0.2)
				(max_length 1)
				(best_width_ratio 0.9)
				(max_width 2)
				(curved_edges yes)
				(filter_ratio 0.9)
				(enabled yes)
				(allow_two_segments yes)
				(prefer_zone_connections yes)
			)
		)
	)
	(footprint "antmicro-footprints:R_0402_1005Metric"
		(layer "F.Cu")
		(at 126.425 86.060001 180)
		(descr "Resistor SMD 0402")
		(tags "resistor SMD 0402")
		(property "Reference" "R241"
			(at -1.575 -6.4 0)
			(layer "F.SilkS")
			(effects
				(font
					(size 0.7 0.7)
					(thickness 0.15)
				)
				(justify right bottom)
			)
		)
		(property "Value" "R_0R_0402"
			(at -1.011843 1.772047 0)
			(layer "F.Fab")
			(effects
				(font
					(size 0.7 0.7)
					(thickness 0.15)
				)
				(justify right bottom)
			)
		)
		(property "Datasheet" "https://industrial.panasonic.com/cdbs/www-data/pdf/RDA0000/AOA0000C301.pdf"
			(at 0 0 180)
			(layer "F.Fab")
			(hide yes)
			(effects
				(font
					(size 1.27 1.27)
					(thickness 0.15)
				)
			)
		)
		(property "Author" "Antmicro"
			(at 252.85 172.120002 0)
			(layer "F.Fab")
			(hide yes)
			(effects
				(font
					(size 1 1)
					(thickness 0.15)
				)
			)
		)
		(property "Current" "1A"
			(at 252.85 172.120002 0)
			(layer "F.Fab")
			(hide yes)
			(effects
				(font
					(size 1 1)
					(thickness 0.15)
				)
			)
		)
		(property "License" "Apache-2.0"
			(at 252.85 172.120002 0)
			(layer "F.Fab")
			(hide yes)
			(effects
				(font
					(size 1 1)
					(thickness 0.15)
				)
			)
		)
		(property "MPN" "ERJ2GE0R00X"
			(at 252.85 172.120002 0)
			(layer "F.Fab")
			(hide yes)
			(effects
				(font
					(size 1 1)
					(thickness 0.15)
				)
			)
		)
		(property "Manufacturer" "Panasonic"
			(at 252.85 172.120002 0)
			(layer "F.Fab")
			(hide yes)
			(effects
				(font
					(size 1 1)
					(thickness 0.15)
				)
			)
		)
		(property "Public" "False"
			(at 252.85 172.120002 0)
			(layer "F.Fab")
			(hide yes)
			(effects
				(font
					(size 1 1)
					(thickness 0.15)
				)
			)
		)
		(property "Tolerance" ""
			(at 252.85 172.120002 0)
			(layer "F.Fab")
			(hide yes)
			(effects
				(font
					(size 1 1)
					(thickness 0.15)
				)
			)
		)
		(property "Val" "0R"
			(at 252.85 172.120002 0)
			(layer "F.Fab")
			(hide yes)
			(effects
				(font
					(size 1 1)
					(thickness 0.15)
				)
			)
		)
		(sheetname "GPIO expander")
		(sheetfile "gpio_exp.kicad_sch")
		(attr smd)
		(fp_rect
			(start -0.925 -0.47)
			(end 0.925 0.47)
			(stroke
				(width 0.05)
				(type default)
			)
			(fill no)
			(layer "F.CrtYd")
		)
		(fp_rect
			(start -0.5 -0.25)
			(end 0.5 0.25)
			(stroke
				(width 0.15)
				(type solid)
			)
			(fill no)
			(layer "F.Fab")
		)
		(pad "1" smd roundrect
			(at -0.48 0 180)
			(size 0.59 0.64)
			(layers "F.Cu" "F.Mask" "F.Paste")
			(roundrect_rratio 0.25)
			(net 642 "Net-(U41-IO0_3)")
			(pintype "passive")
			(teardrops
				(best_length_ratio 0.2)
				(max_length 1)
				(best_width_ratio 0.9)
				(max_width 2)
				(curved_edges yes)
				(filter_ratio 0.9)
				(enabled yes)
				(allow_two_segments yes)
				(prefer_zone_connections yes)
			)
		)
		(pad "2" smd roundrect
			(at 0.48 0 180)
			(size 0.59 0.64)
			(layers "F.Cu" "F.Mask" "F.Paste")
			(roundrect_rratio 0.25)
			(net 941 "/2xUSB3.0+RJ45/EN_1")
			(pintype "passive")
			(teardrops
				(best_length_ratio 0.2)
				(max_length 1)
				(best_width_ratio 0.9)
				(max_width 2)
				(curved_edges yes)
				(filter_ratio 0.9)
				(enabled yes)
				(allow_two_segments yes)
				(prefer_zone_connections yes)
			)
		)
	)
	(footprint "antmicro-footprints:R_0402_1005Metric"
		(layer "F.Cu")
		(at 123.38 75.81 -90)
		(descr "Resistor SMD 0402")
		(tags "resistor SMD 0402")
		(property "Reference" "R75"
			(at -3 -0.45 90)
			(layer "F.SilkS")
			(effects
				(font
					(size 0.7 0.7)
					(thickness 0.15)
				)
				(justify right bottom)
			)
		)
		(property "Value" "R_0R_0402"
			(at -1.011843 1.772047 90)
			(layer "F.Fab")
			(effects
				(font
					(size 0.7 0.7)
					(thickness 0.15)
				)
				(justify right bottom)
			)
		)
		(property "Datasheet" "https://industrial.panasonic.com/cdbs/www-data/pdf/RDA0000/AOA0000C301.pdf"
			(at 0 0 270)
			(layer "F.Fab")
			(hide yes)
			(effects
				(font
					(size 1.27 1.27)
					(thickness 0.15)
				)
			)
		)
		(property "Author" "Antmicro"
			(at 47.57 199.19 0)
			(layer "F.Fab")
			(hide yes)
			(effects
				(font
					(size 1 1)
					(thickness 0.15)
				)
			)
		)
		(property "Current" "1A"
			(at 47.57 199.19 0)
			(layer "F.Fab")
			(hide yes)
			(effects
				(font
					(size 1 1)
					(thickness 0.15)
				)
			)
		)
		(property "License" "Apache-2.0"
			(at 47.57 199.19 0)
			(layer "F.Fab")
			(hide yes)
			(effects
				(font
					(size 1 1)
					(thickness 0.15)
				)
			)
		)
		(property "MPN" "ERJ2GE0R00X"
			(at 47.57 199.19 0)
			(layer "F.Fab")
			(hide yes)
			(effects
				(font
					(size 1 1)
					(thickness 0.15)
				)
			)
		)
		(property "Manufacturer" "Panasonic"
			(at 47.57 199.19 0)
			(layer "F.Fab")
			(hide yes)
			(effects
				(font
					(size 1 1)
					(thickness 0.15)
				)
			)
		)
		(property "Public" "False"
			(at 47.57 199.19 0)
			(layer "F.Fab")
			(hide yes)
			(effects
				(font
					(size 1 1)
					(thickness 0.15)
				)
			)
		)
		(property "Tolerance" ""
			(at 47.57 199.19 0)
			(layer "F.Fab")
			(hide yes)
			(effects
				(font
					(size 1 1)
					(thickness 0.15)
				)
			)
		)
		(property "Val" "0R"
			(at 47.57 199.19 0)
			(layer "F.Fab")
			(hide yes)
			(effects
				(font
					(size 1 1)
					(thickness 0.15)
				)
			)
		)
		(sheetname "USB-C console")
		(sheetfile "usb-c_console.kicad_sch")
		(attr smd)
		(fp_rect
			(start -0.925 -0.47)
			(end 0.925 0.47)
			(stroke
				(width 0.05)
				(type default)
			)
			(fill no)
			(layer "F.CrtYd")
		)
		(fp_rect
			(start -0.5 -0.25)
			(end 0.5 0.25)
			(stroke
				(width 0.15)
				(type solid)
			)
			(fill no)
			(layer "F.Fab")
		)
		(pad "1" smd roundrect
			(at -0.48 0 270)
			(size 0.59 0.64)
			(layers "F.Cu" "F.Mask" "F.Paste")
			(roundrect_rratio 0.25)
			(net 572 "Net-(U7-A_{2})")
			(pintype "passive")
			(teardrops
				(best_length_ratio 0.2)
				(max_length 1)
				(best_width_ratio 0.9)
				(max_width 2)
				(curved_edges yes)
				(filter_ratio 0.9)
				(enabled yes)
				(allow_two_segments yes)
				(prefer_zone_connections yes)
			)
		)
		(pad "2" smd roundrect
			(at 0.48 0 270)
			(size 0.59 0.64)
			(layers "F.Cu" "F.Mask" "F.Paste")
			(roundrect_rratio 0.25)
			(net 345 "/Com Express 7 MGMT/SER0.RX")
			(pintype "passive")
			(teardrops
				(best_length_ratio 0.2)
				(max_length 1)
				(best_width_ratio 0.9)
				(max_width 2)
				(curved_edges yes)
				(filter_ratio 0.9)
				(enabled yes)
				(allow_two_segments yes)
				(prefer_zone_connections yes)
			)
		)
	)
	(footprint "antmicro-footprints:TP_SMD_0.75mm"
		(layer "F.Cu")
		(at 129.09 129.56)
		(property "Reference" "TP96"
			(at 0.46 -1.25 90)
			(layer "F.SilkS")
			(effects
				(font
					(size 0.7 0.7)
					(thickness 0.15)
				)
				(justify left bottom)
			)
		)
		(property "Value" "TP_0.75mm_SMD"
			(at 0 1.2 0)
			(layer "F.Fab")
			(effects
				(font
					(size 0.7 0.7)
					(thickness 0.15)
				)
				(justify left bottom)
			)
		)
		(property "Author" "Antmicro"
			(at 0 0 0)
			(layer "F.Fab")
			(hide yes)
			(effects
				(font
					(size 1 1)
					(thickness 0.15)
				)
			)
		)
		(property "License" "Apache-2.0"
			(at 0 0 0)
			(layer "F.Fab")
			(hide yes)
			(effects
				(font
					(size 1 1)
					(thickness 0.15)
				)
			)
		)
		(property "MPN" ""
			(at 0 0 0)
			(layer "F.Fab")
			(hide yes)
			(effects
				(font
					(size 1 1)
					(thickness 0.15)
				)
			)
		)
		(property "Manufacturer" ""
			(at 0 0 0)
			(layer "F.Fab")
			(hide yes)
			(effects
				(font
					(size 1 1)
					(thickness 0.15)
				)
			)
		)
		(property "Public" "False"
			(at 0 0 0)
			(layer "F.Fab")
			(hide yes)
			(effects
				(font
					(size 1 1)
					(thickness 0.15)
				)
			)
		)
		(sheetname "KR to SFI #2")
		(sheetfile "kr_sfi.kicad_sch")
		(attr exclude_from_pos_files exclude_from_bom)
		(fp_circle
			(center 0 0)
			(end 0.475 0)
			(stroke
				(width 0.05)
				(type default)
			)
			(fill no)
			(layer "F.CrtYd")
		)
		(pad "1" smd circle
			(at 0 0)
			(size 0.75 0.75)
			(layers "F.Cu" "F.Mask")
			(net 759 "Net-(U45B-LS_OK_{OUT_B})")
			(pinfunction "1")
			(pintype "passive")
			(teardrops
				(best_length_ratio 0.4)
				(max_length 1)
				(best_width_ratio 0.9)
				(max_width 2)
				(curved_edges yes)
				(filter_ratio 0.9)
				(enabled yes)
				(allow_two_segments yes)
				(prefer_zone_connections yes)
			)
		)
	)
	(footprint "antmicro-footprints:TSSOP-8_3x3mm_P0.65mm"
		(layer "F.Cu")
		(at 124.72 149.26 -90)
		(property "Reference" "U44"
			(at -1.075 -2.655 90)
			(layer "F.SilkS")
			(effects
				(font
					(size 0.7 0.7)
					(thickness 0.15)
				)
				(justify right bottom)
			)
		)
		(property "Value" "NTS0102_TSSOP"
			(at 0 2.8 90)
			(layer "F.Fab")
			(effects
				(font
					(size 0.7 0.7)
					(thickness 0.15)
				)
				(justify right bottom)
			)
		)
		(property "Datasheet" "https://www.mouser.com/datasheet/2/302/NTS0102-1127324.pdf"
			(at 0 0 270)
			(layer "F.Fab")
			(hide yes)
			(effects
				(font
					(size 1.27 1.27)
					(thickness 0.15)
				)
			)
		)
		(property "Author" "Antmicro"
			(at -24.54 273.98 0)
			(layer "F.Fab")
			(hide yes)
			(effects
				(font
					(size 1 1)
					(thickness 0.15)
				)
			)
		)
		(property "License" "Apache-2.0"
			(at -24.54 273.98 0)
			(layer "F.Fab")
			(hide yes)
			(effects
				(font
					(size 1 1)
					(thickness 0.15)
				)
			)
		)
		(property "MPN" "NTS0102DP"
			(at -24.54 273.98 0)
			(layer "F.Fab")
			(hide yes)
			(effects
				(font
					(size 1 1)
					(thickness 0.15)
				)
			)
		)
		(property "Manufacturer" "NXP"
			(at -24.54 273.98 0)
			(layer "F.Fab")
			(hide yes)
			(effects
				(font
					(size 1 1)
					(thickness 0.15)
				)
			)
		)
		(sheetname "KR to SFI #2")
		(sheetfile "kr_sfi.kicad_sch")
		(attr smd)
		(fp_line
			(start -1.55 1.561)
			(end 1.552 1.561)
			(stroke
				(width 0.15)
				(type solid)
			)
			(layer "F.SilkS")
		)
		(fp_line
			(start -1.525 -1.537)
			(end 1.552 -1.539)
			(stroke
				(width 0.15)
				(type solid)
			)
			(layer "F.SilkS")
		)
		(fp_circle
			(center -1.87 -1.4)
			(end -1.82 -1.4)
			(stroke
				(width 0.15)
				(type solid)
			)
			(fill yes)
			(layer "F.SilkS")
		)
		(fp_rect
			(start -3.15 -1.789)
			(end 3.15 1.811)
			(stroke
				(width 0.05)
				(type solid)
			)
			(fill no)
			(layer "F.CrtYd")
		)
		(fp_line
			(start -1.55 1.561)
			(end 1.552 1.561)
			(stroke
				(width 0.15)
				(type solid)
			)
			(layer "F.Fab")
		)
		(fp_line
			(start -1.55 -0.937)
			(end -1.55 1.561)
			(stroke
				(width 0.15)
				(type solid)
			)
			(layer "F.Fab")
		)
		(fp_line
			(start -1.55 -0.937)
			(end -0.949 -1.539)
			(stroke
				(width 0.15)
				(type solid)
			)
			(layer "F.Fab")
		)
		(fp_line
			(start -0.949 -1.539)
			(end 1.552 -1.539)
			(stroke
				(width 0.15)
				(type solid)
			)
			(layer "F.Fab")
		)
		(fp_line
			(start 1.552 -1.539)
			(end 1.552 1.561)
			(stroke
				(width 0.15)
				(type solid)
			)
			(layer "F.Fab")
		)
		(pad "1" smd roundrect
			(at -2.148 -0.962 270)
			(size 1.47 0.4)
			(layers "F.Cu" "F.Mask" "F.Paste")
			(roundrect_rratio 0.25)
			(net 429 "/2xSFP+/MDIO1.MDC")
			(pinfunction "B_{2}")
			(pintype "bidirectional")
			(teardrops
				(best_length_ratio 0.2)
				(max_length 1)
				(best_width_ratio 0.9)
				(max_width 2)
				(curved_edges yes)
				(filter_ratio 0.9)
				(enabled yes)
				(allow_two_segments yes)
				(prefer_zone_connections yes)
			)
		)
		(pad "2" smd roundrect
			(at -2.148 -0.313 270)
			(size 1.47 0.4)
			(layers "F.Cu" "F.Mask" "F.Paste")
			(roundrect_rratio 0.25)
			(net 1 "GND")
			(pinfunction "GND")
			(pintype "power_in")
			(teardrops
				(best_length_ratio 0.2)
				(max_length 1)
				(best_width_ratio 0.9)
				(max_width 2)
				(curved_edges yes)
				(filter_ratio 0.9)
				(enabled yes)
				(allow_two_segments yes)
				(prefer_zone_connections yes)
			)
		)
		(pad "3" smd roundrect
			(at -2.148 0.338 270)
			(size 1.47 0.4)
			(layers "F.Cu" "F.Mask" "F.Paste")
			(roundrect_rratio 0.25)
			(net 78 "+1V8")
			(pinfunction "VCC_{A}")
			(pintype "power_in")
			(teardrops
				(best_length_ratio 0.2)
				(max_length 1)
				(best_width_ratio 0.9)
				(max_width 2)
				(curved_edges yes)
				(filter_ratio 0.9)
				(enabled yes)
				(allow_two_segments yes)
				(prefer_zone_connections yes)
			)
		)
		(pad "4" smd roundrect
			(at -2.148 0.987 270)
			(size 1.47 0.4)
			(layers "F.Cu" "F.Mask" "F.Paste")
			(roundrect_rratio 0.25)
			(net 671 "/2xSFP+/KR to SFI #2/MDC_R")
			(pinfunction "A_{2}")
			(pintype "bidirectional")
			(teardrops
				(best_length_ratio 0.2)
				(max_length 1)
				(best_width_ratio 0.9)
				(max_width 2)
				(curved_edges yes)
				(filter_ratio 0.9)
				(enabled yes)
				(allow_two_segments yes)
				(prefer_zone_connections yes)
			)
		)
		(pad "5" smd roundrect
			(at 2.151 0.987 270)
			(size 1.47 0.4)
			(layers "F.Cu" "F.Mask" "F.Paste")
			(roundrect_rratio 0.25)
			(net 669 "/2xSFP+/KR to SFI #2/MDIO_R")
			(pinfunction "A_{1}")
			(pintype "bidirectional")
			(teardrops
				(best_length_ratio 0.2)
				(max_length 1)
				(best_width_ratio 0.9)
				(max_width 2)
				(curved_edges yes)
				(filter_ratio 0.9)
				(enabled yes)
				(allow_two_segments yes)
				(prefer_zone_connections yes)
			)
		)
		(pad "6" smd roundrect
			(at 2.151 0.338 270)
			(size 1.47 0.4)
			(layers "F.Cu" "F.Mask" "F.Paste")
			(roundrect_rratio 0.25)
			(net 78 "+1V8")
			(pinfunction "OE")
			(pintype "input")
			(teardrops
				(best_length_ratio 0.2)
				(max_length 1)
				(best_width_ratio 0.9)
				(max_width 2)
				(curved_edges yes)
				(filter_ratio 0.9)
				(enabled yes)
				(allow_two_segments yes)
				(prefer_zone_connections yes)
			)
		)
		(pad "7" smd roundrect
			(at 2.151 -0.313 270)
			(size 1.47 0.4)
			(layers "F.Cu" "F.Mask" "F.Paste")
			(roundrect_rratio 0.25)
			(net 2 "+3V3")
			(pinfunction "VCC_{B}")
			(pintype "power_in")
			(teardrops
				(best_length_ratio 0.2)
				(max_length 1)
				(best_width_ratio 0.9)
				(max_width 2)
				(curved_edges yes)
				(filter_ratio 0.9)
				(enabled yes)
				(allow_two_segments yes)
				(prefer_zone_connections yes)
			)
		)
		(pad "8" smd roundrect
			(at 2.151 -0.962 270)
			(size 1.47 0.4)
			(layers "F.Cu" "F.Mask" "F.Paste")
			(roundrect_rratio 0.25)
			(net 490 "/2xSFP+/MDIO1.MDIO")
			(pinfunction "B_{1}")
			(pintype "bidirectional")
			(teardrops
				(best_length_ratio 0.2)
				(max_length 1)
				(best_width_ratio 0.9)
				(max_width 2)
				(curved_edges yes)
				(filter_ratio 0.9)
				(enabled yes)
				(allow_two_segments yes)
				(prefer_zone_connections yes)
			)
		)
	)
	(footprint "antmicro-footprints:DFN-8-1EP_3x2mm_P0.5mm_EP1.36x1.46mm"
		(layer "F.Cu")
		(at 238.5 155.41 90)
		(property "Reference" "U31"
			(at -1.18 2.21 270)
			(layer "F.SilkS")
			(effects
				(font
					(size 0.7 0.7)
					(thickness 0.15)
				)
				(justify left bottom)
			)
		)
		(property "Value" "M24C64-F_DFN8"
			(at 0 2.2 90)
			(layer "F.Fab")
			(effects
				(font
					(size 0.7 0.7)
					(thickness 0.15)
				)
				(justify left bottom)
			)
		)
		(property "Datasheet" "https://eu.mouser.com/datasheet/2/389/cd00259166-1797197.pdf"
			(at 0 0 90)
			(layer "F.Fab")
			(hide yes)
			(effects
				(font
					(size 1.27 1.27)
					(thickness 0.15)
				)
			)
		)
		(property "Author" "Antmicro"
			(at 393.91 -83.09 0)
			(layer "F.Fab")
			(hide yes)
			(effects
				(font
					(size 1 1)
					(thickness 0.15)
				)
			)
		)
		(property "License" "Apache-2.0"
			(at 393.91 -83.09 0)
			(layer "F.Fab")
			(hide yes)
			(effects
				(font
					(size 1 1)
					(thickness 0.15)
				)
			)
		)
		(property "MPN" "M24C64-FMC6TG"
			(at 393.91 -83.09 0)
			(layer "F.Fab")
			(hide yes)
			(effects
				(font
					(size 1 1)
					(thickness 0.15)
				)
			)
		)
		(property "Manufacturer" "STMicroelectronics"
			(at 393.91 -83.09 0)
			(layer "F.Fab")
			(hide yes)
			(effects
				(font
					(size 1 1)
					(thickness 0.15)
				)
			)
		)
		(property ki_fp_filters "UFDFPN8DFN8_2X3_STM UFDFPN8DFN8_2X3_STM-M UFDFPN8DFN8_2X3_STM-L")
		(sheetname "Com Express 7 MGMT")
		(sheetfile "com_express_7_mgmt.kicad_sch")
		(attr smd)
		(fp_line
			(start 1.498 -1.12)
			(end -1.511 -1.12)
			(stroke
				(width 0.15)
				(type solid)
			)
			(layer "F.SilkS")
		)
		(fp_line
			(start -1.501 1.111)
			(end 1.518 1.111)
			(stroke
				(width 0.15)
				(type solid)
			)
			(layer "F.SilkS")
		)
		(fp_circle
			(center -1.751 -1.05)
			(end -1.7 -1.05)
			(stroke
				(width 0.15)
				(type solid)
			)
			(fill yes)
			(layer "F.SilkS")
		)
		(fp_line
			(start 1.889 -1.262)
			(end 1.889 1.228)
			(stroke
				(width 0.05)
				(type solid)
			)
			(layer "F.CrtYd")
		)
		(fp_line
			(start -1.901 -1.262)
			(end 1.889 -1.262)
			(stroke
				(width 0.05)
				(type solid)
			)
			(layer "F.CrtYd")
		)
		(fp_line
			(start 1.889 1.228)
			(end -1.901 1.228)
			(stroke
				(width 0.05)
				(type solid)
			)
			(layer "F.CrtYd")
		)
		(fp_line
			(start -1.901 1.228)
			(end -1.901 -1.262)
			(stroke
				(width 0.05)
				(type solid)
			)
			(layer "F.CrtYd")
		)
		(fp_line
			(start 1.498 -0.999)
			(end -1.491 -0.999)
			(stroke
				(width 0.15)
				(type solid)
			)
			(layer "F.Fab")
		)
		(fp_line
			(start 1.498 -0.999)
			(end 1.498 0.99)
			(stroke
				(width 0.15)
				(type solid)
			)
			(layer "F.Fab")
		)
		(fp_line
			(start -1.501 0.99)
			(end -1.501 -0.989)
			(stroke
				(width 0.15)
				(type solid)
			)
			(layer "F.Fab")
		)
		(fp_line
			(start 1.498 0.999)
			(end -1.501 0.999)
			(stroke
				(width 0.15)
				(type solid)
			)
			(layer "F.Fab")
		)
		(pad "1" smd rect
			(at -1.451 -0.749)
			(size 0.3 0.7)
			(layers "F.Cu" "F.Mask" "F.Paste")
			(net 73 "+3V3_AON")
			(pinfunction "E0")
			(pintype "input")
			(teardrops
				(best_length_ratio 0.2)
				(max_length 1)
				(best_width_ratio 0.9)
				(max_width 2)
				(curved_edges yes)
				(filter_ratio 0.9)
				(enabled yes)
				(allow_two_segments yes)
				(prefer_zone_connections yes)
			)
		)
		(pad "2" smd rect
			(at -1.451 -0.25)
			(size 0.3 0.7)
			(layers "F.Cu" "F.Mask" "F.Paste")
			(net 73 "+3V3_AON")
			(pinfunction "E1")
			(pintype "input")
			(teardrops
				(best_length_ratio 0.2)
				(max_length 1)
				(best_width_ratio 0.9)
				(max_width 2)
				(curved_edges yes)
				(filter_ratio 0.9)
				(enabled yes)
				(allow_two_segments yes)
				(prefer_zone_connections yes)
			)
		)
		(pad "3" smd rect
			(at -1.451 0.249)
			(size 0.3 0.7)
			(layers "F.Cu" "F.Mask" "F.Paste")
			(net 73 "+3V3_AON")
			(pinfunction "E2")
			(pintype "input")
			(teardrops
				(best_length_ratio 0.2)
				(max_length 1)
				(best_width_ratio 0.9)
				(max_width 2)
				(curved_edges yes)
				(filter_ratio 0.9)
				(enabled yes)
				(allow_two_segments yes)
				(prefer_zone_connections yes)
			)
		)
		(pad "4" smd rect
			(at -1.451 0.75)
			(size 0.3 0.7)
			(layers "F.Cu" "F.Mask" "F.Paste")
			(net 1 "GND")
			(pinfunction "VSS")
			(pintype "power_in")
			(teardrops
				(best_length_ratio 0.2)
				(max_length 1)
				(best_width_ratio 0.9)
				(max_width 2)
				(curved_edges yes)
				(filter_ratio 0.9)
				(enabled yes)
				(allow_two_segments yes)
				(prefer_zone_connections yes)
			)
		)
		(pad "5" smd rect
			(at 1.448 0.75)
			(size 0.3 0.7)
			(layers "F.Cu" "F.Mask" "F.Paste")
			(net 372 "/Com Express 7 MGMT/I2C.SDA")
			(pinfunction "SDA")
			(pintype "bidirectional")
			(teardrops
				(best_length_ratio 0.2)
				(max_length 1)
				(best_width_ratio 0.9)
				(max_width 2)
				(curved_edges yes)
				(filter_ratio 0.9)
				(enabled yes)
				(allow_two_segments yes)
				(prefer_zone_connections yes)
			)
		)
		(pad "6" smd rect
			(at 1.448 0.249)
			(size 0.3 0.7)
			(layers "F.Cu" "F.Mask" "F.Paste")
			(net 371 "/Com Express 7 MGMT/I2C.SCL")
			(pinfunction "SCL")
			(pintype "input")
			(teardrops
				(best_length_ratio 0.2)
				(max_length 1)
				(best_width_ratio 0.9)
				(max_width 2)
				(curved_edges yes)
				(filter_ratio 0.9)
				(enabled yes)
				(allow_two_segments yes)
				(prefer_zone_connections yes)
			)
		)
		(pad "7" smd rect
			(at 1.448 -0.25)
			(size 0.3 0.7)
			(layers "F.Cu" "F.Mask" "F.Paste")
			(net 598 "Net-(U31-~{WC})")
			(pinfunction "~{WC}")
			(pintype "input")
			(teardrops
				(best_length_ratio 0.2)
				(max_length 1)
				(best_width_ratio 0.9)
				(max_width 2)
				(curved_edges yes)
				(filter_ratio 0.9)
				(enabled yes)
				(allow_two_segments yes)
				(prefer_zone_connections yes)
			)
		)
		(pad "8" smd rect
			(at 1.448 -0.749)
			(size 0.3 0.7)
			(layers "F.Cu" "F.Mask" "F.Paste")
			(net 73 "+3V3_AON")
			(pinfunction "VCC")
			(pintype "power_in")
			(teardrops
				(best_length_ratio 0.2)
				(max_length 1)
				(best_width_ratio 0.9)
				(max_width 2)
				(curved_edges yes)
				(filter_ratio 0.9)
				(enabled yes)
				(allow_two_segments yes)
				(prefer_zone_connections yes)
			)
		)
		(pad "9" smd rect
			(at 0 0)
			(size 1.5 1.7)
			(layers "F.Cu" "F.Mask" "F.Paste")
			(net 1 "GND")
			(pinfunction "VSS")
			(pintype "passive")
			(solder_paste_margin_ratio -0.1)
			(teardrops
				(best_length_ratio 0.2)
				(max_length 1)
				(best_width_ratio 0.9)
				(max_width 2)
				(curved_edges yes)
				(filter_ratio 0.9)
				(enabled no)
				(allow_two_segments yes)
				(prefer_zone_connections yes)
			)
		)
	)
	(footprint "antmicro-footprints:TP_SMD_0.75mm"
		(layer "F.Cu")
		(at 258.35 128.235 90)
		(property "Reference" "TP43"
			(at -0.425 0.4 180)
			(layer "F.SilkS")
			(effects
				(font
					(size 0.7 0.7)
					(thickness 0.15)
				)
				(justify left bottom)
			)
		)
		(property "Value" "TP_0.75mm_SMD"
			(at 0 1.2 90)
			(layer "F.Fab")
			(effects
				(font
					(size 0.7 0.7)
					(thickness 0.15)
				)
				(justify left bottom)
			)
		)
		(property "Author" "Antmicro"
			(at 386.585 -130.115 0)
			(layer "F.Fab")
			(hide yes)
			(effects
				(font
					(size 1 1)
					(thickness 0.15)
				)
			)
		)
		(property "License" "Apache-2.0"
			(at 386.585 -130.115 0)
			(layer "F.Fab")
			(hide yes)
			(effects
				(font
					(size 1 1)
					(thickness 0.15)
				)
			)
		)
		(property "MPN" ""
			(at 386.585 -130.115 0)
			(layer "F.Fab")
			(hide yes)
			(effects
				(font
					(size 1 1)
					(thickness 0.15)
				)
			)
		)
		(property "Manufacturer" ""
			(at 386.585 -130.115 0)
			(layer "F.Fab")
			(hide yes)
			(effects
				(font
					(size 1 1)
					(thickness 0.15)
				)
			)
		)
		(property "Public" "False"
			(at 386.585 -130.115 0)
			(layer "F.Fab")
			(hide yes)
			(effects
				(font
					(size 1 1)
					(thickness 0.15)
				)
			)
		)
		(sheetname "Com Express 7 MGMT")
		(sheetfile "com_express_7_mgmt.kicad_sch")
		(attr exclude_from_pos_files exclude_from_bom)
		(fp_circle
			(center 0 0)
			(end 0.475 0)
			(stroke
				(width 0.05)
				(type default)
			)
			(fill no)
			(layer "F.CrtYd")
		)
		(pad "1" smd circle
			(at 0 0 90)
			(size 0.75 0.75)
			(layers "F.Cu" "F.Mask")
			(net 708 "Net-(U32-~{MR})")
			(pinfunction "1")
			(pintype "passive")
			(teardrops
				(best_length_ratio 0.4)
				(max_length 1)
				(best_width_ratio 0.9)
				(max_width 2)
				(curved_edges yes)
				(filter_ratio 0.9)
				(enabled yes)
				(allow_two_segments yes)
				(prefer_zone_connections yes)
			)
		)
	)
	(footprint "antmicro-footprints:C_0402_1005Metric"
		(layer "F.Cu")
		(at 306.65 153.83 90)
		(descr "Capacitor SMD 0402")
		(tags "capacitor SMD 0402")
		(property "Reference" "C96"
			(at -0.68 -0.5 90)
			(layer "F.SilkS")
			(effects
				(font
					(size 0.7 0.7)
					(thickness 0.15)
				)
				(justify left bottom)
			)
		)
		(property "Value" "C_100n_0402"
			(at -1.022927 2.155213 90)
			(layer "F.Fab")
			(effects
				(font
					(size 0.7 0.7)
					(thickness 0.15)
				)
				(justify left bottom)
			)
		)
		(property "Datasheet" "https://www.murata.com/products/productdetail?partno=GRM155R61H104KE14%23"
			(at 0 0 90)
			(layer "F.Fab")
			(hide yes)
			(effects
				(font
					(size 1.27 1.27)
					(thickness 0.15)
				)
			)
		)
		(property "Author" "Antmicro"
			(at 460.48 -152.82 0)
			(layer "F.Fab")
			(hide yes)
			(effects
				(font
					(size 1 1)
					(thickness 0.15)
				)
			)
		)
		(property "Dielectric" "X5R"
			(at 460.48 -152.82 0)
			(layer "F.Fab")
			(hide yes)
			(effects
				(font
					(size 1 1)
					(thickness 0.15)
				)
			)
		)
		(property "License" "Apache-2.0"
			(at 460.48 -152.82 0)
			(layer "F.Fab")
			(hide yes)
			(effects
				(font
					(size 1 1)
					(thickness 0.15)
				)
			)
		)
		(property "MPN" "GRM155R61H104KE14D"
			(at 460.48 -152.82 0)
			(layer "F.Fab")
			(hide yes)
			(effects
				(font
					(size 1 1)
					(thickness 0.15)
				)
			)
		)
		(property "Manufacturer" "Murata"
			(at 460.48 -152.82 0)
			(layer "F.Fab")
			(hide yes)
			(effects
				(font
					(size 1 1)
					(thickness 0.15)
				)
			)
		)
		(property "Public" "False"
			(at 460.48 -152.82 0)
			(layer "F.Fab")
			(hide yes)
			(effects
				(font
					(size 1 1)
					(thickness 0.15)
				)
			)
		)
		(property "Val" "100n"
			(at 460.48 -152.82 0)
			(layer "F.Fab")
			(hide yes)
			(effects
				(font
					(size 1 1)
					(thickness 0.15)
				)
			)
		)
		(property "Voltage" "50V"
			(at 460.48 -152.82 0)
			(layer "F.Fab")
			(hide yes)
			(effects
				(font
					(size 1 1)
					(thickness 0.15)
				)
			)
		)
		(sheetname "Com Express 7 MGMT")
		(sheetfile "com_express_7_mgmt.kicad_sch")
		(attr smd)
		(fp_rect
			(start -0.925 -0.47)
			(end 0.925 0.47)
			(stroke
				(width 0.05)
				(type default)
			)
			(fill no)
			(layer "F.CrtYd")
		)
		(fp_line
			(start 0.504 -0.25)
			(end 0.504 0.248)
			(stroke
				(width 0.15)
				(type solid)
			)
			(layer "F.Fab")
		)
		(fp_line
			(start -0.494 -0.25)
			(end 0.504 -0.25)
			(stroke
				(width 0.15)
				(type solid)
			)
			(layer "F.Fab")
		)
		(fp_line
			(start 0.504 0.248)
			(end -0.494 0.248)
			(stroke
				(width 0.15)
				(type solid)
			)
			(layer "F.Fab")
		)
		(fp_line
			(start -0.494 0.248)
			(end -0.494 -0.25)
			(stroke
				(width 0.15)
				(type solid)
			)
			(layer "F.Fab")
		)
		(pad "1" smd roundrect
			(at -0.48 0 90)
			(size 0.59 0.64)
			(layers "F.Cu" "F.Mask" "F.Paste")
			(roundrect_rratio 0.25)
			(net 1 "GND")
			(pintype "passive")
			(teardrops
				(best_length_ratio 0.2)
				(max_length 1)
				(best_width_ratio 0.9)
				(max_width 2)
				(curved_edges yes)
				(filter_ratio 0.9)
				(enabled yes)
				(allow_two_segments yes)
				(prefer_zone_connections yes)
			)
		)
		(pad "2" smd roundrect
			(at 0.48 0 90)
			(size 0.59 0.64)
			(layers "F.Cu" "F.Mask" "F.Paste")
			(roundrect_rratio 0.25)
			(net 73 "+3V3_AON")
			(pintype "passive")
			(teardrops
				(best_length_ratio 0.2)
				(max_length 1)
				(best_width_ratio 0.9)
				(max_width 2)
				(curved_edges yes)
				(filter_ratio 0.9)
				(enabled yes)
				(allow_two_segments yes)
				(prefer_zone_connections yes)
			)
		)
	)
	(footprint "antmicro-footprints:C_0402_1005Metric"
		(layer "F.Cu")
		(at 234.970708 75.76)
		(descr "Capacitor SMD 0402")
		(tags "capacitor SMD 0402")
		(property "Reference" "C92"
			(at -3.05 0.45 0)
			(layer "F.SilkS")
			(effects
				(font
					(size 0.7 0.7)
					(thickness 0.15)
				)
				(justify left bottom)
			)
		)
		(property "Value" "C_100n_0402"
			(at -1.022927 2.155213 0)
			(layer "F.Fab")
			(effects
				(font
					(size 0.7 0.7)
					(thickness 0.15)
				)
				(justify left bottom)
			)
		)
		(property "Datasheet" "https://www.murata.com/products/productdetail?partno=GRM155R61H104KE14%23"
			(at 0 0 0)
			(layer "F.Fab")
			(hide yes)
			(effects
				(font
					(size 1.27 1.27)
					(thickness 0.15)
				)
			)
		)
		(property "Author" "Antmicro"
			(at 0 0 0)
			(layer "F.Fab")
			(hide yes)
			(effects
				(font
					(size 1 1)
					(thickness 0.15)
				)
			)
		)
		(property "Dielectric" "X5R"
			(at 0 0 0)
			(layer "F.Fab")
			(hide yes)
			(effects
				(font
					(size 1 1)
					(thickness 0.15)
				)
			)
		)
		(property "License" "Apache-2.0"
			(at 0 0 0)
			(layer "F.Fab")
			(hide yes)
			(effects
				(font
					(size 1 1)
					(thickness 0.15)
				)
			)
		)
		(property "MPN" "GRM155R61H104KE14D"
			(at 0 0 0)
			(layer "F.Fab")
			(hide yes)
			(effects
				(font
					(size 1 1)
					(thickness 0.15)
				)
			)
		)
		(property "Manufacturer" "Murata"
			(at 0 0 0)
			(layer "F.Fab")
			(hide yes)
			(effects
				(font
					(size 1 1)
					(thickness 0.15)
				)
			)
		)
		(property "Public" "False"
			(at 0 0 0)
			(layer "F.Fab")
			(hide yes)
			(effects
				(font
					(size 1 1)
					(thickness 0.15)
				)
			)
		)
		(property "Val" "100n"
			(at 0 0 0)
			(layer "F.Fab")
			(hide yes)
			(effects
				(font
					(size 1 1)
					(thickness 0.15)
				)
			)
		)
		(property "Voltage" "50V"
			(at 0 0 0)
			(layer "F.Fab")
			(hide yes)
			(effects
				(font
					(size 1 1)
					(thickness 0.15)
				)
			)
		)
		(sheetname "Misc")
		(sheetfile "misc.kicad_sch")
		(attr smd)
		(fp_rect
			(start -0.925 -0.47)
			(end 0.925 0.47)
			(stroke
				(width 0.05)
				(type default)
			)
			(fill no)
			(layer "F.CrtYd")
		)
		(fp_line
			(start -0.494 -0.25)
			(end 0.504 -0.25)
			(stroke
				(width 0.15)
				(type solid)
			)
			(layer "F.Fab")
		)
		(fp_line
			(start -0.494 0.248)
			(end -0.494 -0.25)
			(stroke
				(width 0.15)
				(type solid)
			)
			(layer "F.Fab")
		)
		(fp_line
			(start 0.504 -0.25)
			(end 0.504 0.248)
			(stroke
				(width 0.15)
				(type solid)
			)
			(layer "F.Fab")
		)
		(fp_line
			(start 0.504 0.248)
			(end -0.494 0.248)
			(stroke
				(width 0.15)
				(type solid)
			)
			(layer "F.Fab")
		)
		(pad "1" smd roundrect
			(at -0.48 0)
			(size 0.59 0.64)
			(layers "F.Cu" "F.Mask" "F.Paste")
			(roundrect_rratio 0.25)
			(net 1 "GND")
			(pintype "passive")
			(teardrops
				(best_length_ratio 0.2)
				(max_length 1)
				(best_width_ratio 0.9)
				(max_width 2)
				(curved_edges yes)
				(filter_ratio 0.9)
				(enabled yes)
				(allow_two_segments yes)
				(prefer_zone_connections yes)
			)
		)
		(pad "2" smd roundrect
			(at 0.48 0)
			(size 0.59 0.64)
			(layers "F.Cu" "F.Mask" "F.Paste")
			(roundrect_rratio 0.25)
			(net 52 "+5V")
			(pintype "passive")
			(teardrops
				(best_length_ratio 0.2)
				(max_length 1)
				(best_width_ratio 0.9)
				(max_width 2)
				(curved_edges yes)
				(filter_ratio 0.9)
				(enabled yes)
				(allow_two_segments yes)
				(prefer_zone_connections yes)
			)
		)
	)
	(footprint "antmicro-footprints:R_0402_1005Metric"
		(layer "F.Cu")
		(at 208.939 78.11 180)
		(descr "Resistor SMD 0402")
		(tags "resistor SMD 0402")
		(property "Reference" "R180"
			(at -1.511 -1.4 0)
			(layer "F.SilkS")
			(effects
				(font
					(size 0.7 0.7)
					(thickness 0.15)
				)
				(justify right bottom)
			)
		)
		(property "Value" "R_1k_0402"
			(at -1.011843 1.772047 0)
			(layer "F.Fab")
			(effects
				(font
					(size 0.7 0.7)
					(thickness 0.15)
				)
				(justify right bottom)
			)
		)
		(property "Datasheet" "https://www.bourns.com/docs/product-datasheets/cr.pdf"
			(at 0 0 180)
			(layer "F.Fab")
			(hide yes)
			(effects
				(font
					(size 1.27 1.27)
					(thickness 0.15)
				)
			)
		)
		(property "Author" "Antmicro"
			(at 417.878 156.22 0)
			(layer "F.Fab")
			(hide yes)
			(effects
				(font
					(size 1 1)
					(thickness 0.15)
				)
			)
		)
		(property "License" "Apache-2.0"
			(at 417.878 156.22 0)
			(layer "F.Fab")
			(hide yes)
			(effects
				(font
					(size 1 1)
					(thickness 0.15)
				)
			)
		)
		(property "MPN" "CR0402-FX-1001GLF"
			(at 417.878 156.22 0)
			(layer "F.Fab")
			(hide yes)
			(effects
				(font
					(size 1 1)
					(thickness 0.15)
				)
			)
		)
		(property "Manufacturer" "Bourns"
			(at 417.878 156.22 0)
			(layer "F.Fab")
			(hide yes)
			(effects
				(font
					(size 1 1)
					(thickness 0.15)
				)
			)
		)
		(property "Public" "False"
			(at 417.878 156.22 0)
			(layer "F.Fab")
			(hide yes)
			(effects
				(font
					(size 1 1)
					(thickness 0.15)
				)
			)
		)
		(property "Tolerance" "1%"
			(at 417.878 156.22 0)
			(layer "F.Fab")
			(hide yes)
			(effects
				(font
					(size 1 1)
					(thickness 0.15)
				)
			)
		)
		(property "Val" "1k"
			(at 417.878 156.22 0)
			(layer "F.Fab")
			(hide yes)
			(effects
				(font
					(size 1 1)
					(thickness 0.15)
				)
			)
		)
		(sheetname "Com Express 7 MGMT")
		(sheetfile "com_express_7_mgmt.kicad_sch")
		(attr smd)
		(fp_rect
			(start -0.925 -0.47)
			(end 0.925 0.47)
			(stroke
				(width 0.05)
				(type default)
			)
			(fill no)
			(layer "F.CrtYd")
		)
		(fp_rect
			(start -0.5 -0.25)
			(end 0.5 0.25)
			(stroke
				(width 0.15)
				(type solid)
			)
			(fill no)
			(layer "F.Fab")
		)
		(pad "1" smd roundrect
			(at -0.48 0 180)
			(size 0.59 0.64)
			(layers "F.Cu" "F.Mask" "F.Paste")
			(roundrect_rratio 0.25)
			(net 310 "/Com Express 7 MGMT/~{BIOS_DIS0}")
			(pintype "passive")
			(teardrops
				(best_length_ratio 0.2)
				(max_length 1)
				(best_width_ratio 0.9)
				(max_width 2)
				(curved_edges yes)
				(filter_ratio 0.9)
				(enabled yes)
				(allow_two_segments yes)
				(prefer_zone_connections yes)
			)
		)
		(pad "2" smd roundrect
			(at 0.48 0 180)
			(size 0.59 0.64)
			(layers "F.Cu" "F.Mask" "F.Paste")
			(roundrect_rratio 0.25)
			(net 525 "Net-(J14-Pad2)")
			(pintype "passive")
			(teardrops
				(best_length_ratio 0.2)
				(max_length 1)
				(best_width_ratio 0.9)
				(max_width 2)
				(curved_edges yes)
				(filter_ratio 0.9)
				(enabled yes)
				(allow_two_segments yes)
				(prefer_zone_connections yes)
			)
		)
	)
	(footprint "antmicro-footprints:R_0402_1005Metric"
		(layer "F.Cu")
		(at 121.4 147.361 90)
		(descr "Resistor SMD 0402")
		(tags "resistor SMD 0402")
		(property "Reference" "R218"
			(at -3.749 0.45 90)
			(layer "F.SilkS")
			(effects
				(font
					(size 0.7 0.7)
					(thickness 0.15)
				)
				(justify left bottom)
			)
		)
		(property "Value" "R_0R_0402"
			(at -1.011843 1.772047 90)
			(layer "F.Fab")
			(effects
				(font
					(size 0.7 0.7)
					(thickness 0.15)
				)
				(justify left bottom)
			)
		)
		(property "Datasheet" "https://industrial.panasonic.com/cdbs/www-data/pdf/RDA0000/AOA0000C301.pdf"
			(at 0 0 90)
			(layer "F.Fab")
			(hide yes)
			(effects
				(font
					(size 1.27 1.27)
					(thickness 0.15)
				)
			)
		)
		(property "Author" "Antmicro"
			(at 268.761 25.961 0)
			(layer "F.Fab")
			(hide yes)
			(effects
				(font
					(size 1 1)
					(thickness 0.15)
				)
			)
		)
		(property "Current" "1A"
			(at 268.761 25.961 0)
			(layer "F.Fab")
			(hide yes)
			(effects
				(font
					(size 1 1)
					(thickness 0.15)
				)
			)
		)
		(property "License" "Apache-2.0"
			(at 268.761 25.961 0)
			(layer "F.Fab")
			(hide yes)
			(effects
				(font
					(size 1 1)
					(thickness 0.15)
				)
			)
		)
		(property "MPN" "ERJ2GE0R00X"
			(at 268.761 25.961 0)
			(layer "F.Fab")
			(hide yes)
			(effects
				(font
					(size 1 1)
					(thickness 0.15)
				)
			)
		)
		(property "Manufacturer" "Panasonic"
			(at 268.761 25.961 0)
			(layer "F.Fab")
			(hide yes)
			(effects
				(font
					(size 1 1)
					(thickness 0.15)
				)
			)
		)
		(property "Public" "False"
			(at 268.761 25.961 0)
			(layer "F.Fab")
			(hide yes)
			(effects
				(font
					(size 1 1)
					(thickness 0.15)
				)
			)
		)
		(property "Tolerance" ""
			(at 268.761 25.961 0)
			(layer "F.Fab")
			(hide yes)
			(effects
				(font
					(size 1 1)
					(thickness 0.15)
				)
			)
		)
		(property "Val" "0R"
			(at 268.761 25.961 0)
			(layer "F.Fab")
			(hide yes)
			(effects
				(font
					(size 1 1)
					(thickness 0.15)
				)
			)
		)
		(sheetname "PCIe redriver")
		(sheetfile "pcie_redriver.kicad_sch")
		(attr smd dnp)
		(fp_rect
			(start -0.925 -0.47)
			(end 0.925 0.47)
			(stroke
				(width 0.05)
				(type default)
			)
			(fill no)
			(layer "F.CrtYd")
		)
		(fp_rect
			(start -0.5 -0.25)
			(end 0.5 0.25)
			(stroke
				(width 0.15)
				(type solid)
			)
			(fill no)
			(layer "F.Fab")
		)
		(pad "1" smd roundrect
			(at -0.48 0 90)
			(size 0.59 0.64)
			(layers "F.Cu" "F.Mask" "F.Paste")
			(roundrect_rratio 0.25)
			(net 1 "GND")
			(pintype "passive")
			(teardrops
				(best_length_ratio 0.2)
				(max_length 1)
				(best_width_ratio 0.9)
				(max_width 2)
				(curved_edges yes)
				(filter_ratio 0.9)
				(enabled yes)
				(allow_two_segments yes)
				(prefer_zone_connections yes)
			)
		)
		(pad "2" smd roundrect
			(at 0.48 0 90)
			(size 0.59 0.64)
			(layers "F.Cu" "F.Mask" "F.Paste")
			(roundrect_rratio 0.25)
			(net 945 "/GPIO expander/GPIOEX5")
			(pintype "passive")
			(teardrops
				(best_length_ratio 0.2)
				(max_length 1)
				(best_width_ratio 0.9)
				(max_width 2)
				(curved_edges yes)
				(filter_ratio 0.9)
				(enabled yes)
				(allow_two_segments yes)
				(prefer_zone_connections yes)
			)
		)
	)
	(footprint "antmicro-footprints:R_0402_1005Metric"
		(layer "F.Cu")
		(at 252.664999 88.449999)
		(descr "Resistor SMD 0402")
		(tags "resistor SMD 0402")
		(property "Reference" "R148"
			(at -0.864999 0.440001 0)
			(layer "F.SilkS")
			(effects
				(font
					(size 0.7 0.7)
					(thickness 0.15)
				)
				(justify right bottom)
			)
		)
		(property "Value" "R_0R_0402"
			(at -1.011843 1.772047 0)
			(layer "F.Fab")
			(effects
				(font
					(size 0.7 0.7)
					(thickness 0.15)
				)
				(justify left bottom)
			)
		)
		(property "Datasheet" "https://industrial.panasonic.com/cdbs/www-data/pdf/RDA0000/AOA0000C301.pdf"
			(at 0 0 0)
			(layer "F.Fab")
			(hide yes)
			(effects
				(font
					(size 1.27 1.27)
					(thickness 0.15)
				)
			)
		)
		(property "Author" "Antmicro"
			(at 0 0 0)
			(layer "F.Fab")
			(hide yes)
			(effects
				(font
					(size 1 1)
					(thickness 0.15)
				)
			)
		)
		(property "Current" "1A"
			(at 0 0 0)
			(layer "F.Fab")
			(hide yes)
			(effects
				(font
					(size 1 1)
					(thickness 0.15)
				)
			)
		)
		(property "License" "Apache-2.0"
			(at 0 0 0)
			(layer "F.Fab")
			(hide yes)
			(effects
				(font
					(size 1 1)
					(thickness 0.15)
				)
			)
		)
		(property "MPN" "ERJ2GE0R00X"
			(at 0 0 0)
			(layer "F.Fab")
			(hide yes)
			(effects
				(font
					(size 1 1)
					(thickness 0.15)
				)
			)
		)
		(property "Manufacturer" "Panasonic"
			(at 0 0 0)
			(layer "F.Fab")
			(hide yes)
			(effects
				(font
					(size 1 1)
					(thickness 0.15)
				)
			)
		)
		(property "Public" "False"
			(at 0 0 0)
			(layer "F.Fab")
			(hide yes)
			(effects
				(font
					(size 1 1)
					(thickness 0.15)
				)
			)
		)
		(property "Tolerance" ""
			(at 0 0 0)
			(layer "F.Fab")
			(hide yes)
			(effects
				(font
					(size 1 1)
					(thickness 0.15)
				)
			)
		)
		(property "Val" "0R"
			(at 0 0 0)
			(layer "F.Fab")
			(hide yes)
			(effects
				(font
					(size 1 1)
					(thickness 0.15)
				)
			)
		)
		(sheetname "Misc")
		(sheetfile "misc.kicad_sch")
		(attr smd)
		(fp_rect
			(start -0.925 -0.47)
			(end 0.925 0.47)
			(stroke
				(width 0.05)
				(type default)
			)
			(fill no)
			(layer "F.CrtYd")
		)
		(fp_rect
			(start -0.5 -0.25)
			(end 0.5 0.25)
			(stroke
				(width 0.15)
				(type solid)
			)
			(fill no)
			(layer "F.Fab")
		)
		(pad "1" smd roundrect
			(at -0.48 0)
			(size 0.59 0.64)
			(layers "F.Cu" "F.Mask" "F.Paste")
			(roundrect_rratio 0.25)
			(net 74 "+1V0")
			(pintype "passive")
			(teardrops
				(best_length_ratio 0.2)
				(max_length 1)
				(best_width_ratio 0.9)
				(max_width 2)
				(curved_edges yes)
				(filter_ratio 0.9)
				(enabled yes)
				(allow_two_segments yes)
				(prefer_zone_connections yes)
			)
		)
		(pad "2" smd roundrect
			(at 0.48 0)
			(size 0.59 0.64)
			(layers "F.Cu" "F.Mask" "F.Paste")
			(roundrect_rratio 0.25)
			(net 590 "Net-(U24-+2.5V_{IN})")
			(pintype "passive")
			(teardrops
				(best_length_ratio 0.2)
				(max_length 1)
				(best_width_ratio 0.9)
				(max_width 2)
				(curved_edges yes)
				(filter_ratio 0.9)
				(enabled yes)
				(allow_two_segments yes)
				(prefer_zone_connections yes)
			)
		)
	)
	(footprint "antmicro-footprints:R_0402_1005Metric"
		(layer "F.Cu")
		(at 112.1 139.96 180)
		(descr "Resistor SMD 0402")
		(tags "resistor SMD 0402")
		(property "Reference" "R321"
			(at -3.65 -0.45 0)
			(layer "F.SilkS")
			(effects
				(font
					(size 0.7 0.7)
					(thickness 0.15)
				)
				(justify right bottom)
			)
		)
		(property "Value" "R_10k_0402"
			(at -1.011843 1.772047 0)
			(layer "F.Fab")
			(effects
				(font
					(size 0.7 0.7)
					(thickness 0.15)
				)
				(justify right bottom)
			)
		)
		(property "Datasheet" "https://www.bourns.com/docs/product-datasheets/cr.pdf"
			(at 0 0 180)
			(layer "F.Fab")
			(hide yes)
			(effects
				(font
					(size 1.27 1.27)
					(thickness 0.15)
				)
			)
		)
		(property "Author" "Antmicro"
			(at 224.2 279.92 0)
			(layer "F.Fab")
			(hide yes)
			(effects
				(font
					(size 1 1)
					(thickness 0.15)
				)
			)
		)
		(property "License" "Apache-2.0"
			(at 224.2 279.92 0)
			(layer "F.Fab")
			(hide yes)
			(effects
				(font
					(size 1 1)
					(thickness 0.15)
				)
			)
		)
		(property "MPN" "CR0402-FX-1002GLF"
			(at 224.2 279.92 0)
			(layer "F.Fab")
			(hide yes)
			(effects
				(font
					(size 1 1)
					(thickness 0.15)
				)
			)
		)
		(property "Manufacturer" "Bourns"
			(at 224.2 279.92 0)
			(layer "F.Fab")
			(hide yes)
			(effects
				(font
					(size 1 1)
					(thickness 0.15)
				)
			)
		)
		(property "Public" "False"
			(at 224.2 279.92 0)
			(layer "F.Fab")
			(hide yes)
			(effects
				(font
					(size 1 1)
					(thickness 0.15)
				)
			)
		)
		(property "Tolerance" "1%"
			(at 224.2 279.92 0)
			(layer "F.Fab")
			(hide yes)
			(effects
				(font
					(size 1 1)
					(thickness 0.15)
				)
			)
		)
		(property "Val" "10k"
			(at 224.2 279.92 0)
			(layer "F.Fab")
			(hide yes)
			(effects
				(font
					(size 1 1)
					(thickness 0.15)
				)
			)
		)
		(sheetname "SD card")
		(sheetfile "sd_card.kicad_sch")
		(attr smd)
		(fp_rect
			(start -0.925 -0.47)
			(end 0.925 0.47)
			(stroke
				(width 0.05)
				(type default)
			)
			(fill no)
			(layer "F.CrtYd")
		)
		(fp_rect
			(start -0.5 -0.25)
			(end 0.5 0.25)
			(stroke
				(width 0.15)
				(type solid)
			)
			(fill no)
			(layer "F.Fab")
		)
		(pad "1" smd roundrect
			(at -0.48 0 180)
			(size 0.59 0.64)
			(layers "F.Cu" "F.Mask" "F.Paste")
			(roundrect_rratio 0.25)
			(net 531 "/Com Express 7 Interfaces/SD_CD")
			(pintype "passive")
			(teardrops
				(best_length_ratio 0.2)
				(max_length 1)
				(best_width_ratio 0.9)
				(max_width 2)
				(curved_edges yes)
				(filter_ratio 0.9)
				(enabled yes)
				(allow_two_segments yes)
				(prefer_zone_connections yes)
			)
		)
		(pad "2" smd roundrect
			(at 0.48 0 180)
			(size 0.59 0.64)
			(layers "F.Cu" "F.Mask" "F.Paste")
			(roundrect_rratio 0.25)
			(net 2 "+3V3")
			(pintype "passive")
			(teardrops
				(best_length_ratio 0.2)
				(max_length 1)
				(best_width_ratio 0.9)
				(max_width 2)
				(curved_edges yes)
				(filter_ratio 0.9)
				(enabled yes)
				(allow_two_segments yes)
				(prefer_zone_connections yes)
			)
		)
	)
	(footprint "antmicro-footprints:R_0402_1005Metric"
		(layer "F.Cu")
		(at 209.38 127.82 180)
		(descr "Resistor SMD 0402")
		(tags "resistor SMD 0402")
		(property "Reference" "R192"
			(at 0.83 -0.39 0)
			(layer "F.SilkS")
			(effects
				(font
					(size 0.7 0.7)
					(thickness 0.15)
				)
				(justify right bottom)
			)
		)
		(property "Value" "R_0R_0402"
			(at -1.011843 1.772047 0)
			(layer "F.Fab")
			(effects
				(font
					(size 0.7 0.7)
					(thickness 0.15)
				)
				(justify right bottom)
			)
		)
		(property "Datasheet" "https://industrial.panasonic.com/cdbs/www-data/pdf/RDA0000/AOA0000C301.pdf"
			(at 0 0 180)
			(layer "F.Fab")
			(hide yes)
			(effects
				(font
					(size 1.27 1.27)
					(thickness 0.15)
				)
			)
		)
		(property "Author" "Antmicro"
			(at 418.76 255.64 0)
			(layer "F.Fab")
			(hide yes)
			(effects
				(font
					(size 1 1)
					(thickness 0.15)
				)
			)
		)
		(property "Current" "1A"
			(at 418.76 255.64 0)
			(layer "F.Fab")
			(hide yes)
			(effects
				(font
					(size 1 1)
					(thickness 0.15)
				)
			)
		)
		(property "License" "Apache-2.0"
			(at 418.76 255.64 0)
			(layer "F.Fab")
			(hide yes)
			(effects
				(font
					(size 1 1)
					(thickness 0.15)
				)
			)
		)
		(property "MPN" "ERJ2GE0R00X"
			(at 418.76 255.64 0)
			(layer "F.Fab")
			(hide yes)
			(effects
				(font
					(size 1 1)
					(thickness 0.15)
				)
			)
		)
		(property "Manufacturer" "Panasonic"
			(at 418.76 255.64 0)
			(layer "F.Fab")
			(hide yes)
			(effects
				(font
					(size 1 1)
					(thickness 0.15)
				)
			)
		)
		(property "Public" "False"
			(at 418.76 255.64 0)
			(layer "F.Fab")
			(hide yes)
			(effects
				(font
					(size 1 1)
					(thickness 0.15)
				)
			)
		)
		(property "Tolerance" ""
			(at 418.76 255.64 0)
			(layer "F.Fab")
			(hide yes)
			(effects
				(font
					(size 1 1)
					(thickness 0.15)
				)
			)
		)
		(property "Val" "0R"
			(at 418.76 255.64 0)
			(layer "F.Fab")
			(hide yes)
			(effects
				(font
					(size 1 1)
					(thickness 0.15)
				)
			)
		)
		(sheetname "PCIe misc")
		(sheetfile "pcie_misc.kicad_sch")
		(attr smd)
		(fp_rect
			(start -0.925 -0.47)
			(end 0.925 0.47)
			(stroke
				(width 0.05)
				(type default)
			)
			(fill no)
			(layer "F.CrtYd")
		)
		(fp_rect
			(start -0.5 -0.25)
			(end 0.5 0.25)
			(stroke
				(width 0.15)
				(type solid)
			)
			(fill no)
			(layer "F.Fab")
		)
		(pad "1" smd roundrect
			(at -0.48 0 180)
			(size 0.59 0.64)
			(layers "F.Cu" "F.Mask" "F.Paste")
			(roundrect_rratio 0.25)
			(net 611 "/PCIe misc/DIF0+")
			(pintype "passive")
			(teardrops
				(best_length_ratio 0.2)
				(max_length 1)
				(best_width_ratio 0.9)
				(max_width 2)
				(curved_edges yes)
				(filter_ratio 0.9)
				(enabled yes)
				(allow_two_segments yes)
				(prefer_zone_connections yes)
			)
		)
		(pad "2" smd roundrect
			(at 0.48 0 180)
			(size 0.59 0.64)
			(layers "F.Cu" "F.Mask" "F.Paste")
			(roundrect_rratio 0.25)
			(net 231 "/M.2 key M #1/PCIE_{REF}.CK+")
			(pintype "passive")
			(teardrops
				(best_length_ratio 0.2)
				(max_length 1)
				(best_width_ratio 0.9)
				(max_width 2)
				(curved_edges yes)
				(filter_ratio 0.9)
				(enabled yes)
				(allow_two_segments yes)
				(prefer_zone_connections yes)
			)
		)
	)
	(footprint "antmicro-footprints:R_0402_1005Metric"
		(layer "F.Cu")
		(at 192.342893 129.492893 -135)
		(descr "Resistor SMD 0402")
		(tags "resistor SMD 0402")
		(property "Reference" "R219"
			(at -3.65 -0.4 45)
			(layer "F.SilkS")
			(effects
				(font
					(size 0.7 0.7)
					(thickness 0.15)
				)
				(justify right bottom)
			)
		)
		(property "Value" "R_1k_0402"
			(at -1.011843 1.772046 45)
			(layer "F.Fab")
			(effects
				(font
					(size 0.7 0.7)
					(thickness 0.15)
				)
				(justify right bottom)
			)
		)
		(property "Datasheet" "https://www.bourns.com/docs/product-datasheets/cr.pdf"
			(at 0 0 45)
			(layer "F.Fab")
			(hide yes)
			(effects
				(font
					(size 1.27 1.27)
					(thickness 0.15)
				)
			)
		)
		(property "Author" "Antmicro"
			(at 389.1 261.22 45)
			(layer "F.Fab")
			(hide yes)
			(effects
				(font
					(size 1 1)
					(thickness 0.15)
				)
			)
		)
		(property "License" "Apache-2.0"
			(at 389.1 261.22 45)
			(layer "F.Fab")
			(hide yes)
			(effects
				(font
					(size 1 1)
					(thickness 0.15)
				)
			)
		)
		(property "MPN" "CR0402-FX-1001GLF"
			(at 389.1 261.22 45)
			(layer "F.Fab")
			(hide yes)
			(effects
				(font
					(size 1 1)
					(thickness 0.15)
				)
			)
		)
		(property "Manufacturer" "Bourns"
			(at 389.1 261.22 45)
			(layer "F.Fab")
			(hide yes)
			(effects
				(font
					(size 1 1)
					(thickness 0.15)
				)
			)
		)
		(property "Public" "False"
			(at 389.1 261.22 45)
			(layer "F.Fab")
			(hide yes)
			(effects
				(font
					(size 1 1)
					(thickness 0.15)
				)
			)
		)
		(property "Tolerance" "1%"
			(at 389.1 261.22 45)
			(layer "F.Fab")
			(hide yes)
			(effects
				(font
					(size 1 1)
					(thickness 0.15)
				)
			)
		)
		(property "Val" "1k"
			(at 389.1 261.22 45)
			(layer "F.Fab")
			(hide yes)
			(effects
				(font
					(size 1 1)
					(thickness 0.15)
				)
			)
		)
		(sheetname "PCIe redriver")
		(sheetfile "pcie_redriver.kicad_sch")
		(attr smd)
		(fp_poly
			(pts
				(xy -0.925 -0.47) (xy 0.925 -0.47) (xy 0.925 0.47) (xy -0.925 0.47)
			)
			(stroke
				(width 0.05)
				(type default)
			)
			(fill no)
			(layer "F.CrtYd")
		)
		(fp_poly
			(pts
				(xy -0.5 -0.25) (xy 0.5 -0.25) (xy 0.5 0.25) (xy -0.5 0.25)
			)
			(stroke
				(width 0.15)
				(type solid)
			)
			(fill no)
			(layer "F.Fab")
		)
		(pad "1" smd roundrect
			(at -0.48 0 225)
			(size 0.59 0.64)
			(layers "F.Cu" "F.Mask" "F.Paste")
			(roundrect_rratio 0.25)
			(net 2 "+3V3")
			(pintype "passive")
			(teardrops
				(best_length_ratio 0.2)
				(max_length 1)
				(best_width_ratio 0.9)
				(max_width 2)
				(curved_edges yes)
				(filter_ratio 0.9)
				(enabled yes)
				(allow_two_segments yes)
				(prefer_zone_connections yes)
			)
		)
		(pad "2" smd roundrect
			(at 0.48 0 225)
			(size 0.59 0.64)
			(layers "F.Cu" "F.Mask" "F.Paste")
			(roundrect_rratio 0.25)
			(net 973 "/PCIe redriver/RX_SW")
			(pintype "passive")
			(teardrops
				(best_length_ratio 0.2)
				(max_length 1)
				(best_width_ratio 0.9)
				(max_width 2)
				(curved_edges yes)
				(filter_ratio 0.9)
				(enabled yes)
				(allow_two_segments yes)
				(prefer_zone_connections yes)
			)
		)
	)
	(footprint "antmicro-footprints:BGA-144_12x12_13.05x13.05mm_P1.0mm"
		(layer "F.Cu")
		(at 150.95 137.36 -90)
		(property "Reference" "U43"
			(at 7.9 4.65 180)
			(layer "F.SilkS")
			(effects
				(font
					(size 0.7 0.7)
					(thickness 0.15)
				)
				(justify right bottom)
			)
		)
		(property "Value" "TLK10232CTR"
			(at 0 7.525 90)
			(layer "F.Fab")
			(effects
				(font
					(size 0.7 0.7)
					(thickness 0.15)
				)
				(justify right bottom)
			)
		)
		(property "Datasheet" "https://www.ti.com/lit/ds/symlink/tlk10232.pdf?ts=1712150848075&ref_url=https%253A%252F%252Fwww.mouser.pl%252F"
			(at 0 0 270)
			(layer "F.Fab")
			(hide yes)
			(effects
				(font
					(size 1.27 1.27)
					(thickness 0.15)
				)
			)
		)
		(property "Author" "Antmicro"
			(at 13.59 288.31 0)
			(layer "F.Fab")
			(hide yes)
			(effects
				(font
					(size 1 1)
					(thickness 0.15)
				)
			)
		)
		(property "License" "Apache-2.0"
			(at 13.59 288.31 0)
			(layer "F.Fab")
			(hide yes)
			(effects
				(font
					(size 1 1)
					(thickness 0.15)
				)
			)
		)
		(property "MPN" "TLK10232CTR"
			(at 13.59 288.31 0)
			(layer "F.Fab")
			(hide yes)
			(effects
				(font
					(size 1 1)
					(thickness 0.15)
				)
			)
		)
		(property "Manufacturer" "Texas Instruments"
			(at 13.59 288.31 0)
			(layer "F.Fab")
			(hide yes)
			(effects
				(font
					(size 1 1)
					(thickness 0.15)
				)
			)
		)
		(sheetname "KR to SFI #1")
		(sheetfile "kr_sfi.kicad_sch")
		(attr smd)
		(fp_line
			(start -6.645 6.645)
			(end -6.645 3.382)
			(stroke
				(width 0.15)
				(type solid)
			)
			(layer "F.SilkS")
		)
		(fp_line
			(start -3.382 6.645)
			(end -6.645 6.645)
			(stroke
				(width 0.15)
				(type solid)
			)
			(layer "F.SilkS")
		)
		(fp_line
			(start 3.382 6.645)
			(end 6.645 6.645)
			(stroke
				(width 0.15)
				(type solid)
			)
			(layer "F.SilkS")
		)
		(fp_line
			(start 6.645 6.645)
			(end 6.645 3.382)
			(stroke
				(width 0.15)
				(type solid)
			)
			(layer "F.SilkS")
		)
		(fp_line
			(start -6.645 -5.525)
			(end -6.645 -3.382)
			(stroke
				(width 0.15)
				(type solid)
			)
			(layer "F.SilkS")
		)
		(fp_line
			(start -5.525 -6.645)
			(end -6.645 -5.525)
			(stroke
				(width 0.15)
				(type solid)
			)
			(layer "F.SilkS")
		)
		(fp_line
			(start -3.382 -6.645)
			(end -5.525 -6.645)
			(stroke
				(width 0.15)
				(type solid)
			)
			(layer "F.SilkS")
		)
		(fp_line
			(start 3.382 -6.645)
			(end 6.645 -6.645)
			(stroke
				(width 0.15)
				(type solid)
			)
			(layer "F.SilkS")
		)
		(fp_line
			(start 6.645 -6.645)
			(end 6.645 -3.382)
			(stroke
				(width 0.15)
				(type solid)
			)
			(layer "F.SilkS")
		)
		(fp_circle
			(center -6.525 -6.525)
			(end -6.425 -6.525)
			(stroke
				(width 0.2)
				(type solid)
			)
			(fill no)
			(layer "F.SilkS")
		)
		(fp_rect
			(start -6.95 -6.95)
			(end 6.95 6.95)
			(stroke
				(width 0.05)
				(type solid)
			)
			(fill no)
			(layer "F.CrtYd")
		)
		(fp_line
			(start -6.525 6.525)
			(end 6.525 6.525)
			(stroke
				(width 0.15)
				(type solid)
			)
			(layer "F.Fab")
		)
		(fp_line
			(start 6.525 6.525)
			(end 6.525 -6.525)
			(stroke
				(width 0.15)
				(type solid)
			)
			(layer "F.Fab")
		)
		(fp_line
			(start -6.525 -5.525)
			(end -6.525 6.525)
			(stroke
				(width 0.15)
				(type solid)
			)
			(layer "F.Fab")
		)
		(fp_line
			(start -5.525 -6.525)
			(end -6.525 -5.525)
			(stroke
				(width 0.15)
				(type solid)
			)
			(layer "F.Fab")
		)
		(fp_line
			(start 6.525 -6.525)
			(end -5.525 -6.525)
			(stroke
				(width 0.15)
				(type solid)
			)
			(layer "F.Fab")
		)
		(pad "A1" smd circle
			(at -5.5 -5.5 270)
			(size 0.5 0.5)
			(layers "F.Cu" "F.Mask" "F.Paste")
			(net 800 "unconnected-(U43A-INA1+-PadA1)")
			(pinfunction "INA1+")
			(pintype "input+no_connect")
			(solder_mask_margin 0.05)
			(teardrops
				(best_length_ratio 0.4)
				(max_length 1)
				(best_width_ratio 0.9)
				(max_width 2)
				(curved_edges yes)
				(filter_ratio 0.9)
				(enabled yes)
				(allow_two_segments yes)
				(prefer_zone_connections yes)
			)
		)
		(pad "A2" smd circle
			(at -4.5 -5.5 270)
			(size 0.5 0.5)
			(layers "F.Cu" "F.Mask" "F.Paste")
			(net 1 "GND")
			(pinfunction "GND")
			(pintype "passive")
			(solder_mask_margin 0.05)
			(teardrops
				(best_length_ratio 0.4)
				(max_length 1)
				(best_width_ratio 0.9)
				(max_width 2)
				(curved_edges yes)
				(filter_ratio 0.9)
				(enabled yes)
				(allow_two_segments yes)
				(prefer_zone_connections yes)
			)
		)
		(pad "A3" smd circle
			(at -3.5 -5.5 270)
			(size 0.5 0.5)
			(layers "F.Cu" "F.Mask" "F.Paste")
			(net 801 "unconnected-(U43A-INA0--PadA3)")
			(pinfunction "INA0-")
			(pintype "input+no_connect")
			(solder_mask_margin 0.05)
			(teardrops
				(best_length_ratio 0.4)
				(max_length 1)
				(best_width_ratio 0.9)
				(max_width 2)
				(curved_edges yes)
				(filter_ratio 0.9)
				(enabled yes)
				(allow_two_segments yes)
				(prefer_zone_connections yes)
			)
		)
		(pad "A4" smd circle
			(at -2.5 -5.5 270)
			(size 0.5 0.5)
			(layers "F.Cu" "F.Mask" "F.Paste")
			(net 802 "unconnected-(U43A-INA0+-PadA4)")
			(pinfunction "INA0+")
			(pintype "input+no_connect")
			(solder_mask_margin 0.05)
			(teardrops
				(best_length_ratio 0.4)
				(max_length 1)
				(best_width_ratio 0.9)
				(max_width 2)
				(curved_edges yes)
				(filter_ratio 0.9)
				(enabled yes)
				(allow_two_segments yes)
				(prefer_zone_connections yes)
			)
		)
		(pad "A5" smd circle
			(at -1.5 -5.5 270)
			(size 0.5 0.5)
			(layers "F.Cu" "F.Mask" "F.Paste")
			(net 1 "GND")
			(pinfunction "GND")
			(pintype "passive")
			(solder_mask_margin 0.05)
			(teardrops
				(best_length_ratio 0.4)
				(max_length 1)
				(best_width_ratio 0.9)
				(max_width 2)
				(curved_edges yes)
				(filter_ratio 0.9)
				(enabled yes)
				(allow_two_segments yes)
				(prefer_zone_connections yes)
			)
		)
		(pad "A6" smd circle
			(at -0.5 -5.5 270)
			(size 0.5 0.5)
			(layers "F.Cu" "F.Mask" "F.Paste")
			(net 803 "unconnected-(U43A-OUTA0+-PadA6)")
			(pinfunction "OUTA0+")
			(pintype "output+no_connect")
			(solder_mask_margin 0.05)
			(teardrops
				(best_length_ratio 0.4)
				(max_length 1)
				(best_width_ratio 0.9)
				(max_width 2)
				(curved_edges yes)
				(filter_ratio 0.9)
				(enabled yes)
				(allow_two_segments yes)
				(prefer_zone_connections yes)
			)
		)
		(pad "A7" smd circle
			(at 0.5 -5.5 270)
			(size 0.5 0.5)
			(layers "F.Cu" "F.Mask" "F.Paste")
			(net 804 "unconnected-(U43A-OUTA0--PadA7)")
			(pinfunction "OUTA0-")
			(pintype "output+no_connect")
			(solder_mask_margin 0.05)
			(teardrops
				(best_length_ratio 0.4)
				(max_length 1)
				(best_width_ratio 0.9)
				(max_width 2)
				(curved_edges yes)
				(filter_ratio 0.9)
				(enabled yes)
				(allow_two_segments yes)
				(prefer_zone_connections yes)
			)
		)
		(pad "A8" smd circle
			(at 1.5 -5.5 270)
			(size 0.5 0.5)
			(layers "F.Cu" "F.Mask" "F.Paste")
			(net 657 "Net-(U43A-~{PDTRXA})")
			(pinfunction "~{PDTRXA}")
			(pintype "input")
			(solder_mask_margin 0.05)
			(teardrops
				(best_length_ratio 0.4)
				(max_length 1)
				(best_width_ratio 0.9)
				(max_width 2)
				(curved_edges yes)
				(filter_ratio 0.9)
				(enabled yes)
				(allow_two_segments yes)
				(prefer_zone_connections yes)
			)
		)
		(pad "A9" smd circle
			(at 2.5 -5.5 270)
			(size 0.5 0.5)
			(layers "F.Cu" "F.Mask" "F.Paste")
			(net 732 "Net-(U43C-CLKOUTB+)")
			(pinfunction "CLKOUTB+")
			(pintype "output")
			(solder_mask_margin 0.05)
			(teardrops
				(best_length_ratio 0.4)
				(max_length 1)
				(best_width_ratio 0.9)
				(max_width 2)
				(curved_edges yes)
				(filter_ratio 0.9)
				(enabled yes)
				(allow_two_segments yes)
				(prefer_zone_connections yes)
			)
		)
		(pad "A10" smd circle
			(at 3.5 -5.5 270)
			(size 0.5 0.5)
			(layers "F.Cu" "F.Mask" "F.Paste")
			(net 733 "Net-(U43C-CLKOUTB-)")
			(pinfunction "CLKOUTB-")
			(pintype "output")
			(solder_mask_margin 0.05)
			(teardrops
				(best_length_ratio 0.4)
				(max_length 1)
				(best_width_ratio 0.9)
				(max_width 2)
				(curved_edges yes)
				(filter_ratio 0.9)
				(enabled yes)
				(allow_two_segments yes)
				(prefer_zone_connections yes)
			)
		)
		(pad "A11" smd circle
			(at 4.5 -5.5 270)
			(size 0.5 0.5)
			(layers "F.Cu" "F.Mask" "F.Paste")
			(net 1 "GND")
			(pinfunction "GND")
			(pintype "power_in")
			(solder_mask_margin 0.05)
			(teardrops
				(best_length_ratio 0.4)
				(max_length 1)
				(best_width_ratio 0.9)
				(max_width 2)
				(curved_edges yes)
				(filter_ratio 0.9)
				(enabled yes)
				(allow_two_segments yes)
				(prefer_zone_connections yes)
			)
		)
		(pad "A12" smd circle
			(at 5.5 -5.5 270)
			(size 0.5 0.5)
			(layers "F.Cu" "F.Mask" "F.Paste")
			(net 114 "/2xSFP+/KR to SFI #1/KR_C.TX-")
			(pinfunction "HSRXA-")
			(pintype "input")
			(solder_mask_margin 0.05)
			(teardrops
				(best_length_ratio 0.4)
				(max_length 1)
				(best_width_ratio 0.9)
				(max_width 2)
				(curved_edges yes)
				(filter_ratio 0.9)
				(enabled yes)
				(allow_two_segments yes)
				(prefer_zone_connections yes)
			)
		)
		(pad "B1" smd circle
			(at -5.5 -4.5 270)
			(size 0.5 0.5)
			(layers "F.Cu" "F.Mask" "F.Paste")
			(net 805 "unconnected-(U43A-INA1--PadB1)")
			(pinfunction "INA1-")
			(pintype "input+no_connect")
			(solder_mask_margin 0.05)
			(teardrops
				(best_length_ratio 0.4)
				(max_length 1)
				(best_width_ratio 0.9)
				(max_width 2)
				(curved_edges yes)
				(filter_ratio 0.9)
				(enabled yes)
				(allow_two_segments yes)
				(prefer_zone_connections yes)
			)
		)
		(pad "B2" smd circle
			(at -4.5 -4.5 270)
			(size 0.5 0.5)
			(layers "F.Cu" "F.Mask" "F.Paste")
			(net 806 "unconnected-(U43A-INA2+-PadB2)")
			(pinfunction "INA2+")
			(pintype "input+no_connect")
			(solder_mask_margin 0.05)
			(teardrops
				(best_length_ratio 0.4)
				(max_length 1)
				(best_width_ratio 0.9)
				(max_width 2)
				(curved_edges yes)
				(filter_ratio 0.9)
				(enabled yes)
				(allow_two_segments yes)
				(prefer_zone_connections yes)
			)
		)
		(pad "B3" smd circle
			(at -3.5 -4.5 270)
			(size 0.5 0.5)
			(layers "F.Cu" "F.Mask" "F.Paste")
			(net 1 "GND")
			(pinfunction "GND")
			(pintype "passive")
			(solder_mask_margin 0.05)
			(teardrops
				(best_length_ratio 0.4)
				(max_length 1)
				(best_width_ratio 0.9)
				(max_width 2)
				(curved_edges yes)
				(filter_ratio 0.9)
				(enabled yes)
				(allow_two_segments yes)
				(prefer_zone_connections yes)
			)
		)
		(pad "B4" smd circle
			(at -2.5 -4.5 270)
			(size 0.5 0.5)
			(layers "F.Cu" "F.Mask" "F.Paste")
			(net 1 "GND")
			(pinfunction "GND")
			(pintype "passive")
			(solder_mask_margin 0.05)
			(teardrops
				(best_length_ratio 0.4)
				(max_length 1)
				(best_width_ratio 0.9)
				(max_width 2)
				(curved_edges yes)
				(filter_ratio 0.9)
				(enabled yes)
				(allow_two_segments yes)
				(prefer_zone_connections yes)
			)
		)
		(pad "B5" smd circle
			(at -1.5 -4.5 270)
			(size 0.5 0.5)
			(layers "F.Cu" "F.Mask" "F.Paste")
			(net 807 "unconnected-(U43A-OUTA1+-PadB5)")
			(pinfunction "OUTA1+")
			(pintype "output+no_connect")
			(solder_mask_margin 0.05)
			(teardrops
				(best_length_ratio 0.4)
				(max_length 1)
				(best_width_ratio 0.9)
				(max_width 2)
				(curved_edges yes)
				(filter_ratio 0.9)
				(enabled yes)
				(allow_two_segments yes)
				(prefer_zone_connections yes)
			)
		)
		(pad "B6" smd circle
			(at -0.5 -4.5 270)
			(size 0.5 0.5)
			(layers "F.Cu" "F.Mask" "F.Paste")
			(net 808 "unconnected-(U43A-OUTA1--PadB6)")
			(pinfunction "OUTA1-")
			(pintype "output+no_connect")
			(solder_mask_margin 0.05)
			(teardrops
				(best_length_ratio 0.4)
				(max_length 1)
				(best_width_ratio 0.9)
				(max_width 2)
				(curved_edges yes)
				(filter_ratio 0.9)
				(enabled yes)
				(allow_two_segments yes)
				(prefer_zone_connections yes)
			)
		)
		(pad "B7" smd circle
			(at 0.5 -4.5 270)
			(size 0.5 0.5)
			(layers "F.Cu" "F.Mask" "F.Paste")
			(net 1 "GND")
			(pinfunction "GND")
			(pintype "passive")
			(solder_mask_margin 0.05)
			(teardrops
				(best_length_ratio 0.4)
				(max_length 1)
				(best_width_ratio 0.9)
				(max_width 2)
				(curved_edges yes)
				(filter_ratio 0.9)
				(enabled yes)
				(allow_two_segments yes)
				(prefer_zone_connections yes)
			)
		)
		(pad "B8" smd circle
			(at 1.5 -4.5 270)
			(size 0.5 0.5)
			(layers "F.Cu" "F.Mask" "F.Paste")
			(net 724 "/2xSFP+/KR to SFI #1/TMS")
			(pinfunction "TMS")
			(pintype "input")
			(solder_mask_margin 0.05)
			(teardrops
				(best_length_ratio 0.4)
				(max_length 1)
				(best_width_ratio 0.9)
				(max_width 2)
				(curved_edges yes)
				(filter_ratio 0.9)
				(enabled yes)
				(allow_two_segments yes)
				(prefer_zone_connections yes)
			)
		)
		(pad "B9" smd circle
			(at 2.5 -4.5 270)
			(size 0.5 0.5)
			(layers "F.Cu" "F.Mask" "F.Paste")
			(net 652 "/2xSFP+/KR to SFI #1/PRBSEN")
			(pinfunction "PRBSEN")
			(pintype "input")
			(solder_mask_margin 0.05)
			(teardrops
				(best_length_ratio 0.4)
				(max_length 1)
				(best_width_ratio 0.9)
				(max_width 2)
				(curved_edges yes)
				(filter_ratio 0.9)
				(enabled yes)
				(allow_two_segments yes)
				(prefer_zone_connections yes)
			)
		)
		(pad "B10" smd circle
			(at 3.5 -4.5 270)
			(size 0.5 0.5)
			(layers "F.Cu" "F.Mask" "F.Paste")
			(net 735 "Net-(U43A-LS_OK_{IN_A})")
			(pinfunction "LS_OK_{IN_A}")
			(pintype "input")
			(solder_mask_margin 0.05)
			(teardrops
				(best_length_ratio 0.4)
				(max_length 1)
				(best_width_ratio 0.9)
				(max_width 2)
				(curved_edges yes)
				(filter_ratio 0.9)
				(enabled yes)
				(allow_two_segments yes)
				(prefer_zone_connections yes)
			)
		)
		(pad "B11" smd circle
			(at 4.5 -4.5 270)
			(size 0.5 0.5)
			(layers "F.Cu" "F.Mask" "F.Paste")
			(net 1 "GND")
			(pinfunction "GND")
			(pintype "passive")
			(solder_mask_margin 0.05)
			(teardrops
				(best_length_ratio 0.4)
				(max_length 1)
				(best_width_ratio 0.9)
				(max_width 2)
				(curved_edges yes)
				(filter_ratio 0.9)
				(enabled yes)
				(allow_two_segments yes)
				(prefer_zone_connections yes)
			)
		)
		(pad "B12" smd circle
			(at 5.5 -4.5 270)
			(size 0.5 0.5)
			(layers "F.Cu" "F.Mask" "F.Paste")
			(net 112 "/2xSFP+/KR to SFI #1/KR_C.TX+")
			(pinfunction "HSRXA+")
			(pintype "input")
			(solder_mask_margin 0.05)
			(teardrops
				(best_length_ratio 0.4)
				(max_length 1)
				(best_width_ratio 0.9)
				(max_width 2)
				(curved_edges yes)
				(filter_ratio 0.9)
				(enabled yes)
				(allow_two_segments yes)
				(prefer_zone_connections yes)
			)
		)
		(pad "C1" smd circle
			(at -5.5 -3.5 270)
			(size 0.5 0.5)
			(layers "F.Cu" "F.Mask" "F.Paste")
			(net 1 "GND")
			(pinfunction "GND")
			(pintype "passive")
			(solder_mask_margin 0.05)
			(teardrops
				(best_length_ratio 0.4)
				(max_length 1)
				(best_width_ratio 0.9)
				(max_width 2)
				(curved_edges yes)
				(filter_ratio 0.9)
				(enabled yes)
				(allow_two_segments yes)
				(prefer_zone_connections yes)
			)
		)
		(pad "C2" smd circle
			(at -4.5 -3.5 270)
			(size 0.5 0.5)
			(layers "F.Cu" "F.Mask" "F.Paste")
			(net 809 "unconnected-(U43A-INA2--PadC2)")
			(pinfunction "INA2-")
			(pintype "input+no_connect")
			(solder_mask_margin 0.05)
			(teardrops
				(best_length_ratio 0.4)
				(max_length 1)
				(best_width_ratio 0.9)
				(max_width 2)
				(curved_edges yes)
				(filter_ratio 0.9)
				(enabled yes)
				(allow_two_segments yes)
				(prefer_zone_connections yes)
			)
		)
		(pad "C3" smd circle
			(at -3.5 -3.5 270)
			(size 0.5 0.5)
			(layers "F.Cu" "F.Mask" "F.Paste")
			(net 78 "+1V8")
			(pinfunction "VDDRA_{LS/HS}")
			(pintype "power_in")
			(solder_mask_margin 0.05)
			(teardrops
				(best_length_ratio 0.4)
				(max_length 1)
				(best_width_ratio 0.9)
				(max_width 2)
				(curved_edges yes)
				(filter_ratio 0.9)
				(enabled yes)
				(allow_two_segments yes)
				(prefer_zone_connections yes)
			)
		)
		(pad "C4" smd circle
			(at -2.5 -3.5 270)
			(size 0.5 0.5)
			(layers "F.Cu" "F.Mask" "F.Paste")
			(net 810 "unconnected-(U43A-OUTA2+-PadC4)")
			(pinfunction "OUTA2+")
			(pintype "output+no_connect")
			(solder_mask_margin 0.05)
			(teardrops
				(best_length_ratio 0.4)
				(max_length 1)
				(best_width_ratio 0.9)
				(max_width 2)
				(curved_edges yes)
				(filter_ratio 0.9)
				(enabled yes)
				(allow_two_segments yes)
				(prefer_zone_connections yes)
			)
		)
		(pad "C5" smd circle
			(at -1.5 -3.5 270)
			(size 0.5 0.5)
			(layers "F.Cu" "F.Mask" "F.Paste")
			(net 811 "unconnected-(U43A-OUTA2--PadC5)")
			(pinfunction "OUTA2-")
			(pintype "output+no_connect")
			(solder_mask_margin 0.05)
			(teardrops
				(best_length_ratio 0.4)
				(max_length 1)
				(best_width_ratio 0.9)
				(max_width 2)
				(curved_edges yes)
				(filter_ratio 0.9)
				(enabled yes)
				(allow_two_segments yes)
				(prefer_zone_connections yes)
			)
		)
		(pad "C6" smd circle
			(at -0.5 -3.5 270)
			(size 0.5 0.5)
			(layers "F.Cu" "F.Mask" "F.Paste")
			(net 1 "GND")
			(pinfunction "GND")
			(pintype "passive")
			(solder_mask_margin 0.05)
			(teardrops
				(best_length_ratio 0.4)
				(max_length 1)
				(best_width_ratio 0.9)
				(max_width 2)
				(curved_edges yes)
				(filter_ratio 0.9)
				(enabled yes)
				(allow_two_segments yes)
				(prefer_zone_connections yes)
			)
		)
		(pad "C7" smd circle
			(at 0.5 -3.5 270)
			(size 0.5 0.5)
			(layers "F.Cu" "F.Mask" "F.Paste")
			(net 74 "+1V0")
			(pinfunction "VDDO0")
			(pintype "power_in")
			(solder_mask_margin 0.05)
			(teardrops
				(best_length_ratio 0.4)
				(max_length 1)
				(best_width_ratio 0.9)
				(max_width 2)
				(curved_edges yes)
				(filter_ratio 0.9)
				(enabled yes)
				(allow_two_segments yes)
				(prefer_zone_connections yes)
			)
		)
		(pad "C8" smd circle
			(at 1.5 -3.5 270)
			(size 0.5 0.5)
			(layers "F.Cu" "F.Mask" "F.Paste")
			(net 722 "/2xSFP+/KR to SFI #1/TDI")
			(pinfunction "TDI")
			(pintype "input")
			(solder_mask_margin 0.05)
			(teardrops
				(best_length_ratio 0.4)
				(max_length 1)
				(best_width_ratio 0.9)
				(max_width 2)
				(curved_edges yes)
				(filter_ratio 0.9)
				(enabled yes)
				(allow_two_segments yes)
				(prefer_zone_connections yes)
			)
		)
		(pad "C9" smd circle
			(at 2.5 -3.5 270)
			(size 0.5 0.5)
			(layers "F.Cu" "F.Mask" "F.Paste")
			(net 730 "Net-(U43C-CLKOUTA+)")
			(pinfunction "CLKOUTA+")
			(pintype "output")
			(solder_mask_margin 0.05)
			(teardrops
				(best_length_ratio 0.4)
				(max_length 1)
				(best_width_ratio 0.9)
				(max_width 2)
				(curved_edges yes)
				(filter_ratio 0.9)
				(enabled yes)
				(allow_two_segments yes)
				(prefer_zone_connections yes)
			)
		)
		(pad "C10" smd circle
			(at 3.5 -3.5 270)
			(size 0.5 0.5)
			(layers "F.Cu" "F.Mask" "F.Paste")
			(net 731 "Net-(U43C-CLKOUTA-)")
			(pinfunction "CLKOUTA-")
			(pintype "output")
			(solder_mask_margin 0.05)
			(teardrops
				(best_length_ratio 0.4)
				(max_length 1)
				(best_width_ratio 0.9)
				(max_width 2)
				(curved_edges yes)
				(filter_ratio 0.9)
				(enabled yes)
				(allow_two_segments yes)
				(prefer_zone_connections yes)
			)
		)
		(pad "C11" smd circle
			(at 4.5 -3.5 270)
			(size 0.5 0.5)
			(layers "F.Cu" "F.Mask" "F.Paste")
			(net 728 "Net-(U43C-AMUXA)")
			(pinfunction "AMUXA")
			(pintype "passive")
			(solder_mask_margin 0.05)
			(teardrops
				(best_length_ratio 0.4)
				(max_length 1)
				(best_width_ratio 0.9)
				(max_width 2)
				(curved_edges yes)
				(filter_ratio 0.9)
				(enabled yes)
				(allow_two_segments yes)
				(prefer_zone_connections yes)
			)
		)
		(pad "C12" smd circle
			(at 5.5 -3.5 270)
			(size 0.5 0.5)
			(layers "F.Cu" "F.Mask" "F.Paste")
			(net 1 "GND")
			(pinfunction "GND")
			(pintype "passive")
			(solder_mask_margin 0.05)
			(teardrops
				(best_length_ratio 0.4)
				(max_length 1)
				(best_width_ratio 0.9)
				(max_width 2)
				(curved_edges yes)
				(filter_ratio 0.9)
				(enabled yes)
				(allow_two_segments yes)
				(prefer_zone_connections yes)
			)
		)
		(pad "D1" smd circle
			(at -5.5 -2.5 270)
			(size 0.5 0.5)
			(layers "F.Cu" "F.Mask" "F.Paste")
			(net 812 "unconnected-(U43A-INA3+-PadD1)")
			(pinfunction "INA3+")
			(pintype "input+no_connect")
			(solder_mask_margin 0.05)
			(teardrops
				(best_length_ratio 0.4)
				(max_length 1)
				(best_width_ratio 0.9)
				(max_width 2)
				(curved_edges yes)
				(filter_ratio 0.9)
				(enabled yes)
				(allow_two_segments yes)
				(prefer_zone_connections yes)
			)
		)
		(pad "D2" smd circle
			(at -4.5 -2.5 270)
			(size 0.5 0.5)
			(layers "F.Cu" "F.Mask" "F.Paste")
			(net 74 "+1V0")
			(pinfunction "VDDA_{LS/HS}")
			(pintype "power_in")
			(solder_mask_margin 0.05)
			(teardrops
				(best_length_ratio 0.4)
				(max_length 1)
				(best_width_ratio 0.9)
				(max_width 2)
				(curved_edges yes)
				(filter_ratio 0.9)
				(enabled yes)
				(allow_two_segments yes)
				(prefer_zone_connections yes)
			)
		)
		(pad "D3" smd circle
			(at -3.5 -2.5 270)
			(size 0.5 0.5)
			(layers "F.Cu" "F.Mask" "F.Paste")
			(net 1 "GND")
			(pinfunction "GND")
			(pintype "passive")
			(solder_mask_margin 0.05)
			(teardrops
				(best_length_ratio 0.4)
				(max_length 1)
				(best_width_ratio 0.9)
				(max_width 2)
				(curved_edges yes)
				(filter_ratio 0.9)
				(enabled yes)
				(allow_two_segments yes)
				(prefer_zone_connections yes)
			)
		)
		(pad "D4" smd circle
			(at -2.5 -2.5 270)
			(size 0.5 0.5)
			(layers "F.Cu" "F.Mask" "F.Paste")
			(net 729 "Net-(U43C-AMUXB)")
			(pinfunction "AMUXB")
			(pintype "passive")
			(solder_mask_margin 0.05)
			(teardrops
				(best_length_ratio 0.4)
				(max_length 1)
				(best_width_ratio 0.9)
				(max_width 2)
				(curved_edges yes)
				(filter_ratio 0.9)
				(enabled yes)
				(allow_two_segments yes)
				(prefer_zone_connections yes)
			)
		)
		(pad "D5" smd circle
			(at -1.5 -2.5 270)
			(size 0.5 0.5)
			(layers "F.Cu" "F.Mask" "F.Paste")
			(net 1 "GND")
			(pinfunction "GND")
			(pintype "passive")
			(solder_mask_margin 0.05)
			(teardrops
				(best_length_ratio 0.4)
				(max_length 1)
				(best_width_ratio 0.9)
				(max_width 2)
				(curved_edges yes)
				(filter_ratio 0.9)
				(enabled yes)
				(allow_two_segments yes)
				(prefer_zone_connections yes)
			)
		)
		(pad "D6" smd circle
			(at -0.5 -2.5 270)
			(size 0.5 0.5)
			(layers "F.Cu" "F.Mask" "F.Paste")
			(net 723 "/2xSFP+/KR to SFI #1/TDO")
			(pinfunction "TDO")
			(pintype "output")
			(solder_mask_margin 0.05)
			(teardrops
				(best_length_ratio 0.4)
				(max_length 1)
				(best_width_ratio 0.9)
				(max_width 2)
				(curved_edges yes)
				(filter_ratio 0.9)
				(enabled yes)
				(allow_two_segments yes)
				(prefer_zone_connections yes)
			)
		)
		(pad "D7" smd circle
			(at 0.5 -2.5 270)
			(size 0.5 0.5)
			(layers "F.Cu" "F.Mask" "F.Paste")
			(net 74 "+1V0")
			(pinfunction "VPP")
			(pintype "power_in")
			(solder_mask_margin 0.05)
			(teardrops
				(best_length_ratio 0.4)
				(max_length 1)
				(best_width_ratio 0.9)
				(max_width 2)
				(curved_edges yes)
				(filter_ratio 0.9)
				(enabled yes)
				(allow_two_segments yes)
				(prefer_zone_connections yes)
			)
		)
		(pad "D8" smd circle
			(at 1.5 -2.5 270)
			(size 0.5 0.5)
			(layers "F.Cu" "F.Mask" "F.Paste")
			(net 725 "/2xSFP+/KR to SFI #1/TCK")
			(pinfunction "TCK")
			(pintype "input")
			(solder_mask_margin 0.05)
			(teardrops
				(best_length_ratio 0.4)
				(max_length 1)
				(best_width_ratio 0.9)
				(max_width 2)
				(curved_edges yes)
				(filter_ratio 0.9)
				(enabled yes)
				(allow_two_segments yes)
				(prefer_zone_connections yes)
			)
		)
		(pad "D9" smd circle
			(at 2.5 -2.5 270)
			(size 0.5 0.5)
			(layers "F.Cu" "F.Mask" "F.Paste")
			(net 736 "Net-(U43A-LS_OK_{OUT_A})")
			(pinfunction "LS_OK_{OUT_A}")
			(pintype "output")
			(solder_mask_margin 0.05)
			(teardrops
				(best_length_ratio 0.4)
				(max_length 1)
				(best_width_ratio 0.9)
				(max_width 2)
				(curved_edges yes)
				(filter_ratio 0.9)
				(enabled yes)
				(allow_two_segments yes)
				(prefer_zone_connections yes)
			)
		)
		(pad "D10" smd circle
			(at 3.5 -2.5 270)
			(size 0.5 0.5)
			(layers "F.Cu" "F.Mask" "F.Paste")
			(net 1 "GND")
			(pinfunction "GND")
			(pintype "passive")
			(solder_mask_margin 0.05)
			(teardrops
				(best_length_ratio 0.4)
				(max_length 1)
				(best_width_ratio 0.9)
				(max_width 2)
				(curved_edges yes)
				(filter_ratio 0.9)
				(enabled yes)
				(allow_two_segments yes)
				(prefer_zone_connections yes)
			)
		)
		(pad "D11" smd circle
			(at 4.5 -2.5 270)
			(size 0.5 0.5)
			(layers "F.Cu" "F.Mask" "F.Paste")
			(net 1 "GND")
			(pinfunction "GND")
			(pintype "passive")
			(solder_mask_margin 0.05)
			(teardrops
				(best_length_ratio 0.4)
				(max_length 1)
				(best_width_ratio 0.9)
				(max_width 2)
				(curved_edges yes)
				(filter_ratio 0.9)
				(enabled yes)
				(allow_two_segments yes)
				(prefer_zone_connections yes)
			)
		)
		(pad "D12" smd circle
			(at 5.5 -2.5 270)
			(size 0.5 0.5)
			(layers "F.Cu" "F.Mask" "F.Paste")
			(net 664 "/2xSFP+/KR to SFI #1/KR_R.RX+")
			(pinfunction "HSTXA+")
			(pintype "output")
			(solder_mask_margin 0.05)
			(teardrops
				(best_length_ratio 0.4)
				(max_length 1)
				(best_width_ratio 0.9)
				(max_width 2)
				(curved_edges yes)
				(filter_ratio 0.9)
				(enabled yes)
				(allow_two_segments yes)
				(prefer_zone_connections yes)
			)
		)
		(pad "E1" smd circle
			(at -5.5 -1.5 270)
			(size 0.5 0.5)
			(layers "F.Cu" "F.Mask" "F.Paste")
			(net 813 "unconnected-(U43A-INA3--PadE1)")
			(pinfunction "INA3-")
			(pintype "input+no_connect")
			(solder_mask_margin 0.05)
			(teardrops
				(best_length_ratio 0.4)
				(max_length 1)
				(best_width_ratio 0.9)
				(max_width 2)
				(curved_edges yes)
				(filter_ratio 0.9)
				(enabled yes)
				(allow_two_segments yes)
				(prefer_zone_connections yes)
			)
		)
		(pad "E2" smd circle
			(at -4.5 -1.5 270)
			(size 0.5 0.5)
			(layers "F.Cu" "F.Mask" "F.Paste")
			(net 1 "GND")
			(pinfunction "GND")
			(pintype "passive")
			(solder_mask_margin 0.05)
			(teardrops
				(best_length_ratio 0.4)
				(max_length 1)
				(best_width_ratio 0.9)
				(max_width 2)
				(curved_edges yes)
				(filter_ratio 0.9)
				(enabled yes)
				(allow_two_segments yes)
				(prefer_zone_connections yes)
			)
		)
		(pad "E3" smd circle
			(at -3.5 -1.5 270)
			(size 0.5 0.5)
			(layers "F.Cu" "F.Mask" "F.Paste")
			(net 814 "unconnected-(U43A-OUTA3--PadE3)")
			(pinfunction "OUTA3-")
			(pintype "output+no_connect")
			(solder_mask_margin 0.05)
			(teardrops
				(best_length_ratio 0.4)
				(max_length 1)
				(best_width_ratio 0.9)
				(max_width 2)
				(curved_edges yes)
				(filter_ratio 0.9)
				(enabled yes)
				(allow_two_segments yes)
				(prefer_zone_connections yes)
			)
		)
		(pad "E4" smd circle
			(at -2.5 -1.5 270)
			(size 0.5 0.5)
			(layers "F.Cu" "F.Mask" "F.Paste")
			(net 1 "GND")
			(pinfunction "GND")
			(pintype "passive")
			(solder_mask_margin 0.05)
			(teardrops
				(best_length_ratio 0.4)
				(max_length 1)
				(best_width_ratio 0.9)
				(max_width 2)
				(curved_edges yes)
				(filter_ratio 0.9)
				(enabled yes)
				(allow_two_segments yes)
				(prefer_zone_connections yes)
			)
		)
		(pad "E5" smd circle
			(at -1.5 -1.5 270)
			(size 0.5 0.5)
			(layers "F.Cu" "F.Mask" "F.Paste")
			(net 726 "/2xSFP+/KR to SFI #1/~{TRST}")
			(pinfunction "~{TRST}")
			(pintype "input")
			(solder_mask_margin 0.05)
			(teardrops
				(best_length_ratio 0.4)
				(max_length 1)
				(best_width_ratio 0.9)
				(max_width 2)
				(curved_edges yes)
				(filter_ratio 0.9)
				(enabled yes)
				(allow_two_segments yes)
				(prefer_zone_connections yes)
			)
		)
		(pad "E6" smd circle
			(at -0.5 -1.5 270)
			(size 0.5 0.5)
			(layers "F.Cu" "F.Mask" "F.Paste")
			(net 74 "+1V0")
			(pinfunction "VDDD")
			(pintype "power_in")
			(solder_mask_margin 0.05)
			(teardrops
				(best_length_ratio 0.4)
				(max_length 1)
				(best_width_ratio 0.9)
				(max_width 2)
				(curved_edges yes)
				(filter_ratio 0.9)
				(enabled yes)
				(allow_two_segments yes)
				(prefer_zone_connections yes)
			)
		)
		(pad "E7" smd circle
			(at 0.5 -1.5 270)
			(size 0.5 0.5)
			(layers "F.Cu" "F.Mask" "F.Paste")
			(net 74 "+1V0")
			(pinfunction "DVDD")
			(pintype "power_in")
			(solder_mask_margin 0.05)
			(teardrops
				(best_length_ratio 0.4)
				(max_length 1)
				(best_width_ratio 0.9)
				(max_width 2)
				(curved_edges yes)
				(filter_ratio 0.9)
				(enabled yes)
				(allow_two_segments yes)
				(prefer_zone_connections yes)
			)
		)
		(pad "E8" smd circle
			(at 1.5 -1.5 270)
			(size 0.5 0.5)
			(layers "F.Cu" "F.Mask" "F.Paste")
			(net 74 "+1V0")
			(pinfunction "VDDD")
			(pintype "passive")
			(solder_mask_margin 0.05)
			(teardrops
				(best_length_ratio 0.4)
				(max_length 1)
				(best_width_ratio 0.9)
				(max_width 2)
				(curved_edges yes)
				(filter_ratio 0.9)
				(enabled yes)
				(allow_two_segments yes)
				(prefer_zone_connections yes)
			)
		)
		(pad "E9" smd circle
			(at 2.5 -1.5 270)
			(size 0.5 0.5)
			(layers "F.Cu" "F.Mask" "F.Paste")
			(net 734 "Net-(U43A-LOSA)")
			(pinfunction "LOSA")
			(pintype "output")
			(solder_mask_margin 0.05)
			(teardrops
				(best_length_ratio 0.4)
				(max_length 1)
				(best_width_ratio 0.9)
				(max_width 2)
				(curved_edges yes)
				(filter_ratio 0.9)
				(enabled yes)
				(allow_two_segments yes)
				(prefer_zone_connections yes)
			)
		)
		(pad "E10" smd circle
			(at 3.5 -1.5 270)
			(size 0.5 0.5)
			(layers "F.Cu" "F.Mask" "F.Paste")
			(net 655 "Net-(U43C-PRTAD0)")
			(pinfunction "PRTAD0")
			(pintype "input")
			(solder_mask_margin 0.05)
			(teardrops
				(best_length_ratio 0.4)
				(max_length 1)
				(best_width_ratio 0.9)
				(max_width 2)
				(curved_edges yes)
				(filter_ratio 0.9)
				(enabled yes)
				(allow_two_segments yes)
				(prefer_zone_connections yes)
			)
		)
		(pad "E11" smd circle
			(at 4.5 -1.5 270)
			(size 0.5 0.5)
			(layers "F.Cu" "F.Mask" "F.Paste")
			(net 78 "+1V8")
			(pinfunction "VDDRA_{LS/HS}")
			(pintype "passive")
			(solder_mask_margin 0.05)
			(teardrops
				(best_length_ratio 0.4)
				(max_length 1)
				(best_width_ratio 0.9)
				(max_width 2)
				(curved_edges yes)
				(filter_ratio 0.9)
				(enabled yes)
				(allow_two_segments yes)
				(prefer_zone_connections yes)
			)
		)
		(pad "E12" smd circle
			(at 5.5 -1.5 270)
			(size 0.5 0.5)
			(layers "F.Cu" "F.Mask" "F.Paste")
			(net 665 "/2xSFP+/KR to SFI #1/KR_R.RX-")
			(pinfunction "HSTXA-")
			(pintype "output")
			(solder_mask_margin 0.05)
			(teardrops
				(best_length_ratio 0.4)
				(max_length 1)
				(best_width_ratio 0.9)
				(max_width 2)
				(curved_edges yes)
				(filter_ratio 0.9)
				(enabled yes)
				(allow_two_segments yes)
				(prefer_zone_connections yes)
			)
		)
		(pad "F1" smd circle
			(at -5.5 -0.5 270)
			(size 0.5 0.5)
			(layers "F.Cu" "F.Mask" "F.Paste")
			(net 1 "GND")
			(pinfunction "GND")
			(pintype "passive")
			(solder_mask_margin 0.05)
			(teardrops
				(best_length_ratio 0.4)
				(max_length 1)
				(best_width_ratio 0.9)
				(max_width 2)
				(curved_edges yes)
				(filter_ratio 0.9)
				(enabled yes)
				(allow_two_segments yes)
				(prefer_zone_connections yes)
			)
		)
		(pad "F2" smd circle
			(at -4.5 -0.5 270)
			(size 0.5 0.5)
			(layers "F.Cu" "F.Mask" "F.Paste")
			(net 74 "+1V0")
			(pinfunction "VDDA_{LS/HS}")
			(pintype "passive")
			(solder_mask_margin 0.05)
			(teardrops
				(best_length_ratio 0.4)
				(max_length 1)
				(best_width_ratio 0.9)
				(max_width 2)
				(curved_edges yes)
				(filter_ratio 0.9)
				(enabled yes)
				(allow_two_segments yes)
				(prefer_zone_connections yes)
			)
		)
		(pad "F3" smd circle
			(at -3.5 -0.5 270)
			(size 0.5 0.5)
			(layers "F.Cu" "F.Mask" "F.Paste")
			(net 815 "unconnected-(U43A-OUTA3+-PadF3)")
			(pinfunction "OUTA3+")
			(pintype "output+no_connect")
			(solder_mask_margin 0.05)
			(teardrops
				(best_length_ratio 0.4)
				(max_length 1)
				(best_width_ratio 0.9)
				(max_width 2)
				(curved_edges yes)
				(filter_ratio 0.9)
				(enabled yes)
				(allow_two_segments yes)
				(prefer_zone_connections yes)
			)
		)
		(pad "F4" smd circle
			(at -2.5 -0.5 270)
			(size 0.5 0.5)
			(layers "F.Cu" "F.Mask" "F.Paste")
			(net 74 "+1V0")
			(pinfunction "VDDT_{LS/HS}")
			(pintype "power_in")
			(solder_mask_margin 0.05)
			(teardrops
				(best_length_ratio 0.4)
				(max_length 1)
				(best_width_ratio 0.9)
				(max_width 2)
				(curved_edges yes)
				(filter_ratio 0.9)
				(enabled yes)
				(allow_two_segments yes)
				(prefer_zone_connections yes)
			)
		)
		(pad "F5" smd circle
			(at -1.5 -0.5 270)
			(size 0.5 0.5)
			(layers "F.Cu" "F.Mask" "F.Paste")
			(net 1 "GND")
			(pinfunction "GND")
			(pintype "passive")
			(solder_mask_margin 0.05)
			(teardrops
				(best_length_ratio 0.4)
				(max_length 1)
				(best_width_ratio 0.9)
				(max_width 2)
				(curved_edges yes)
				(filter_ratio 0.9)
				(enabled yes)
				(allow_two_segments yes)
				(prefer_zone_connections yes)
			)
		)
		(pad "F6" smd circle
			(at -0.5 -0.5 270)
			(size 0.5 0.5)
			(layers "F.Cu" "F.Mask" "F.Paste")
			(net 74 "+1V0")
			(pinfunction "VDDD")
			(pintype "passive")
			(solder_mask_margin 0.05)
			(teardrops
				(best_length_ratio 0.4)
				(max_length 1)
				(best_width_ratio 0.9)
				(max_width 2)
				(curved_edges yes)
				(filter_ratio 0.9)
				(enabled yes)
				(allow_two_segments yes)
				(prefer_zone_connections yes)
			)
		)
		(pad "F7" smd circle
			(at 0.5 -0.5 270)
			(size 0.5 0.5)
			(layers "F.Cu" "F.Mask" "F.Paste")
			(net 74 "+1V0")
			(pinfunction "DVDD")
			(pintype "passive")
			(solder_mask_margin 0.05)
			(teardrops
				(best_length_ratio 0.4)
				(max_length 1)
				(best_width_ratio 0.9)
				(max_width 2)
				(curved_edges yes)
				(filter_ratio 0.9)
				(enabled yes)
				(allow_two_segments yes)
				(prefer_zone_connections yes)
			)
		)
		(pad "F8" smd circle
			(at 1.5 -0.5 270)
			(size 0.5 0.5)
			(layers "F.Cu" "F.Mask" "F.Paste")
			(net 1 "GND")
			(pinfunction "GND")
			(pintype "passive")
			(solder_mask_margin 0.05)
			(teardrops
				(best_length_ratio 0.4)
				(max_length 1)
				(best_width_ratio 0.9)
				(max_width 2)
				(curved_edges yes)
				(filter_ratio 0.9)
				(enabled yes)
				(allow_two_segments yes)
				(prefer_zone_connections yes)
			)
		)
		(pad "F9" smd circle
			(at 2.5 -0.5 270)
			(size 0.5 0.5)
			(layers "F.Cu" "F.Mask" "F.Paste")
			(net 74 "+1V0")
			(pinfunction "VDDT_{LS/HS}")
			(pintype "passive")
			(solder_mask_margin 0.05)
			(teardrops
				(best_length_ratio 0.4)
				(max_length 1)
				(best_width_ratio 0.9)
				(max_width 2)
				(curved_edges yes)
				(filter_ratio 0.9)
				(enabled yes)
				(allow_two_segments yes)
				(prefer_zone_connections yes)
			)
		)
		(pad "F10" smd circle
			(at 3.5 -0.5 270)
			(size 0.5 0.5)
			(layers "F.Cu" "F.Mask" "F.Paste")
			(net 1 "GND")
			(pinfunction "GND")
			(pintype "passive")
			(solder_mask_margin 0.05)
			(teardrops
				(best_length_ratio 0.4)
				(max_length 1)
				(best_width_ratio 0.9)
				(max_width 2)
				(curved_edges yes)
				(filter_ratio 0.9)
				(enabled yes)
				(allow_two_segments yes)
				(prefer_zone_connections yes)
			)
		)
		(pad "F11" smd circle
			(at 4.5 -0.5 270)
			(size 0.5 0.5)
			(layers "F.Cu" "F.Mask" "F.Paste")
			(net 74 "+1V0")
			(pinfunction "VDDA_{LS/HS}")
			(pintype "passive")
			(solder_mask_margin 0.05)
			(teardrops
				(best_length_ratio 0.4)
				(max_length 1)
				(best_width_ratio 0.9)
				(max_width 2)
				(curved_edges yes)
				(filter_ratio 0.9)
				(enabled yes)
				(allow_two_segments yes)
				(prefer_zone_connections yes)
			)
		)
		(pad "F12" smd circle
			(at 5.5 -0.5 270)
			(size 0.5 0.5)
			(layers "F.Cu" "F.Mask" "F.Paste")
			(net 1 "GND")
			(pinfunction "GND")
			(pintype "passive")
			(solder_mask_margin 0.05)
			(teardrops
				(best_length_ratio 0.4)
				(max_length 1)
				(best_width_ratio 0.9)
				(max_width 2)
				(curved_edges yes)
				(filter_ratio 0.9)
				(enabled yes)
				(allow_two_segments yes)
				(prefer_zone_connections yes)
			)
		)
		(pad "G1" smd circle
			(at -5.5 0.5 270)
			(size 0.5 0.5)
			(layers "F.Cu" "F.Mask" "F.Paste")
			(net 1 "GND")
			(pinfunction "GND")
			(pintype "passive")
			(solder_mask_margin 0.05)
			(teardrops
				(best_length_ratio 0.4)
				(max_length 1)
				(best_width_ratio 0.9)
				(max_width 2)
				(curved_edges yes)
				(filter_ratio 0.9)
				(enabled yes)
				(allow_two_segments yes)
				(prefer_zone_connections yes)
			)
		)
		(pad "G2" smd circle
			(at -4.5 0.5 270)
			(size 0.5 0.5)
			(layers "F.Cu" "F.Mask" "F.Paste")
			(net 74 "+1V0")
			(pinfunction "VDDA_{LS/HS}")
			(pintype "passive")
			(solder_mask_margin 0.05)
			(teardrops
				(best_length_ratio 0.4)
				(max_length 1)
				(best_width_ratio 0.9)
				(max_width 2)
				(curved_edges yes)
				(filter_ratio 0.9)
				(enabled yes)
				(allow_two_segments yes)
				(prefer_zone_connections yes)
			)
		)
		(pad "G3" smd circle
			(at -3.5 0.5 270)
			(size 0.5 0.5)
			(layers "F.Cu" "F.Mask" "F.Paste")
			(net 1 "GND")
			(pinfunction "GND")
			(pintype "passive")
			(solder_mask_margin 0.05)
			(teardrops
				(best_length_ratio 0.4)
				(max_length 1)
				(best_width_ratio 0.9)
				(max_width 2)
				(curved_edges yes)
				(filter_ratio 0.9)
				(enabled yes)
				(allow_two_segments yes)
				(prefer_zone_connections yes)
			)
		)
		(pad "G4" smd circle
			(at -2.5 0.5 270)
			(size 0.5 0.5)
			(layers "F.Cu" "F.Mask" "F.Paste")
			(net 74 "+1V0")
			(pinfunction "VDDT_{LS/HS}")
			(pintype "passive")
			(solder_mask_margin 0.05)
			(teardrops
				(best_length_ratio 0.4)
				(max_length 1)
				(best_width_ratio 0.9)
				(max_width 2)
				(curved_edges yes)
				(filter_ratio 0.9)
				(enabled yes)
				(allow_two_segments yes)
				(prefer_zone_connections yes)
			)
		)
		(pad "G5" smd circle
			(at -1.5 0.5 270)
			(size 0.5 0.5)
			(layers "F.Cu" "F.Mask" "F.Paste")
			(net 1 "GND")
			(pinfunction "GND")
			(pintype "passive")
			(solder_mask_margin 0.05)
			(teardrops
				(best_length_ratio 0.4)
				(max_length 1)
				(best_width_ratio 0.9)
				(max_width 2)
				(curved_edges yes)
				(filter_ratio 0.9)
				(enabled yes)
				(allow_two_segments yes)
				(prefer_zone_connections yes)
			)
		)
		(pad "G6" smd circle
			(at -0.5 0.5 270)
			(size 0.5 0.5)
			(layers "F.Cu" "F.Mask" "F.Paste")
			(net 74 "+1V0")
			(pinfunction "DVDD")
			(pintype "passive")
			(solder_mask_margin 0.05)
			(teardrops
				(best_length_ratio 0.4)
				(max_length 1)
				(best_width_ratio 0.9)
				(max_width 2)
				(curved_edges yes)
				(filter_ratio 0.9)
				(enabled yes)
				(allow_two_segments yes)
				(prefer_zone_connections yes)
			)
		)
		(pad "G7" smd circle
			(at 0.5 0.5 270)
			(size 0.5 0.5)
			(layers "F.Cu" "F.Mask" "F.Paste")
			(net 1 "GND")
			(pinfunction "GND")
			(pintype "passive")
			(solder_mask_margin 0.05)
			(teardrops
				(best_length_ratio 0.4)
				(max_length 1)
				(best_width_ratio 0.9)
				(max_width 2)
				(curved_edges yes)
				(filter_ratio 0.9)
				(enabled yes)
				(allow_two_segments yes)
				(prefer_zone_connections yes)
			)
		)
		(pad "G8" smd circle
			(at 1.5 0.5 270)
			(size 0.5 0.5)
			(layers "F.Cu" "F.Mask" "F.Paste")
			(net 74 "+1V0")
			(pinfunction "DVDD")
			(pintype "passive")
			(solder_mask_margin 0.05)
			(teardrops
				(best_length_ratio 0.4)
				(max_length 1)
				(best_width_ratio 0.9)
				(max_width 2)
				(curved_edges yes)
				(filter_ratio 0.9)
				(enabled yes)
				(allow_two_segments yes)
				(prefer_zone_connections yes)
			)
		)
		(pad "G9" smd circle
			(at 2.5 0.5 270)
			(size 0.5 0.5)
			(layers "F.Cu" "F.Mask" "F.Paste")
			(net 656 "Net-(U43C-PRTAD1)")
			(pinfunction "PRTAD1")
			(pintype "input")
			(solder_mask_margin 0.05)
			(teardrops
				(best_length_ratio 0.4)
				(max_length 1)
				(best_width_ratio 0.9)
				(max_width 2)
				(curved_edges yes)
				(filter_ratio 0.9)
				(enabled yes)
				(allow_two_segments yes)
				(prefer_zone_connections yes)
			)
		)
		(pad "G10" smd circle
			(at 3.5 0.5 270)
			(size 0.5 0.5)
			(layers "F.Cu" "F.Mask" "F.Paste")
			(net 74 "+1V0")
			(pinfunction "VDDA_{LS/HS}")
			(pintype "passive")
			(solder_mask_margin 0.05)
			(teardrops
				(best_length_ratio 0.4)
				(max_length 1)
				(best_width_ratio 0.9)
				(max_width 2)
				(curved_edges yes)
				(filter_ratio 0.9)
				(enabled yes)
				(allow_two_segments yes)
				(prefer_zone_connections yes)
			)
		)
		(pad "G11" smd circle
			(at 4.5 0.5 270)
			(size 0.5 0.5)
			(layers "F.Cu" "F.Mask" "F.Paste")
			(net 1 "GND")
			(pinfunction "GND")
			(pintype "passive")
			(solder_mask_margin 0.05)
			(teardrops
				(best_length_ratio 0.4)
				(max_length 1)
				(best_width_ratio 0.9)
				(max_width 2)
				(curved_edges yes)
				(filter_ratio 0.9)
				(enabled yes)
				(allow_two_segments yes)
				(prefer_zone_connections yes)
			)
		)
		(pad "G12" smd circle
			(at 5.5 0.5 270)
			(size 0.5 0.5)
			(layers "F.Cu" "F.Mask" "F.Paste")
			(net 686 "/2xSFP+/KR to SFI #1/SFI_R.RX-")
			(pinfunction "HSRXB-")
			(pintype "input")
			(solder_mask_margin 0.05)
			(teardrops
				(best_length_ratio 0.4)
				(max_length 1)
				(best_width_ratio 0.9)
				(max_width 2)
				(curved_edges yes)
				(filter_ratio 0.9)
				(enabled yes)
				(allow_two_segments yes)
				(prefer_zone_connections yes)
			)
		)
		(pad "H1" smd circle
			(at -5.5 1.5 270)
			(size 0.5 0.5)
			(layers "F.Cu" "F.Mask" "F.Paste")
			(net 816 "unconnected-(U43B-INB0+-PadH1)")
			(pinfunction "INB0+")
			(pintype "input+no_connect")
			(solder_mask_margin 0.05)
			(teardrops
				(best_length_ratio 0.4)
				(max_length 1)
				(best_width_ratio 0.9)
				(max_width 2)
				(curved_edges yes)
				(filter_ratio 0.9)
				(enabled yes)
				(allow_two_segments yes)
				(prefer_zone_connections yes)
			)
		)
		(pad "H2" smd circle
			(at -4.5 1.5 270)
			(size 0.5 0.5)
			(layers "F.Cu" "F.Mask" "F.Paste")
			(net 1 "GND")
			(pinfunction "GND")
			(pintype "passive")
			(solder_mask_margin 0.05)
			(teardrops
				(best_length_ratio 0.4)
				(max_length 1)
				(best_width_ratio 0.9)
				(max_width 2)
				(curved_edges yes)
				(filter_ratio 0.9)
				(enabled yes)
				(allow_two_segments yes)
				(prefer_zone_connections yes)
			)
		)
		(pad "H3" smd circle
			(at -3.5 1.5 270)
			(size 0.5 0.5)
			(layers "F.Cu" "F.Mask" "F.Paste")
			(net 817 "unconnected-(U43B-OUTB0--PadH3)")
			(pinfunction "OUTB0-")
			(pintype "output+no_connect")
			(solder_mask_margin 0.05)
			(teardrops
				(best_length_ratio 0.4)
				(max_length 1)
				(best_width_ratio 0.9)
				(max_width 2)
				(curved_edges yes)
				(filter_ratio 0.9)
				(enabled yes)
				(allow_two_segments yes)
				(prefer_zone_connections yes)
			)
		)
		(pad "H4" smd circle
			(at -2.5 1.5 270)
			(size 0.5 0.5)
			(layers "F.Cu" "F.Mask" "F.Paste")
			(net 1 "GND")
			(pinfunction "GND")
			(pintype "passive")
			(solder_mask_margin 0.05)
			(teardrops
				(best_length_ratio 0.4)
				(max_length 1)
				(best_width_ratio 0.9)
				(max_width 2)
				(curved_edges yes)
				(filter_ratio 0.9)
				(enabled yes)
				(allow_two_segments yes)
				(prefer_zone_connections yes)
			)
		)
		(pad "H5" smd circle
			(at -1.5 1.5 270)
			(size 0.5 0.5)
			(layers "F.Cu" "F.Mask" "F.Paste")
			(net 141 "/2xSFP+/KR to SFI #1/~{RESET}")
			(pinfunction "~{RESET}")
			(pintype "input")
			(solder_mask_margin 0.05)
			(teardrops
				(best_length_ratio 0.4)
				(max_length 1)
				(best_width_ratio 0.9)
				(max_width 2)
				(curved_edges yes)
				(filter_ratio 0.9)
				(enabled yes)
				(allow_two_segments yes)
				(prefer_zone_connections yes)
			)
		)
		(pad "H6" smd circle
			(at -0.5 1.5 270)
			(size 0.5 0.5)
			(layers "F.Cu" "F.Mask" "F.Paste")
			(net 74 "+1V0")
			(pinfunction "VDDD")
			(pintype "passive")
			(solder_mask_margin 0.05)
			(teardrops
				(best_length_ratio 0.4)
				(max_length 1)
				(best_width_ratio 0.9)
				(max_width 2)
				(curved_edges yes)
				(filter_ratio 0.9)
				(enabled yes)
				(allow_two_segments yes)
				(prefer_zone_connections yes)
			)
		)
		(pad "H7" smd circle
			(at 0.5 1.5 270)
			(size 0.5 0.5)
			(layers "F.Cu" "F.Mask" "F.Paste")
			(net 74 "+1V0")
			(pinfunction "DVDD")
			(pintype "passive")
			(solder_mask_margin 0.05)
			(teardrops
				(best_length_ratio 0.4)
				(max_length 1)
				(best_width_ratio 0.9)
				(max_width 2)
				(curved_edges yes)
				(filter_ratio 0.9)
				(enabled yes)
				(allow_two_segments yes)
				(prefer_zone_connections yes)
			)
		)
		(pad "H8" smd circle
			(at 1.5 1.5 270)
			(size 0.5 0.5)
			(layers "F.Cu" "F.Mask" "F.Paste")
			(net 74 "+1V0")
			(pinfunction "VDDD")
			(pintype "passive")
			(solder_mask_margin 0.05)
			(teardrops
				(best_length_ratio 0.4)
				(max_length 1)
				(best_width_ratio 0.9)
				(max_width 2)
				(curved_edges yes)
				(filter_ratio 0.9)
				(enabled yes)
				(allow_two_segments yes)
				(prefer_zone_connections yes)
			)
		)
		(pad "H9" smd circle
			(at 2.5 1.5 270)
			(size 0.5 0.5)
			(layers "F.Cu" "F.Mask" "F.Paste")
			(net 739 "Net-(U43B-LS_OK_{OUT_B})")
			(pinfunction "LS_OK_{OUT_B}")
			(pintype "output")
			(solder_mask_margin 0.05)
			(teardrops
				(best_length_ratio 0.4)
				(max_length 1)
				(best_width_ratio 0.9)
				(max_width 2)
				(curved_edges yes)
				(filter_ratio 0.9)
				(enabled yes)
				(allow_two_segments yes)
				(prefer_zone_connections yes)
			)
		)
		(pad "H10" smd circle
			(at 3.5 1.5 270)
			(size 0.5 0.5)
			(layers "F.Cu" "F.Mask" "F.Paste")
			(net 662 "Net-(U43C-MODE_{SEL})")
			(pinfunction "MODE_{SEL}")
			(pintype "input")
			(solder_mask_margin 0.05)
			(teardrops
				(best_length_ratio 0.4)
				(max_length 1)
				(best_width_ratio 0.9)
				(max_width 2)
				(curved_edges yes)
				(filter_ratio 0.9)
				(enabled yes)
				(allow_two_segments yes)
				(prefer_zone_connections yes)
			)
		)
		(pad "H11" smd circle
			(at 4.5 1.5 270)
			(size 0.5 0.5)
			(layers "F.Cu" "F.Mask" "F.Paste")
			(net 1 "GND")
			(pinfunction "GND")
			(pintype "passive")
			(solder_mask_margin 0.05)
			(teardrops
				(best_length_ratio 0.4)
				(max_length 1)
				(best_width_ratio 0.9)
				(max_width 2)
				(curved_edges yes)
				(filter_ratio 0.9)
				(enabled yes)
				(allow_two_segments yes)
				(prefer_zone_connections yes)
			)
		)
		(pad "H12" smd circle
			(at 5.5 1.5 270)
			(size 0.5 0.5)
			(layers "F.Cu" "F.Mask" "F.Paste")
			(net 667 "/2xSFP+/KR to SFI #1/SFI_R.RX+")
			(pinfunction "HSRXB+")
			(pintype "input")
			(solder_mask_margin 0.05)
			(teardrops
				(best_length_ratio 0.4)
				(max_length 1)
				(best_width_ratio 0.9)
				(max_width 2)
				(curved_edges yes)
				(filter_ratio 0.9)
				(enabled yes)
				(allow_two_segments yes)
				(prefer_zone_connections yes)
			)
		)
		(pad "J1" smd circle
			(at -5.5 2.5 270)
			(size 0.5 0.5)
			(layers "F.Cu" "F.Mask" "F.Paste")
			(net 818 "unconnected-(U43B-INB0--PadJ1)")
			(pinfunction "INB0-")
			(pintype "input+no_connect")
			(solder_mask_margin 0.05)
			(teardrops
				(best_length_ratio 0.4)
				(max_length 1)
				(best_width_ratio 0.9)
				(max_width 2)
				(curved_edges yes)
				(filter_ratio 0.9)
				(enabled yes)
				(allow_two_segments yes)
				(prefer_zone_connections yes)
			)
		)
		(pad "J2" smd circle
			(at -4.5 2.5 270)
			(size 0.5 0.5)
			(layers "F.Cu" "F.Mask" "F.Paste")
			(net 74 "+1V0")
			(pinfunction "VDDA_{LS/HS}")
			(pintype "passive")
			(solder_mask_margin 0.05)
			(teardrops
				(best_length_ratio 0.4)
				(max_length 1)
				(best_width_ratio 0.9)
				(max_width 2)
				(curved_edges yes)
				(filter_ratio 0.9)
				(enabled yes)
				(allow_two_segments yes)
				(prefer_zone_connections yes)
			)
		)
		(pad "J3" smd circle
			(at -3.5 2.5 270)
			(size 0.5 0.5)
			(layers "F.Cu" "F.Mask" "F.Paste")
			(net 819 "unconnected-(U43B-OUTB0+-PadJ3)")
			(pinfunction "OUTB0+")
			(pintype "output+no_connect")
			(solder_mask_margin 0.05)
			(teardrops
				(best_length_ratio 0.4)
				(max_length 1)
				(best_width_ratio 0.9)
				(max_width 2)
				(curved_edges yes)
				(filter_ratio 0.9)
				(enabled yes)
				(allow_two_segments yes)
				(prefer_zone_connections yes)
			)
		)
		(pad "J4" smd circle
			(at -2.5 2.5 270)
			(size 0.5 0.5)
			(layers "F.Cu" "F.Mask" "F.Paste")
			(net 660 "Net-(U43B-~{PDTRXB})")
			(pinfunction "~{PDTRXB}")
			(pintype "input")
			(solder_mask_margin 0.05)
			(teardrops
				(best_length_ratio 0.4)
				(max_length 1)
				(best_width_ratio 0.9)
				(max_width 2)
				(curved_edges yes)
				(filter_ratio 0.9)
				(enabled yes)
				(allow_two_segments yes)
				(prefer_zone_connections yes)
			)
		)
		(pad "J5" smd circle
			(at -1.5 2.5 270)
			(size 0.5 0.5)
			(layers "F.Cu" "F.Mask" "F.Paste")
			(net 1 "GND")
			(pinfunction "GND")
			(pintype "passive")
			(solder_mask_margin 0.05)
			(teardrops
				(best_length_ratio 0.4)
				(max_length 1)
				(best_width_ratio 0.9)
				(max_width 2)
				(curved_edges yes)
				(filter_ratio 0.9)
				(enabled yes)
				(allow_two_segments yes)
				(prefer_zone_connections yes)
			)
		)
		(pad "J6" smd circle
			(at -0.5 2.5 270)
			(size 0.5 0.5)
			(layers "F.Cu" "F.Mask" "F.Paste")
			(net 659 "Net-(U43C-PRTAD3)")
			(pinfunction "PRTAD3")
			(pintype "input")
			(solder_mask_margin 0.05)
			(teardrops
				(best_length_ratio 0.4)
				(max_length 1)
				(best_width_ratio 0.9)
				(max_width 2)
				(curved_edges yes)
				(filter_ratio 0.9)
				(enabled yes)
				(allow_two_segments yes)
				(prefer_zone_connections yes)
			)
		)
		(pad "J7" smd circle
			(at 0.5 2.5 270)
			(size 0.5 0.5)
			(layers "F.Cu" "F.Mask" "F.Paste")
			(net 649 "/2xSFP+/KR to SFI #1/MDIO")
			(pinfunction "MDIO")
			(pintype "bidirectional")
			(solder_mask_margin 0.05)
			(teardrops
				(best_length_ratio 0.4)
				(max_length 1)
				(best_width_ratio 0.9)
				(max_width 2)
				(curved_edges yes)
				(filter_ratio 0.9)
				(enabled yes)
				(allow_two_segments yes)
				(prefer_zone_connections yes)
			)
		)
		(pad "J8" smd circle
			(at 1.5 2.5 270)
			(size 0.5 0.5)
			(layers "F.Cu" "F.Mask" "F.Paste")
			(net 651 "/2xSFP+/KR to SFI #1/MDC")
			(pinfunction "MDC")
			(pintype "input")
			(solder_mask_margin 0.05)
			(teardrops
				(best_length_ratio 0.4)
				(max_length 1)
				(best_width_ratio 0.9)
				(max_width 2)
				(curved_edges yes)
				(filter_ratio 0.9)
				(enabled yes)
				(allow_two_segments yes)
				(prefer_zone_connections yes)
			)
		)
		(pad "J9" smd circle
			(at 2.5 2.5 270)
			(size 0.5 0.5)
			(layers "F.Cu" "F.Mask" "F.Paste")
			(net 727 "Net-(U43C-PRBS_{PASS})")
			(pinfunction "PRBS_{PASS}")
			(pintype "output")
			(solder_mask_margin 0.05)
			(teardrops
				(best_length_ratio 0.4)
				(max_length 1)
				(best_width_ratio 0.9)
				(max_width 2)
				(curved_edges yes)
				(filter_ratio 0.9)
				(enabled yes)
				(allow_two_segments yes)
				(prefer_zone_connections yes)
			)
		)
		(pad "J10" smd circle
			(at 3.5 2.5 270)
			(size 0.5 0.5)
			(layers "F.Cu" "F.Mask" "F.Paste")
			(net 654 "Net-(U43C-GPI0)")
			(pinfunction "GPI0")
			(pintype "input")
			(solder_mask_margin 0.05)
			(teardrops
				(best_length_ratio 0.4)
				(max_length 1)
				(best_width_ratio 0.9)
				(max_width 2)
				(curved_edges yes)
				(filter_ratio 0.9)
				(enabled yes)
				(allow_two_segments yes)
				(prefer_zone_connections yes)
			)
		)
		(pad "J11" smd circle
			(at 4.5 2.5 270)
			(size 0.5 0.5)
			(layers "F.Cu" "F.Mask" "F.Paste")
			(net 78 "+1V8")
			(pinfunction "VDDRB_{LS/HS}")
			(pintype "power_in")
			(solder_mask_margin 0.05)
			(teardrops
				(best_length_ratio 0.4)
				(max_length 1)
				(best_width_ratio 0.9)
				(max_width 2)
				(curved_edges yes)
				(filter_ratio 0.9)
				(enabled yes)
				(allow_two_segments yes)
				(prefer_zone_connections yes)
			)
		)
		(pad "J12" smd circle
			(at 5.5 2.5 270)
			(size 0.5 0.5)
			(layers "F.Cu" "F.Mask" "F.Paste")
			(net 1 "GND")
			(pinfunction "GND")
			(pintype "passive")
			(solder_mask_margin 0.05)
			(teardrops
				(best_length_ratio 0.4)
				(max_length 1)
				(best_width_ratio 0.9)
				(max_width 2)
				(curved_edges yes)
				(filter_ratio 0.9)
				(enabled yes)
				(allow_two_segments yes)
				(prefer_zone_connections yes)
			)
		)
		(pad "K1" smd circle
			(at -5.5 3.5 270)
			(size 0.5 0.5)
			(layers "F.Cu" "F.Mask" "F.Paste")
			(net 1 "GND")
			(pinfunction "GND")
			(pintype "passive")
			(solder_mask_margin 0.05)
			(teardrops
				(best_length_ratio 0.4)
				(max_length 1)
				(best_width_ratio 0.9)
				(max_width 2)
				(curved_edges yes)
				(filter_ratio 0.9)
				(enabled yes)
				(allow_two_segments yes)
				(prefer_zone_connections yes)
			)
		)
		(pad "K2" smd circle
			(at -4.5 3.5 270)
			(size 0.5 0.5)
			(layers "F.Cu" "F.Mask" "F.Paste")
			(net 820 "unconnected-(U43B-INB1+-PadK2)")
			(pinfunction "INB1+")
			(pintype "input+no_connect")
			(solder_mask_margin 0.05)
			(teardrops
				(best_length_ratio 0.4)
				(max_length 1)
				(best_width_ratio 0.9)
				(max_width 2)
				(curved_edges yes)
				(filter_ratio 0.9)
				(enabled yes)
				(allow_two_segments yes)
				(prefer_zone_connections yes)
			)
		)
		(pad "K3" smd circle
			(at -3.5 3.5 270)
			(size 0.5 0.5)
			(layers "F.Cu" "F.Mask" "F.Paste")
			(net 78 "+1V8")
			(pinfunction "VDDRB_{LS/HS}")
			(pintype "passive")
			(solder_mask_margin 0.05)
			(teardrops
				(best_length_ratio 0.4)
				(max_length 1)
				(best_width_ratio 0.9)
				(max_width 2)
				(curved_edges yes)
				(filter_ratio 0.9)
				(enabled yes)
				(allow_two_segments yes)
				(prefer_zone_connections yes)
			)
		)
		(pad "K4" smd circle
			(at -2.5 3.5 270)
			(size 0.5 0.5)
			(layers "F.Cu" "F.Mask" "F.Paste")
			(net 821 "unconnected-(U43B-OUTB1--PadK4)")
			(pinfunction "OUTB1-")
			(pintype "output+no_connect")
			(solder_mask_margin 0.05)
			(teardrops
				(best_length_ratio 0.4)
				(max_length 1)
				(best_width_ratio 0.9)
				(max_width 2)
				(curved_edges yes)
				(filter_ratio 0.9)
				(enabled yes)
				(allow_two_segments yes)
				(prefer_zone_connections yes)
			)
		)
		(pad "K5" smd circle
			(at -1.5 3.5 270)
			(size 0.5 0.5)
			(layers "F.Cu" "F.Mask" "F.Paste")
			(net 822 "unconnected-(U43B-OUTB1+-PadK5)")
			(pinfunction "OUTB1+")
			(pintype "output+no_connect")
			(solder_mask_margin 0.05)
			(teardrops
				(best_length_ratio 0.4)
				(max_length 1)
				(best_width_ratio 0.9)
				(max_width 2)
				(curved_edges yes)
				(filter_ratio 0.9)
				(enabled yes)
				(allow_two_segments yes)
				(prefer_zone_connections yes)
			)
		)
		(pad "K6" smd circle
			(at -0.5 3.5 270)
			(size 0.5 0.5)
			(layers "F.Cu" "F.Mask" "F.Paste")
			(net 1 "GND")
			(pinfunction "GND")
			(pintype "passive")
			(solder_mask_margin 0.05)
			(teardrops
				(best_length_ratio 0.4)
				(max_length 1)
				(best_width_ratio 0.9)
				(max_width 2)
				(curved_edges yes)
				(filter_ratio 0.9)
				(enabled yes)
				(allow_two_segments yes)
				(prefer_zone_connections yes)
			)
		)
		(pad "K7" smd circle
			(at 0.5 3.5 270)
			(size 0.5 0.5)
			(layers "F.Cu" "F.Mask" "F.Paste")
			(net 74 "+1V0")
			(pinfunction "VDDO1")
			(pintype "power_in")
			(solder_mask_margin 0.05)
			(teardrops
				(best_length_ratio 0.4)
				(max_length 1)
				(best_width_ratio 0.9)
				(max_width 2)
				(curved_edges yes)
				(filter_ratio 0.9)
				(enabled yes)
				(allow_two_segments yes)
				(prefer_zone_connections yes)
			)
		)
		(pad "K8" smd circle
			(at 1.5 3.5 270)
			(size 0.5 0.5)
			(layers "F.Cu" "F.Mask" "F.Paste")
			(net 737 "Net-(U43B-LOSB)")
			(pinfunction "LOSB")
			(pintype "output")
			(solder_mask_margin 0.05)
			(teardrops
				(best_length_ratio 0.4)
				(max_length 1)
				(best_width_ratio 0.9)
				(max_width 2)
				(curved_edges yes)
				(filter_ratio 0.9)
				(enabled yes)
				(allow_two_segments yes)
				(prefer_zone_connections yes)
			)
		)
		(pad "K9" smd circle
			(at 2.5 3.5 270)
			(size 0.5 0.5)
			(layers "F.Cu" "F.Mask" "F.Paste")
			(net 720 "Net-(U43C-REFCLK1+)")
			(pinfunction "REFCLK1+")
			(pintype "input")
			(solder_mask_margin 0.05)
			(teardrops
				(best_length_ratio 0.4)
				(max_length 1)
				(best_width_ratio 0.9)
				(max_width 2)
				(curved_edges yes)
				(filter_ratio 0.9)
				(enabled yes)
				(allow_two_segments yes)
				(prefer_zone_connections yes)
			)
		)
		(pad "K10" smd circle
			(at 3.5 3.5 270)
			(size 0.5 0.5)
			(layers "F.Cu" "F.Mask" "F.Paste")
			(net 721 "Net-(U43C-REFCLK1-)")
			(pinfunction "REFCLK1-")
			(pintype "input")
			(solder_mask_margin 0.05)
			(teardrops
				(best_length_ratio 0.4)
				(max_length 1)
				(best_width_ratio 0.9)
				(max_width 2)
				(curved_edges yes)
				(filter_ratio 0.9)
				(enabled yes)
				(allow_two_segments yes)
				(prefer_zone_connections yes)
			)
		)
		(pad "K11" smd circle
			(at 4.5 3.5 270)
			(size 0.5 0.5)
			(layers "F.Cu" "F.Mask" "F.Paste")
			(net 1 "GND")
			(pinfunction "GND")
			(pintype "passive")
			(solder_mask_margin 0.05)
			(teardrops
				(best_length_ratio 0.4)
				(max_length 1)
				(best_width_ratio 0.9)
				(max_width 2)
				(curved_edges yes)
				(filter_ratio 0.9)
				(enabled yes)
				(allow_two_segments yes)
				(prefer_zone_connections yes)
			)
		)
		(pad "K12" smd circle
			(at 5.5 3.5 270)
			(size 0.5 0.5)
			(layers "F.Cu" "F.Mask" "F.Paste")
			(net 666 "/2xSFP+/KR to SFI #1/SFI_R.TX+")
			(pinfunction "HSTXB+")
			(pintype "output")
			(solder_mask_margin 0.05)
			(teardrops
				(best_length_ratio 0.4)
				(max_length 1)
				(best_width_ratio 0.9)
				(max_width 2)
				(curved_edges yes)
				(filter_ratio 0.9)
				(enabled yes)
				(allow_two_segments yes)
				(prefer_zone_connections yes)
			)
		)
		(pad "L1" smd circle
			(at -5.5 4.5 270)
			(size 0.5 0.5)
			(layers "F.Cu" "F.Mask" "F.Paste")
			(net 823 "unconnected-(U43B-INB2+-PadL1)")
			(pinfunction "INB2+")
			(pintype "input+no_connect")
			(solder_mask_margin 0.05)
			(teardrops
				(best_length_ratio 0.4)
				(max_length 1)
				(best_width_ratio 0.9)
				(max_width 2)
				(curved_edges yes)
				(filter_ratio 0.9)
				(enabled yes)
				(allow_two_segments yes)
				(prefer_zone_connections yes)
			)
		)
		(pad "L2" smd circle
			(at -4.5 4.5 270)
			(size 0.5 0.5)
			(layers "F.Cu" "F.Mask" "F.Paste")
			(net 824 "unconnected-(U43B-INB1--PadL2)")
			(pinfunction "INB1-")
			(pintype "input+no_connect")
			(solder_mask_margin 0.05)
			(teardrops
				(best_length_ratio 0.4)
				(max_length 1)
				(best_width_ratio 0.9)
				(max_width 2)
				(curved_edges yes)
				(filter_ratio 0.9)
				(enabled yes)
				(allow_two_segments yes)
				(prefer_zone_connections yes)
			)
		)
		(pad "L3" smd circle
			(at -3.5 4.5 270)
			(size 0.5 0.5)
			(layers "F.Cu" "F.Mask" "F.Paste")
			(net 1 "GND")
			(pinfunction "GND")
			(pintype "passive")
			(solder_mask_margin 0.05)
			(teardrops
				(best_length_ratio 0.4)
				(max_length 1)
				(best_width_ratio 0.9)
				(max_width 2)
				(curved_edges yes)
				(filter_ratio 0.9)
				(enabled yes)
				(allow_two_segments yes)
				(prefer_zone_connections yes)
			)
		)
		(pad "L4" smd circle
			(at -2.5 4.5 270)
			(size 0.5 0.5)
			(layers "F.Cu" "F.Mask" "F.Paste")
			(net 1 "GND")
			(pinfunction "GND")
			(pintype "passive")
			(solder_mask_margin 0.05)
			(teardrops
				(best_length_ratio 0.4)
				(max_length 1)
				(best_width_ratio 0.9)
				(max_width 2)
				(curved_edges yes)
				(filter_ratio 0.9)
				(enabled yes)
				(allow_two_segments yes)
				(prefer_zone_connections yes)
			)
		)
		(pad "L5" smd circle
			(at -1.5 4.5 270)
			(size 0.5 0.5)
			(layers "F.Cu" "F.Mask" "F.Paste")
			(net 825 "unconnected-(U43B-OUTB2--PadL5)")
			(pinfunction "OUTB2-")
			(pintype "output+no_connect")
			(solder_mask_margin 0.05)
			(teardrops
				(best_length_ratio 0.4)
				(max_length 1)
				(best_width_ratio 0.9)
				(max_width 2)
				(curved_edges yes)
				(filter_ratio 0.9)
				(enabled yes)
				(allow_two_segments yes)
				(prefer_zone_connections yes)
			)
		)
		(pad "L6" smd circle
			(at -0.5 4.5 270)
			(size 0.5 0.5)
			(layers "F.Cu" "F.Mask" "F.Paste")
			(net 826 "unconnected-(U43B-OUTB2+-PadL6)")
			(pinfunction "OUTB2+")
			(pintype "output+no_connect")
			(solder_mask_margin 0.05)
			(teardrops
				(best_length_ratio 0.4)
				(max_length 1)
				(best_width_ratio 0.9)
				(max_width 2)
				(curved_edges yes)
				(filter_ratio 0.9)
				(enabled yes)
				(allow_two_segments yes)
				(prefer_zone_connections yes)
			)
		)
		(pad "L7" smd circle
			(at 0.5 4.5 270)
			(size 0.5 0.5)
			(layers "F.Cu" "F.Mask" "F.Paste")
			(net 1 "GND")
			(pinfunction "GND")
			(pintype "passive")
			(solder_mask_margin 0.05)
			(teardrops
				(best_length_ratio 0.4)
				(max_length 1)
				(best_width_ratio 0.9)
				(max_width 2)
				(curved_edges yes)
				(filter_ratio 0.9)
				(enabled yes)
				(allow_two_segments yes)
				(prefer_zone_connections yes)
			)
		)
		(pad "L8" smd circle
			(at 1.5 4.5 270)
			(size 0.5 0.5)
			(layers "F.Cu" "F.Mask" "F.Paste")
			(net 738 "Net-(U43B-LS_OK_{IN_B})")
			(pinfunction "LS_OK_{IN_B}")
			(pintype "input")
			(solder_mask_margin 0.05)
			(teardrops
				(best_length_ratio 0.4)
				(max_length 1)
				(best_width_ratio 0.9)
				(max_width 2)
				(curved_edges yes)
				(filter_ratio 0.9)
				(enabled yes)
				(allow_two_segments yes)
				(prefer_zone_connections yes)
			)
		)
		(pad "L9" smd circle
			(at 2.5 4.5 270)
			(size 0.5 0.5)
			(layers "F.Cu" "F.Mask" "F.Paste")
			(net 658 "Net-(U43C-PRTAD2)")
			(pinfunction "PRTAD2")
			(pintype "input")
			(solder_mask_margin 0.05)
			(teardrops
				(best_length_ratio 0.4)
				(max_length 1)
				(best_width_ratio 0.9)
				(max_width 2)
				(curved_edges yes)
				(filter_ratio 0.9)
				(enabled yes)
				(allow_two_segments yes)
				(prefer_zone_connections yes)
			)
		)
		(pad "L10" smd circle
			(at 3.5 4.5 270)
			(size 0.5 0.5)
			(layers "F.Cu" "F.Mask" "F.Paste")
			(net 653 "Net-(U43C-TESTEN)")
			(pinfunction "TESTEN")
			(pintype "input")
			(solder_mask_margin 0.05)
			(teardrops
				(best_length_ratio 0.4)
				(max_length 1)
				(best_width_ratio 0.9)
				(max_width 2)
				(curved_edges yes)
				(filter_ratio 0.9)
				(enabled yes)
				(allow_two_segments yes)
				(prefer_zone_connections yes)
			)
		)
		(pad "L11" smd circle
			(at 4.5 4.5 270)
			(size 0.5 0.5)
			(layers "F.Cu" "F.Mask" "F.Paste")
			(net 1 "GND")
			(pinfunction "GND")
			(pintype "passive")
			(solder_mask_margin 0.05)
			(teardrops
				(best_length_ratio 0.4)
				(max_length 1)
				(best_width_ratio 0.9)
				(max_width 2)
				(curved_edges yes)
				(filter_ratio 0.9)
				(enabled yes)
				(allow_two_segments yes)
				(prefer_zone_connections yes)
			)
		)
		(pad "L12" smd circle
			(at 5.5 4.5 270)
			(size 0.5 0.5)
			(layers "F.Cu" "F.Mask" "F.Paste")
			(net 685 "/2xSFP+/KR to SFI #1/SFI_R.TX-")
			(pinfunction "HSTXB-")
			(pintype "output")
			(solder_mask_margin 0.05)
			(teardrops
				(best_length_ratio 0.4)
				(max_length 1)
				(best_width_ratio 0.9)
				(max_width 2)
				(curved_edges yes)
				(filter_ratio 0.9)
				(enabled yes)
				(allow_two_segments yes)
				(prefer_zone_connections yes)
			)
		)
		(pad "M1" smd circle
			(at -5.5 5.5 270)
			(size 0.5 0.5)
			(layers "F.Cu" "F.Mask" "F.Paste")
			(net 827 "unconnected-(U43B-INB2--PadM1)")
			(pinfunction "INB2-")
			(pintype "input+no_connect")
			(solder_mask_margin 0.05)
			(teardrops
				(best_length_ratio 0.4)
				(max_length 1)
				(best_width_ratio 0.9)
				(max_width 2)
				(curved_edges yes)
				(filter_ratio 0.9)
				(enabled yes)
				(allow_two_segments yes)
				(prefer_zone_connections yes)
			)
		)
		(pad "M2" smd circle
			(at -4.5 5.5 270)
			(size 0.5 0.5)
			(layers "F.Cu" "F.Mask" "F.Paste")
			(net 1 "GND")
			(pinfunction "GND")
			(pintype "passive")
			(solder_mask_margin 0.05)
			(teardrops
				(best_length_ratio 0.4)
				(max_length 1)
				(best_width_ratio 0.9)
				(max_width 2)
				(curved_edges yes)
				(filter_ratio 0.9)
				(enabled yes)
				(allow_two_segments yes)
				(prefer_zone_connections yes)
			)
		)
		(pad "M3" smd circle
			(at -3.5 5.5 270)
			(size 0.5 0.5)
			(layers "F.Cu" "F.Mask" "F.Paste")
			(net 828 "unconnected-(U43B-INB3+-PadM3)")
			(pinfunction "INB3+")
			(pintype "input+no_connect")
			(solder_mask_margin 0.05)
			(teardrops
				(best_length_ratio 0.4)
				(max_length 1)
				(best_width_ratio 0.9)
				(max_width 2)
				(curved_edges yes)
				(filter_ratio 0.9)
				(enabled yes)
				(allow_two_segments yes)
				(prefer_zone_connections yes)
			)
		)
		(pad "M4" smd circle
			(at -2.5 5.5 270)
			(size 0.5 0.5)
			(layers "F.Cu" "F.Mask" "F.Paste")
			(net 829 "unconnected-(U43B-INB3--PadM4)")
			(pinfunction "INB3-")
			(pintype "input+no_connect")
			(solder_mask_margin 0.05)
			(teardrops
				(best_length_ratio 0.4)
				(max_length 1)
				(best_width_ratio 0.9)
				(max_width 2)
				(curved_edges yes)
				(filter_ratio 0.9)
				(enabled yes)
				(allow_two_segments yes)
				(prefer_zone_connections yes)
			)
		)
		(pad "M5" smd circle
			(at -1.5 5.5 270)
			(size 0.5 0.5)
			(layers "F.Cu" "F.Mask" "F.Paste")
			(net 1 "GND")
			(pinfunction "GND")
			(pintype "passive")
			(solder_mask_margin 0.05)
			(teardrops
				(best_length_ratio 0.4)
				(max_length 1)
				(best_width_ratio 0.9)
				(max_width 2)
				(curved_edges yes)
				(filter_ratio 0.9)
				(enabled yes)
				(allow_two_segments yes)
				(prefer_zone_connections yes)
			)
		)
		(pad "M6" smd circle
			(at -0.5 5.5 270)
			(size 0.5 0.5)
			(layers "F.Cu" "F.Mask" "F.Paste")
			(net 830 "unconnected-(U43B-OUTB3--PadM6)")
			(pinfunction "OUTB3-")
			(pintype "output+no_connect")
			(solder_mask_margin 0.05)
			(teardrops
				(best_length_ratio 0.4)
				(max_length 1)
				(best_width_ratio 0.9)
				(max_width 2)
				(curved_edges yes)
				(filter_ratio 0.9)
				(enabled yes)
				(allow_two_segments yes)
				(prefer_zone_connections yes)
			)
		)
		(pad "M7" smd circle
			(at 0.5 5.5 270)
			(size 0.5 0.5)
			(layers "F.Cu" "F.Mask" "F.Paste")
			(net 831 "unconnected-(U43B-OUTB3+-PadM7)")
			(pinfunction "OUTB3+")
			(pintype "output+no_connect")
			(solder_mask_margin 0.05)
			(teardrops
				(best_length_ratio 0.4)
				(max_length 1)
				(best_width_ratio 0.9)
				(max_width 2)
				(curved_edges yes)
				(filter_ratio 0.9)
				(enabled yes)
				(allow_two_segments yes)
				(prefer_zone_connections yes)
			)
		)
		(pad "M8" smd circle
			(at 1.5 5.5 270)
			(size 0.5 0.5)
			(layers "F.Cu" "F.Mask" "F.Paste")
			(net 661 "Net-(U43C-PRTAD4)")
			(pinfunction "PRTAD4")
			(pintype "input")
			(solder_mask_margin 0.05)
			(teardrops
				(best_length_ratio 0.4)
				(max_length 1)
				(best_width_ratio 0.9)
				(max_width 2)
				(curved_edges yes)
				(filter_ratio 0.9)
				(enabled yes)
				(allow_two_segments yes)
				(prefer_zone_connections yes)
			)
		)
		(pad "M9" smd circle
			(at 2.5 5.5 270)
			(size 0.5 0.5)
			(layers "F.Cu" "F.Mask" "F.Paste")
			(net 663 "Net-(U43C-ST)")
			(pinfunction "ST")
			(pintype "input")
			(solder_mask_margin 0.05)
			(teardrops
				(best_length_ratio 0.4)
				(max_length 1)
				(best_width_ratio 0.9)
				(max_width 2)
				(curved_edges yes)
				(filter_ratio 0.9)
				(enabled yes)
				(allow_two_segments yes)
				(prefer_zone_connections yes)
			)
		)
		(pad "M10" smd circle
			(at 3.5 5.5 270)
			(size 0.5 0.5)
			(layers "F.Cu" "F.Mask" "F.Paste")
			(net 108 "/2xSFP+/KR to SFI #1/REFCLK+")
			(pinfunction "REFCLK0+")
			(pintype "input")
			(solder_mask_margin 0.05)
			(teardrops
				(best_length_ratio 0.4)
				(max_length 1)
				(best_width_ratio 0.9)
				(max_width 2)
				(curved_edges yes)
				(filter_ratio 0.9)
				(enabled yes)
				(allow_two_segments yes)
				(prefer_zone_connections yes)
			)
		)
		(pad "M11" smd circle
			(at 4.5 5.5 270)
			(size 0.5 0.5)
			(layers "F.Cu" "F.Mask" "F.Paste")
			(net 110 "/2xSFP+/KR to SFI #1/REFCLK-")
			(pinfunction "REFCLK0-")
			(pintype "input")
			(solder_mask_margin 0.05)
			(teardrops
				(best_length_ratio 0.4)
				(max_length 1)
				(best_width_ratio 0.9)
				(max_width 2)
				(curved_edges yes)
				(filter_ratio 0.9)
				(enabled yes)
				(allow_two_segments yes)
				(prefer_zone_connections yes)
			)
		)
		(pad "M12" smd circle
			(at 5.5 5.5 270)
			(size 0.5 0.5)
			(layers "F.Cu" "F.Mask" "F.Paste")
			(net 1 "GND")
			(pinfunction "GND")
			(pintype "passive")
			(solder_mask_margin 0.05)
			(teardrops
				(best_length_ratio 0.4)
				(max_length 1)
				(best_width_ratio 0.9)
				(max_width 2)
				(curved_edges yes)
				(filter_ratio 0.9)
				(enabled yes)
				(allow_two_segments yes)
				(prefer_zone_connections yes)
			)
		)
	)
	(footprint "antmicro-footprints:TP_SMD_0.75mm"
		(layer "F.Cu")
		(at 149.2 128.71)
		(property "Reference" "TP64"
			(at 0.4 -3.3 90)
			(layer "F.SilkS")
			(effects
				(font
					(size 0.7 0.7)
					(thickness 0.15)
				)
				(justify left bottom)
			)
		)
		(property "Value" "TP_0.75mm_SMD"
			(at 0 1.2 0)
			(layer "F.Fab")
			(effects
				(font
					(size 0.7 0.7)
					(thickness 0.15)
				)
				(justify left bottom)
			)
		)
		(property "Author" "Antmicro"
			(at 0 0 0)
			(layer "F.Fab")
			(hide yes)
			(effects
				(font
					(size 1 1)
					(thickness 0.15)
				)
			)
		)
		(property "License" "Apache-2.0"
			(at 0 0 0)
			(layer "F.Fab")
			(hide yes)
			(effects
				(font
					(size 1 1)
					(thickness 0.15)
				)
			)
		)
		(property "MPN" ""
			(at 0 0 0)
			(layer "F.Fab")
			(hide yes)
			(effects
				(font
					(size 1 1)
					(thickness 0.15)
				)
			)
		)
		(property "Manufacturer" ""
			(at 0 0 0)
			(layer "F.Fab")
			(hide yes)
			(effects
				(font
					(size 1 1)
					(thickness 0.15)
				)
			)
		)
		(property "Public" "False"
			(at 0 0 0)
			(layer "F.Fab")
			(hide yes)
			(effects
				(font
					(size 1 1)
					(thickness 0.15)
				)
			)
		)
		(sheetname "KR to SFI #1")
		(sheetfile "kr_sfi.kicad_sch")
		(attr exclude_from_pos_files exclude_from_bom)
		(fp_circle
			(center 0 0)
			(end 0.475 0)
			(stroke
				(width 0.05)
				(type default)
			)
			(fill no)
			(layer "F.CrtYd")
		)
		(pad "1" smd circle
			(at 0 0)
			(size 0.75 0.75)
			(layers "F.Cu" "F.Mask")
			(net 727 "Net-(U43C-PRBS_{PASS})")
			(pinfunction "1")
			(pintype "passive")
			(teardrops
				(best_length_ratio 0.4)
				(max_length 1)
				(best_width_ratio 0.9)
				(max_width 2)
				(curved_edges yes)
				(filter_ratio 0.9)
				(enabled yes)
				(allow_two_segments yes)
				(prefer_zone_connections yes)
			)
		)
	)
	(footprint "antmicro-footprints:R_0402_1005Metric"
		(layer "F.Cu")
		(at 155.299 161.11 180)
		(descr "Resistor SMD 0402")
		(tags "resistor SMD 0402")
		(property "Reference" "R46"
			(at -6.701 17.5 0)
			(layer "F.SilkS")
			(effects
				(font
					(size 0.7 0.7)
					(thickness 0.15)
				)
				(justify right bottom)
			)
		)
		(property "Value" "R_0R_0402"
			(at -1.011843 1.772047 0)
			(layer "F.Fab")
			(effects
				(font
					(size 0.7 0.7)
					(thickness 0.15)
				)
				(justify right bottom)
			)
		)
		(property "Datasheet" "https://industrial.panasonic.com/cdbs/www-data/pdf/RDA0000/AOA0000C301.pdf"
			(at 0 0 180)
			(layer "F.Fab")
			(hide yes)
			(effects
				(font
					(size 1.27 1.27)
					(thickness 0.15)
				)
			)
		)
		(property "Author" "Antmicro"
			(at 310.598 322.22 0)
			(layer "F.Fab")
			(hide yes)
			(effects
				(font
					(size 1 1)
					(thickness 0.15)
				)
			)
		)
		(property "Current" "1A"
			(at 310.598 322.22 0)
			(layer "F.Fab")
			(hide yes)
			(effects
				(font
					(size 1 1)
					(thickness 0.15)
				)
			)
		)
		(property "License" "Apache-2.0"
			(at 310.598 322.22 0)
			(layer "F.Fab")
			(hide yes)
			(effects
				(font
					(size 1 1)
					(thickness 0.15)
				)
			)
		)
		(property "MPN" "ERJ2GE0R00X"
			(at 310.598 322.22 0)
			(layer "F.Fab")
			(hide yes)
			(effects
				(font
					(size 1 1)
					(thickness 0.15)
				)
			)
		)
		(property "Manufacturer" "Panasonic"
			(at 310.598 322.22 0)
			(layer "F.Fab")
			(hide yes)
			(effects
				(font
					(size 1 1)
					(thickness 0.15)
				)
			)
		)
		(property "Public" "False"
			(at 310.598 322.22 0)
			(layer "F.Fab")
			(hide yes)
			(effects
				(font
					(size 1 1)
					(thickness 0.15)
				)
			)
		)
		(property "Tolerance" ""
			(at 310.598 322.22 0)
			(layer "F.Fab")
			(hide yes)
			(effects
				(font
					(size 1 1)
					(thickness 0.15)
				)
			)
		)
		(property "Val" "0R"
			(at 310.598 322.22 0)
			(layer "F.Fab")
			(hide yes)
			(effects
				(font
					(size 1 1)
					(thickness 0.15)
				)
			)
		)
		(sheetname "2xSFP+")
		(sheetfile "2xSFP+.kicad_sch")
		(attr smd)
		(fp_rect
			(start -0.925 -0.47)
			(end 0.925 0.47)
			(stroke
				(width 0.05)
				(type default)
			)
			(fill no)
			(layer "F.CrtYd")
		)
		(fp_rect
			(start -0.5 -0.25)
			(end 0.5 0.25)
			(stroke
				(width 0.15)
				(type solid)
			)
			(fill no)
			(layer "F.Fab")
		)
		(pad "1" smd roundrect
			(at -0.48 0 180)
			(size 0.59 0.64)
			(layers "F.Cu" "F.Mask" "F.Paste")
			(roundrect_rratio 0.25)
			(net 565 "/2xSFP+/~{LED1_0}")
			(pintype "passive")
			(teardrops
				(best_length_ratio 0.2)
				(max_length 1)
				(best_width_ratio 0.9)
				(max_width 2)
				(curved_edges yes)
				(filter_ratio 0.9)
				(enabled yes)
				(allow_two_segments yes)
				(prefer_zone_connections yes)
			)
		)
		(pad "2" smd roundrect
			(at 0.48 0 180)
			(size 0.59 0.64)
			(layers "F.Cu" "F.Mask" "F.Paste")
			(roundrect_rratio 0.25)
			(net 898 "/2xSFP+/SFP1_LEDY")
			(pintype "passive")
			(teardrops
				(best_length_ratio 0.2)
				(max_length 1)
				(best_width_ratio 0.9)
				(max_width 2)
				(curved_edges yes)
				(filter_ratio 0.9)
				(enabled yes)
				(allow_two_segments yes)
				(prefer_zone_connections yes)
			)
		)
	)
	(footprint "antmicro-footprints:Oscillator_SMD_ECS_2520MV_2.5x2mm"
		(layer "F.Cu")
		(at 308.275 78.41)
		(descr "Miniature Crystal Clock Oscillator ECS 2520MV series")
		(tags "Crystal Clock Oscillator ECS 2520MV SMD")
		(property "Reference" "Y1"
			(at 2.125 1.75 90)
			(layer "F.SilkS")
			(effects
				(font
					(size 0.7 0.7)
					(thickness 0.15)
				)
				(justify left bottom)
			)
		)
		(property "Value" "Oscillator_32.768kHz_ECS_2520MV"
			(at 0 2.499 0)
			(layer "F.Fab")
			(effects
				(font
					(size 0.7 0.7)
					(thickness 0.15)
				)
				(justify left bottom)
			)
		)
		(property "Datasheet" "https://ecsxtal.com/store/pdf/ECS-327MVATX.pdf"
			(at 0 0 0)
			(layer "F.Fab")
			(hide yes)
			(effects
				(font
					(size 1.27 1.27)
					(thickness 0.15)
				)
			)
		)
		(property "Author" "Antmicro"
			(at 0 0 0)
			(layer "F.Fab")
			(hide yes)
			(effects
				(font
					(size 1 1)
					(thickness 0.15)
				)
			)
		)
		(property "License" "Apache-2.0"
			(at 0 0 0)
			(layer "F.Fab")
			(hide yes)
			(effects
				(font
					(size 1 1)
					(thickness 0.15)
				)
			)
		)
		(property "MPN" "ECS-327MVATX-2-CN-TR3"
			(at 0 0 0)
			(layer "F.Fab")
			(hide yes)
			(effects
				(font
					(size 1 1)
					(thickness 0.15)
				)
			)
		)
		(property "Manufacturer" "ECS Inc. International"
			(at 0 0 0)
			(layer "F.Fab")
			(hide yes)
			(effects
				(font
					(size 1 1)
					(thickness 0.15)
				)
			)
		)
		(property "Public" "False"
			(at 0 0 0)
			(layer "F.Fab")
			(hide yes)
			(effects
				(font
					(size 1 1)
					(thickness 0.15)
				)
			)
		)
		(property "Val" "32.768 kHz"
			(at 0 0 0)
			(layer "F.Fab")
			(hide yes)
			(effects
				(font
					(size 1 1)
					(thickness 0.15)
				)
			)
		)
		(sheetname "PCIe misc")
		(sheetfile "pcie_misc.kicad_sch")
		(attr smd)
		(fp_line
			(start -1.111 0.32)
			(end -1.111 -0.32)
			(stroke
				(width 0.15)
				(type solid)
			)
			(layer "F.SilkS")
		)
		(fp_line
			(start -0.172 1.36)
			(end 0.17 1.36)
			(stroke
				(width 0.15)
				(type solid)
			)
			(layer "F.SilkS")
		)
		(fp_line
			(start -0.16 -1.361)
			(end 0.17 -1.361)
			(stroke
				(width 0.15)
				(type solid)
			)
			(layer "F.SilkS")
		)
		(fp_line
			(start 1.11 0.32)
			(end 1.11 -0.32)
			(stroke
				(width 0.15)
				(type solid)
			)
			(layer "F.SilkS")
		)
		(fp_circle
			(center -1.1 -1.5)
			(end -1.049 -1.5)
			(stroke
				(width 0.15)
				(type solid)
			)
			(fill yes)
			(layer "F.SilkS")
		)
		(fp_rect
			(start -1.25 -1.5)
			(end 1.25 1.5)
			(stroke
				(width 0.05)
				(type solid)
			)
			(fill no)
			(layer "F.CrtYd")
		)
		(fp_line
			(start -1 -0.75)
			(end -0.5 -1.25)
			(stroke
				(width 0.15)
				(type solid)
			)
			(layer "F.Fab")
		)
		(fp_rect
			(start 1 1.249)
			(end -1 -1.25)
			(stroke
				(width 0.15)
				(type solid)
			)
			(fill no)
			(layer "F.Fab")
		)
		(pad "1" smd roundrect
			(at -0.725 -0.927)
			(size 0.8 0.9)
			(layers "F.Cu" "F.Mask" "F.Paste")
			(roundrect_rratio 0.25)
			(net 610 "Net-(Y1-EN)")
			(pinfunction "EN")
			(pintype "input")
			(teardrops
				(best_length_ratio 0.2)
				(max_length 1)
				(best_width_ratio 0.9)
				(max_width 2)
				(curved_edges yes)
				(filter_ratio 0.9)
				(enabled yes)
				(allow_two_segments yes)
				(prefer_zone_connections yes)
			)
		)
		(pad "2" smd roundrect
			(at -0.725 0.925)
			(size 0.8 0.9)
			(layers "F.Cu" "F.Mask" "F.Paste")
			(roundrect_rratio 0.25)
			(net 1 "GND")
			(pinfunction "GND")
			(pintype "power_in")
			(teardrops
				(best_length_ratio 0.2)
				(max_length 1)
				(best_width_ratio 0.9)
				(max_width 2)
				(curved_edges yes)
				(filter_ratio 0.9)
				(enabled yes)
				(allow_two_segments yes)
				(prefer_zone_connections yes)
			)
		)
		(pad "3" smd roundrect
			(at 0.723 0.925)
			(size 0.8 0.9)
			(layers "F.Cu" "F.Mask" "F.Paste")
			(roundrect_rratio 0.25)
			(net 790 "Net-(U38-1A)")
			(pinfunction "OUT")
			(pintype "output")
			(teardrops
				(best_length_ratio 0.2)
				(max_length 1)
				(best_width_ratio 0.9)
				(max_width 2)
				(curved_edges yes)
				(filter_ratio 0.9)
				(enabled yes)
				(allow_two_segments yes)
				(prefer_zone_connections yes)
			)
		)
		(pad "4" smd roundrect
			(at 0.723 -0.927)
			(size 0.8 0.9)
			(layers "F.Cu" "F.Mask" "F.Paste")
			(roundrect_rratio 0.25)
			(net 2 "+3V3")
			(pinfunction "VDD")
			(pintype "power_in")
			(teardrops
				(best_length_ratio 0.2)
				(max_length 1)
				(best_width_ratio 0.9)
				(max_width 2)
				(curved_edges yes)
				(filter_ratio 0.9)
				(enabled yes)
				(allow_two_segments yes)
				(prefer_zone_connections yes)
			)
		)
	)
	(footprint "antmicro-footprints:TP_SMD_0.75mm"
		(layer "F.Cu")
		(at 136.24 128.71)
		(property "Reference" "TP86"
			(at 0.51 -3.3 90)
			(layer "F.SilkS")
			(effects
				(font
					(size 0.7 0.7)
					(thickness 0.15)
				)
				(justify left bottom)
			)
		)
		(property "Value" "TP_0.75mm_SMD"
			(at 0 1.2 0)
			(layer "F.Fab")
			(effects
				(font
					(size 0.7 0.7)
					(thickness 0.15)
				)
				(justify left bottom)
			)
		)
		(property "Author" "Antmicro"
			(at 0 0 0)
			(layer "F.Fab")
			(hide yes)
			(effects
				(font
					(size 1 1)
					(thickness 0.15)
				)
			)
		)
		(property "License" "Apache-2.0"
			(at 0 0 0)
			(layer "F.Fab")
			(hide yes)
			(effects
				(font
					(size 1 1)
					(thickness 0.15)
				)
			)
		)
		(property "MPN" ""
			(at 0 0 0)
			(layer "F.Fab")
			(hide yes)
			(effects
				(font
					(size 1 1)
					(thickness 0.15)
				)
			)
		)
		(property "Manufacturer" ""
			(at 0 0 0)
			(layer "F.Fab")
			(hide yes)
			(effects
				(font
					(size 1 1)
					(thickness 0.15)
				)
			)
		)
		(property "Public" "False"
			(at 0 0 0)
			(layer "F.Fab")
			(hide yes)
			(effects
				(font
					(size 1 1)
					(thickness 0.15)
				)
			)
		)
		(sheetname "KR to SFI #2")
		(sheetfile "kr_sfi.kicad_sch")
		(attr exclude_from_pos_files exclude_from_bom)
		(fp_circle
			(center 0 0)
			(end 0.475 0)
			(stroke
				(width 0.05)
				(type default)
			)
			(fill no)
			(layer "F.CrtYd")
		)
		(pad "1" smd circle
			(at 0 0)
			(size 0.75 0.75)
			(layers "F.Cu" "F.Mask")
			(net 749 "Net-(U45C-AMUXB)")
			(pinfunction "1")
			(pintype "passive")
			(teardrops
				(best_length_ratio 0.4)
				(max_length 1)
				(best_width_ratio 0.9)
				(max_width 2)
				(curved_edges yes)
				(filter_ratio 0.9)
				(enabled yes)
				(allow_two_segments yes)
				(prefer_zone_connections yes)
			)
		)
	)
	(footprint "antmicro-footprints:R_0603_1608Metric"
		(layer "F.Cu")
		(at 180.13 90.1)
		(descr "Resistor SMD 0603")
		(tags "resistor SMD 0603")
		(property "Reference" "R125"
			(at 1.25 0.45 0)
			(layer "F.SilkS")
			(effects
				(font
					(size 0.7 0.7)
					(thickness 0.15)
				)
				(justify left bottom)
			)
		)
		(property "Value" "R_0R_22.4A_0603"
			(at 0 1.6 0)
			(layer "F.Fab")
			(effects
				(font
					(size 0.7 0.7)
					(thickness 0.15)
				)
				(justify left bottom)
			)
		)
		(property "Datasheet" "https://fscdn.rohm.com/en/products/databook/datasheet/passive/resistor/chip_resistor/pmr-jpw-e.pdf"
			(at 0 0 0)
			(layer "F.Fab")
			(hide yes)
			(effects
				(font
					(size 1.27 1.27)
					(thickness 0.15)
				)
			)
		)
		(property "Author" "Antmicro"
			(at 270.31 -88.19 90)
			(layer "F.Fab")
			(hide yes)
			(effects
				(font
					(size 1 1)
					(thickness 0.15)
				)
			)
		)
		(property "License" "Apache-2.0"
			(at 270.31 -88.19 90)
			(layer "F.Fab")
			(hide yes)
			(effects
				(font
					(size 1 1)
					(thickness 0.15)
				)
			)
		)
		(property "MPN" "PMR03EZPJ000"
			(at 270.31 -88.19 90)
			(layer "F.Fab")
			(hide yes)
			(effects
				(font
					(size 1 1)
					(thickness 0.15)
				)
			)
		)
		(property "Manufacturer" "ROHM Semiconductor"
			(at 270.31 -88.19 90)
			(layer "F.Fab")
			(hide yes)
			(effects
				(font
					(size 1 1)
					(thickness 0.15)
				)
			)
		)
		(property "Max. Curr." "22.4A"
			(at 270.31 -88.19 90)
			(layer "F.Fab")
			(hide yes)
			(effects
				(font
					(size 1 1)
					(thickness 0.15)
				)
			)
		)
		(property "Public" "False"
			(at 270.31 -88.19 90)
			(layer "F.Fab")
			(hide yes)
			(effects
				(font
					(size 1 1)
					(thickness 0.15)
				)
			)
		)
		(property "Tolerance" "template_tolerance"
			(at 270.31 -88.19 90)
			(layer "F.Fab")
			(hide yes)
			(effects
				(font
					(size 1 1)
					(thickness 0.15)
				)
			)
		)
		(property "Val" "0R"
			(at 270.31 -88.19 90)
			(layer "F.Fab")
			(hide yes)
			(effects
				(font
					(size 1 1)
					(thickness 0.15)
				)
			)
		)
		(sheetname "M.2 key M #1")
		(sheetfile "m2keym_low.kicad_sch")
		(attr smd)
		(fp_line
			(start -0.15 -0.4)
			(end 0.15 -0.4)
			(stroke
				(width 0.15)
				(type solid)
			)
			(layer "F.SilkS")
		)
		(fp_line
			(start -0.15 0.4)
			(end 0.15 0.4)
			(stroke
				(width 0.15)
				(type solid)
			)
			(layer "F.SilkS")
		)
		(fp_rect
			(start -1.25 -0.65)
			(end 1.25 0.65)
			(stroke
				(width 0.05)
				(type solid)
			)
			(fill no)
			(layer "F.CrtYd")
		)
		(fp_rect
			(start -0.8 -0.4)
			(end 0.8 0.4)
			(stroke
				(width 0.15)
				(type solid)
			)
			(fill no)
			(layer "F.Fab")
		)
		(pad "1" smd roundrect
			(at -0.7 0)
			(size 0.8 1)
			(layers "F.Cu" "F.Mask" "F.Paste")
			(roundrect_rratio 0.2)
			(net 969 "/M.2 key M #1/M2_3V3")
			(pintype "passive")
			(teardrops
				(best_length_ratio 0.2)
				(max_length 1)
				(best_width_ratio 0.9)
				(max_width 2)
				(curved_edges yes)
				(filter_ratio 0.9)
				(enabled yes)
				(allow_two_segments yes)
				(prefer_zone_connections yes)
			)
		)
		(pad "2" smd roundrect
			(at 0.7 0)
			(size 0.8 1)
			(layers "F.Cu" "F.Mask" "F.Paste")
			(roundrect_rratio 0.2)
			(net 2 "+3V3")
			(pintype "passive")
			(teardrops
				(best_length_ratio 0.2)
				(max_length 1)
				(best_width_ratio 0.9)
				(max_width 2)
				(curved_edges yes)
				(filter_ratio 0.9)
				(enabled yes)
				(allow_two_segments yes)
				(prefer_zone_connections yes)
			)
		)
	)
	(footprint "antmicro-footprints:R_0402_1005Metric"
		(layer "F.Cu")
		(at 190.762015 139.479219 -135)
		(descr "Resistor SMD 0402")
		(tags "resistor SMD 0402")
		(property "Reference" "R227"
			(at 1.119206 -0.465818 45)
			(layer "F.SilkS")
			(effects
				(font
					(size 0.7 0.7)
					(thickness 0.15)
				)
				(justify right bottom)
			)
		)
		(property "Value" "R_1k_0402"
			(at -1.011843 1.772046 45)
			(layer "F.Fab")
			(effects
				(font
					(size 0.7 0.7)
					(thickness 0.15)
				)
				(justify right bottom)
			)
		)
		(property "Datasheet" "https://www.bourns.com/docs/product-datasheets/cr.pdf"
			(at 0 0 45)
			(layer "B.Fab")
			(hide yes)
			(effects
				(font
					(size 1.27 1.27)
					(thickness 0.15)
				)
				(justify mirror)
			)
		)
		(property "Author" "Antmicro"
			(at 0 0 45)
			(layer "F.Fab")
			(hide yes)
			(effects
				(font
					(size 1 1)
					(thickness 0.15)
				)
			)
		)
		(property "License" "Apache-2.0"
			(at 0 0 45)
			(layer "F.Fab")
			(hide yes)
			(effects
				(font
					(size 1 1)
					(thickness 0.15)
				)
			)
		)
		(property "MPN" "CR0402-FX-1001GLF"
			(at 0 0 45)
			(layer "F.Fab")
			(hide yes)
			(effects
				(font
					(size 1 1)
					(thickness 0.15)
				)
			)
		)
		(property "Manufacturer" "Bourns"
			(at 0 0 45)
			(layer "F.Fab")
			(hide yes)
			(effects
				(font
					(size 1 1)
					(thickness 0.15)
				)
			)
		)
		(property "Public" "False"
			(at 0 0 45)
			(layer "F.Fab")
			(hide yes)
			(effects
				(font
					(size 1 1)
					(thickness 0.15)
				)
			)
		)
		(property "Tolerance" "1%"
			(at 0 0 45)
			(layer "F.Fab")
			(hide yes)
			(effects
				(font
					(size 1 1)
					(thickness 0.15)
				)
			)
		)
		(property "Val" "1k"
			(at 0 0 45)
			(layer "F.Fab")
			(hide yes)
			(effects
				(font
					(size 1 1)
					(thickness 0.15)
				)
			)
		)
		(sheetname "PCIe redriver")
		(sheetfile "pcie_redriver.kicad_sch")
		(attr smd dnp)
		(fp_poly
			(pts
				(xy -0.925 -0.47) (xy 0.925 -0.47) (xy 0.925 0.47) (xy -0.925 0.47)
			)
			(stroke
				(width 0.05)
				(type default)
			)
			(fill no)
			(layer "F.CrtYd")
		)
		(fp_poly
			(pts
				(xy -0.5 -0.25) (xy 0.5 -0.25) (xy 0.5 0.25) (xy -0.5 0.25)
			)
			(stroke
				(width 0.15)
				(type solid)
			)
			(fill no)
			(layer "F.Fab")
		)
		(pad "1" smd roundrect
			(at -0.48 0 225)
			(size 0.59 0.64)
			(layers "F.Cu" "F.Mask" "F.Paste")
			(roundrect_rratio 0.25)
			(net 2 "+3V3")
			(pintype "passive")
			(teardrops
				(best_length_ratio 0.2)
				(max_length 1)
				(best_width_ratio 0.9)
				(max_width 2)
				(curved_edges yes)
				(filter_ratio 0.9)
				(enabled yes)
				(allow_two_segments yes)
				(prefer_zone_connections yes)
			)
		)
		(pad "2" smd roundrect
			(at 0.48 0 225)
			(size 0.59 0.64)
			(layers "F.Cu" "F.Mask" "F.Paste")
			(roundrect_rratio 0.25)
			(net 977 "/PCIe redriver/RX_EQ1")
			(pintype "passive")
			(teardrops
				(best_length_ratio 0.2)
				(max_length 1)
				(best_width_ratio 0.9)
				(max_width 2)
				(curved_edges yes)
				(filter_ratio 0.9)
				(enabled yes)
				(allow_two_segments yes)
				(prefer_zone_connections yes)
			)
		)
	)
	(footprint "antmicro-footprints:TP_SMD_0.75mm"
		(layer "F.Cu")
		(at 135.59 129.56)
		(property "Reference" "TP81"
			(at 0.46 -1.25 90)
			(layer "F.SilkS")
			(effects
				(font
					(size 0.7 0.7)
					(thickness 0.15)
				)
				(justify left bottom)
			)
		)
		(property "Value" "TP_0.75mm_SMD"
			(at 0 1.2 0)
			(layer "F.Fab")
			(effects
				(font
					(size 0.7 0.7)
					(thickness 0.15)
				)
				(justify left bottom)
			)
		)
		(property "Author" "Antmicro"
			(at 0 0 0)
			(layer "F.Fab")
			(hide yes)
			(effects
				(font
					(size 1 1)
					(thickness 0.15)
				)
			)
		)
		(property "License" "Apache-2.0"
			(at 0 0 0)
			(layer "F.Fab")
			(hide yes)
			(effects
				(font
					(size 1 1)
					(thickness 0.15)
				)
			)
		)
		(property "MPN" ""
			(at 0 0 0)
			(layer "F.Fab")
			(hide yes)
			(effects
				(font
					(size 1 1)
					(thickness 0.15)
				)
			)
		)
		(property "Manufacturer" ""
			(at 0 0 0)
			(layer "F.Fab")
			(hide yes)
			(effects
				(font
					(size 1 1)
					(thickness 0.15)
				)
			)
		)
		(property "Public" "False"
			(at 0 0 0)
			(layer "F.Fab")
			(hide yes)
			(effects
				(font
					(size 1 1)
					(thickness 0.15)
				)
			)
		)
		(sheetname "KR to SFI #2")
		(sheetfile "kr_sfi.kicad_sch")
		(attr exclude_from_pos_files exclude_from_bom)
		(fp_circle
			(center 0 0)
			(end 0.475 0)
			(stroke
				(width 0.05)
				(type default)
			)
			(fill no)
			(layer "F.CrtYd")
		)
		(pad "1" smd circle
			(at 0 0)
			(size 0.75 0.75)
			(layers "F.Cu" "F.Mask")
			(net 744 "/2xSFP+/KR to SFI #2/TMS")
			(pinfunction "1")
			(pintype "passive")
			(teardrops
				(best_length_ratio 0.4)
				(max_length 1)
				(best_width_ratio 0.9)
				(max_width 2)
				(curved_edges yes)
				(filter_ratio 0.9)
				(enabled yes)
				(allow_two_segments yes)
				(prefer_zone_connections yes)
			)
		)
	)
	(footprint "antmicro-footprints:R_0402_1005Metric"
		(layer "F.Cu")
		(at 209.38 128.82 180)
		(descr "Resistor SMD 0402")
		(tags "resistor SMD 0402")
		(property "Reference" "R193"
			(at 0.83 -0.39 0)
			(layer "F.SilkS")
			(effects
				(font
					(size 0.7 0.7)
					(thickness 0.15)
				)
				(justify right bottom)
			)
		)
		(property "Value" "R_0R_0402"
			(at -1.011843 1.772047 0)
			(layer "F.Fab")
			(effects
				(font
					(size 0.7 0.7)
					(thickness 0.15)
				)
				(justify right bottom)
			)
		)
		(property "Datasheet" "https://industrial.panasonic.com/cdbs/www-data/pdf/RDA0000/AOA0000C301.pdf"
			(at 0 0 180)
			(layer "F.Fab")
			(hide yes)
			(effects
				(font
					(size 1.27 1.27)
					(thickness 0.15)
				)
			)
		)
		(property "Author" "Antmicro"
			(at 418.76 257.64 0)
			(layer "F.Fab")
			(hide yes)
			(effects
				(font
					(size 1 1)
					(thickness 0.15)
				)
			)
		)
		(property "Current" "1A"
			(at 418.76 257.64 0)
			(layer "F.Fab")
			(hide yes)
			(effects
				(font
					(size 1 1)
					(thickness 0.15)
				)
			)
		)
		(property "License" "Apache-2.0"
			(at 418.76 257.64 0)
			(layer "F.Fab")
			(hide yes)
			(effects
				(font
					(size 1 1)
					(thickness 0.15)
				)
			)
		)
		(property "MPN" "ERJ2GE0R00X"
			(at 418.76 257.64 0)
			(layer "F.Fab")
			(hide yes)
			(effects
				(font
					(size 1 1)
					(thickness 0.15)
				)
			)
		)
		(property "Manufacturer" "Panasonic"
			(at 418.76 257.64 0)
			(layer "F.Fab")
			(hide yes)
			(effects
				(font
					(size 1 1)
					(thickness 0.15)
				)
			)
		)
		(property "Public" "False"
			(at 418.76 257.64 0)
			(layer "F.Fab")
			(hide yes)
			(effects
				(font
					(size 1 1)
					(thickness 0.15)
				)
			)
		)
		(property "Tolerance" ""
			(at 418.76 257.64 0)
			(layer "F.Fab")
			(hide yes)
			(effects
				(font
					(size 1 1)
					(thickness 0.15)
				)
			)
		)
		(property "Val" "0R"
			(at 418.76 257.64 0)
			(layer "F.Fab")
			(hide yes)
			(effects
				(font
					(size 1 1)
					(thickness 0.15)
				)
			)
		)
		(sheetname "PCIe misc")
		(sheetfile "pcie_misc.kicad_sch")
		(attr smd)
		(fp_rect
			(start -0.925 -0.47)
			(end 0.925 0.47)
			(stroke
				(width 0.05)
				(type default)
			)
			(fill no)
			(layer "F.CrtYd")
		)
		(fp_rect
			(start -0.5 -0.25)
			(end 0.5 0.25)
			(stroke
				(width 0.15)
				(type solid)
			)
			(fill no)
			(layer "F.Fab")
		)
		(pad "1" smd roundrect
			(at -0.48 0 180)
			(size 0.59 0.64)
			(layers "F.Cu" "F.Mask" "F.Paste")
			(roundrect_rratio 0.25)
			(net 612 "/PCIe misc/DIF0-")
			(pintype "passive")
			(teardrops
				(best_length_ratio 0.2)
				(max_length 1)
				(best_width_ratio 0.9)
				(max_width 2)
				(curved_edges yes)
				(filter_ratio 0.9)
				(enabled yes)
				(allow_two_segments yes)
				(prefer_zone_connections yes)
			)
		)
		(pad "2" smd roundrect
			(at 0.48 0 180)
			(size 0.59 0.64)
			(layers "F.Cu" "F.Mask" "F.Paste")
			(roundrect_rratio 0.25)
			(net 229 "/M.2 key M #1/PCIE_{REF}.CK-")
			(pintype "passive")
			(teardrops
				(best_length_ratio 0.2)
				(max_length 1)
				(best_width_ratio 0.9)
				(max_width 2)
				(curved_edges yes)
				(filter_ratio 0.9)
				(enabled yes)
				(allow_two_segments yes)
				(prefer_zone_connections yes)
			)
		)
	)
	(footprint "antmicro-footprints:Conn_Bel-Fuse_SFP+_2x20_SS-79100-010"
		(locked yes)
		(layer "F.Cu")
		(at 142.55 162.31 -90)
		(property "Reference" "J2"
			(at 8.75 46.6 0)
			(unlocked yes)
			(layer "F.SilkS")
			(effects
				(font
					(size 0.7 0.7)
					(thickness 0.15)
				)
				(justify left bottom)
			)
		)
		(property "Value" "Bel-Fuse_SFP+_2x20_SS-79100-010"
			(at 9.45 1.2 270)
			(unlocked yes)
			(layer "F.Fab")
			(effects
				(font
					(size 0.7 0.7)
					(thickness 0.15)
				)
				(justify left bottom)
			)
		)
		(property "Datasheet" "https://www.belfuse.com/resources/datasheets/stewartconnector/ds-STW-SFP-cages.pdf"
			(at 0 0 270)
			(layer "F.Fab")
			(hide yes)
			(effects
				(font
					(size 1.27 1.27)
					(thickness 0.15)
				)
			)
		)
		(property "Author" "Antmicro"
			(at -19.76 304.86 0)
			(layer "F.Fab")
			(hide yes)
			(effects
				(font
					(size 1 1)
					(thickness 0.15)
				)
			)
		)
		(property "License" "Apache-2.0"
			(at -19.76 304.86 0)
			(layer "F.Fab")
			(hide yes)
			(effects
				(font
					(size 1 1)
					(thickness 0.15)
				)
			)
		)
		(property "MPN" "SS-79100-010"
			(at -19.76 304.86 0)
			(layer "F.Fab")
			(hide yes)
			(effects
				(font
					(size 1 1)
					(thickness 0.15)
				)
			)
		)
		(property "Manufacturer" "Bel Fuse"
			(at -19.76 304.86 0)
			(layer "F.Fab")
			(hide yes)
			(effects
				(font
					(size 1 1)
					(thickness 0.15)
				)
			)
		)
		(sheetname "2xSFP+")
		(sheetfile "2xSFP+.kicad_sch")
		(attr through_hole)
		(fp_line
			(start -7.5 43.5)
			(end -7.5 46.5)
			(stroke
				(width 0.1)
				(type default)
			)
			(layer "F.SilkS")
		)
		(fp_line
			(start 7.5 43.5)
			(end 7.5 46.5)
			(stroke
				(width 0.1)
				(type default)
			)
			(layer "F.SilkS")
		)
		(fp_line
			(start -7.5 35.5)
			(end -7.5 40.5)
			(stroke
				(width 0.1)
				(type default)
			)
			(layer "F.SilkS")
		)
		(fp_line
			(start 7.5 35.5)
			(end 7.5 40.5)
			(stroke
				(width 0.1)
				(type default)
			)
			(layer "F.SilkS")
		)
		(fp_line
			(start -7.5 27.5)
			(end -7.5 32.5)
			(stroke
				(width 0.1)
				(type default)
			)
			(layer "F.SilkS")
		)
		(fp_line
			(start 7.5 27.5)
			(end 7.5 32.5)
			(stroke
				(width 0.1)
				(type default)
			)
			(layer "F.SilkS")
		)
		(fp_line
			(start -7.5 19.5)
			(end -7.5 24.5)
			(stroke
				(width 0.1)
				(type default)
			)
			(layer "F.SilkS")
		)
		(fp_line
			(start 7.5 19.5)
			(end 7.5 24.5)
			(stroke
				(width 0.1)
				(type default)
			)
			(layer "F.SilkS")
		)
		(fp_line
			(start -7.5 11.5)
			(end -7.5 16.5)
			(stroke
				(width 0.1)
				(type default)
			)
			(layer "F.SilkS")
		)
		(fp_line
			(start 7.5 11.5)
			(end 7.5 16.5)
			(stroke
				(width 0.1)
				(type default)
			)
			(layer "F.SilkS")
		)
		(fp_line
			(start -7.5 8.5)
			(end -7.5 -9.75)
			(stroke
				(width 0.1)
				(type default)
			)
			(layer "F.SilkS")
		)
		(fp_line
			(start -7.5 -9.75)
			(end -5.5 -9.75)
			(stroke
				(width 0.1)
				(type default)
			)
			(layer "F.SilkS")
		)
		(fp_line
			(start 5.5 -9.75)
			(end 7.5 -9.75)
			(stroke
				(width 0.1)
				(type default)
			)
			(layer "F.SilkS")
		)
		(fp_line
			(start 7.5 -9.75)
			(end 7.5 8.5)
			(stroke
				(width 0.1)
				(type default)
			)
			(layer "F.SilkS")
		)
		(fp_rect
			(start -9.03 -11.28)
			(end 9.03 54.6)
			(stroke
				(width 0.05)
				(type solid)
			)
			(fill no)
			(layer "F.CrtYd")
		)
		(fp_line
			(start -8.875 50.1)
			(end 9.125 50.1)
			(stroke
				(width 0.15)
				(type solid)
			)
			(layer "F.Fab")
		)
		(fp_line
			(start -8.875 46.6)
			(end 9.125 46.6)
			(stroke
				(width 0.15)
				(type solid)
			)
			(layer "F.Fab")
		)
		(fp_line
			(start 0 25)
			(end 0 30)
			(stroke
				(width 0.15)
				(type solid)
			)
			(layer "F.Fab")
		)
		(fp_line
			(start -6.83 5.6)
			(end -6.83 5.33)
			(stroke
				(width 0.15)
				(type solid)
			)
			(layer "F.Fab")
		)
		(fp_line
			(start -4.85 5.6)
			(end -6.83 5.6)
			(stroke
				(width 0.15)
				(type solid)
			)
			(layer "F.Fab")
		)
		(fp_line
			(start 4.85 5.6)
			(end 6.83 5.6)
			(stroke
				(width 0.15)
				(type solid)
			)
			(layer "F.Fab")
		)
		(fp_line
			(start 6.83 5.6)
			(end 6.83 5.33)
			(stroke
				(width 0.15)
				(type solid)
			)
			(layer "F.Fab")
		)
		(fp_line
			(start -4.85 2)
			(end -4.85 5.6)
			(stroke
				(width 0.15)
				(type solid)
			)
			(layer "F.Fab")
		)
		(fp_line
			(start -4.85 2)
			(end -5.35 1.5)
			(stroke
				(width 0.15)
				(type solid)
			)
			(layer "F.Fab")
		)
		(fp_line
			(start 4.85 2)
			(end 4.85 5.6)
			(stroke
				(width 0.15)
				(type solid)
			)
			(layer "F.Fab")
		)
		(fp_line
			(start 4.85 2)
			(end 5.35 1.5)
			(stroke
				(width 0.15)
				(type solid)
			)
			(layer "F.Fab")
		)
		(fp_line
			(start -6.83 1.5)
			(end -6.83 2.53)
			(stroke
				(width 0.15)
				(type solid)
			)
			(layer "F.Fab")
		)
		(fp_line
			(start -5.35 1.5)
			(end -6.83 1.5)
			(stroke
				(width 0.15)
				(type solid)
			)
			(layer "F.Fab")
		)
		(fp_line
			(start 5.35 1.5)
			(end 6.83 1.5)
			(stroke
				(width 0.15)
				(type solid)
			)
			(layer "F.Fab")
		)
		(fp_line
			(start 6.83 1.5)
			(end 6.83 2.53)
			(stroke
				(width 0.15)
				(type solid)
			)
			(layer "F.Fab")
		)
		(fp_line
			(start -6.83 -1.5)
			(end -6.83 -2.53)
			(stroke
				(width 0.15)
				(type solid)
			)
			(layer "F.Fab")
		)
		(fp_line
			(start -5.35 -1.5)
			(end -6.83 -1.5)
			(stroke
				(width 0.15)
				(type solid)
			)
			(layer "F.Fab")
		)
		(fp_line
			(start 5.35 -1.5)
			(end 6.83 -1.5)
			(stroke
				(width 0.15)
				(type solid)
			)
			(layer "F.Fab")
		)
		(fp_line
			(start 6.83 -1.5)
			(end 6.83 -2.53)
			(stroke
				(width 0.15)
				(type solid)
			)
			(layer "F.Fab")
		)
		(fp_line
			(start -4.85 -2)
			(end -5.35 -1.5)
			(stroke
				(width 0.15)
				(type solid)
			)
			(layer "F.Fab")
		)
		(fp_line
			(start 4.85 -2)
			(end 5.35 -1.5)
			(stroke
				(width 0.15)
				(type solid)
			)
			(layer "F.Fab")
		)
		(fp_line
			(start -4.85 -5.5)
			(end -4.85 -2)
			(stroke
				(width 0.15)
				(type solid)
			)
			(layer "F.Fab")
		)
		(fp_line
			(start -4.85 -5.5)
			(end -5.35 -6)
			(stroke
				(width 0.15)
				(type solid)
			)
			(layer "F.Fab")
		)
		(fp_line
			(start 4.85 -5.5)
			(end 4.85 -2)
			(stroke
				(width 0.15)
				(type solid)
			)
			(layer "F.Fab")
		)
		(fp_line
			(start 4.85 -5.5)
			(end 5.35 -6)
			(stroke
				(width 0.15)
				(type solid)
			)
			(layer "F.Fab")
		)
		(fp_line
			(start -6.83 -6)
			(end -6.83 -5.33)
			(stroke
				(width 0.15)
				(type solid)
			)
			(layer "F.Fab")
		)
		(fp_line
			(start -5.35 -6)
			(end -6.83 -6)
			(stroke
				(width 0.15)
				(type solid)
			)
			(layer "F.Fab")
		)
		(fp_line
			(start 5.35 -6)
			(end 6.83 -6)
			(stroke
				(width 0.15)
				(type solid)
			)
			(layer "F.Fab")
		)
		(fp_line
			(start 6.83 -6)
			(end 6.83 -5.33)
			(stroke
				(width 0.15)
				(type solid)
			)
			(layer "F.Fab")
		)
		(fp_rect
			(start -5.43 2.53)
			(end -6.83 5.33)
			(stroke
				(width 0.15)
				(type solid)
			)
			(fill no)
			(layer "F.Fab")
		)
		(fp_rect
			(start 5.43 2.53)
			(end 6.83 5.33)
			(stroke
				(width 0.15)
				(type solid)
			)
			(fill no)
			(layer "F.Fab")
		)
		(fp_rect
			(start -5.43 -5.33)
			(end -6.83 -2.53)
			(stroke
				(width 0.15)
				(type solid)
			)
			(fill no)
			(layer "F.Fab")
		)
		(fp_rect
			(start 5.43 -5.33)
			(end 6.83 -2.53)
			(stroke
				(width 0.15)
				(type solid)
			)
			(fill no)
			(layer "F.Fab")
		)
		(fp_text user "PCB EDGE"
			(at 5.125 46.35 270)
			(unlocked yes)
			(layer "F.Fab")
			(effects
				(font
					(size 0.7 0.7)
					(thickness 0.15)
				)
				(justify left bottom)
			)
		)
		(fp_text user "LED4"
			(at 6.5 4.75 0)
			(unlocked yes)
			(layer "F.Fab")
			(effects
				(font
					(size 0.5 0.5)
					(thickness 0.125)
				)
				(justify left bottom)
			)
		)
		(fp_text user "LED2"
			(at -5.75 -3.25 0)
			(unlocked yes)
			(layer "F.Fab")
			(effects
				(font
					(size 0.5 0.5)
					(thickness 0.125)
				)
				(justify left bottom)
			)
		)
		(fp_text user "LED1"
			(at -5.75 4.75 0)
			(unlocked yes)
			(layer "F.Fab")
			(effects
				(font
					(size 0.5 0.5)
					(thickness 0.125)
				)
				(justify left bottom)
			)
		)
		(fp_text user "PANEL EDGE"
			(at 5.125 49.85 270)
			(unlocked yes)
			(layer "F.Fab")
			(effects
				(font
					(size 0.7 0.7)
					(thickness 0.15)
				)
				(justify left bottom)
			)
		)
		(fp_text user "LED3"
			(at 6.5 -3.25 0)
			(unlocked yes)
			(layer "F.Fab")
			(effects
				(font
					(size 0.5 0.5)
					(thickness 0.125)
				)
				(justify left bottom)
			)
		)
		(pad "" np_thru_hole circle
			(at -5.5 0 270)
			(size 1.85 1.85)
			(drill 1.85)
			(layers "F&B.Cu" "*.Mask")
		)
		(pad "" np_thru_hole circle
			(at 5.5 -7.5 270)
			(size 1.85 1.85)
			(drill 1.85)
			(layers "F&B.Cu" "*.Mask")
		)
		(pad "L1" thru_hole circle
			(at 3.4 0.74 270)
			(size 0.86 0.86)
			(drill 0.46)
			(layers "*.Cu" "*.Mask")
			(remove_unused_layers no)
			(net 1 "GND")
			(pinfunction "V_{EE}(T)")
			(pintype "passive")
			(teardrops
				(best_length_ratio 0.4)
				(max_length 1)
				(best_width_ratio 0.9)
				(max_width 2)
				(curved_edges yes)
				(filter_ratio 0.9)
				(enabled yes)
				(allow_two_segments yes)
				(prefer_zone_connections yes)
			)
		)
		(pad "L2" thru_hole circle
			(at 2.6 -0.65 270)
			(size 0.86 0.86)
			(drill 0.46)
			(layers "*.Cu" "*.Mask")
			(remove_unused_layers no)
			(net 876 "Net-(J2B-TX_{FAULT})")
			(pinfunction "TX_{FAULT}")
			(pintype "open_collector")
			(teardrops
				(best_length_ratio 0.4)
				(max_length 1)
				(best_width_ratio 0.9)
				(max_width 2)
				(curved_edges yes)
				(filter_ratio 0.9)
				(enabled yes)
				(allow_two_segments yes)
				(prefer_zone_connections yes)
			)
		)
		(pad "L3" thru_hole circle
			(at 1.8 0.74 270)
			(size 0.86 0.86)
			(drill 0.46)
			(layers "*.Cu" "*.Mask")
			(remove_unused_layers no)
			(net 893 "Net-(J2B-TX_{DISABLE})")
			(pinfunction "TX_{DISABLE}")
			(pintype "input")
			(teardrops
				(best_length_ratio 0.4)
				(max_length 1)
				(best_width_ratio 0.9)
				(max_width 2)
				(curved_edges yes)
				(filter_ratio 0.9)
				(enabled yes)
				(allow_two_segments yes)
				(prefer_zone_connections yes)
			)
		)
		(pad "L4" thru_hole circle
			(at 1 -0.65 270)
			(size 0.86 0.86)
			(drill 0.46)
			(layers "*.Cu" "*.Mask")
			(remove_unused_layers no)
			(net 874 "/2xSFP+/SDA1")
			(pinfunction "SDA")
			(pintype "bidirectional")
			(teardrops
				(best_length_ratio 0.4)
				(max_length 1)
				(best_width_ratio 0.9)
				(max_width 2)
				(curved_edges yes)
				(filter_ratio 0.9)
				(enabled yes)
				(allow_two_segments yes)
				(prefer_zone_connections yes)
			)
		)
		(pad "L5" thru_hole circle
			(at 0.2 0.74 270)
			(size 0.86 0.86)
			(drill 0.46)
			(layers "*.Cu" "*.Mask")
			(remove_unused_layers no)
			(net 875 "/2xSFP+/SCL1")
			(pinfunction "SCL")
			(pintype "bidirectional")
			(teardrops
				(best_length_ratio 0.4)
				(max_length 1)
				(best_width_ratio 0.9)
				(max_width 2)
				(curved_edges yes)
				(filter_ratio 0.9)
				(enabled yes)
				(allow_two_segments yes)
				(prefer_zone_connections yes)
			)
		)
		(pad "L6" thru_hole circle
			(at -0.6 -0.65 270)
			(size 0.86 0.86)
			(drill 0.46)
			(layers "*.Cu" "*.Mask")
			(remove_unused_layers no)
			(net 894 "Net-(J2B-MOD_{ABS})")
			(pinfunction "MOD_{ABS}")
			(pintype "passive")
			(teardrops
				(best_length_ratio 0.4)
				(max_length 1)
				(best_width_ratio 0.9)
				(max_width 2)
				(curved_edges yes)
				(filter_ratio 0.9)
				(enabled yes)
				(allow_two_segments yes)
				(prefer_zone_connections yes)
			)
		)
		(pad "L7" thru_hole circle
			(at -1.4 0.74 270)
			(size 0.86 0.86)
			(drill 0.46)
			(layers "*.Cu" "*.Mask")
			(remove_unused_layers no)
			(net 895 "Net-(J2B-RS0)")
			(pinfunction "RS0")
			(pintype "input")
			(teardrops
				(best_length_ratio 0.4)
				(max_length 1)
				(best_width_ratio 0.9)
				(max_width 2)
				(curved_edges yes)
				(filter_ratio 0.9)
				(enabled yes)
				(allow_two_segments yes)
				(prefer_zone_connections yes)
			)
		)
		(pad "L8" thru_hole circle
			(at -2.2 -0.65 270)
			(size 0.86 0.86)
			(drill 0.46)
			(layers "*.Cu" "*.Mask")
			(remove_unused_layers no)
			(net 896 "Net-(J2B-RX_{LOS})")
			(pinfunction "RX_{LOS}")
			(pintype "open_collector")
			(teardrops
				(best_length_ratio 0.4)
				(max_length 1)
				(best_width_ratio 0.9)
				(max_width 2)
				(curved_edges yes)
				(filter_ratio 0.9)
				(enabled yes)
				(allow_two_segments yes)
				(prefer_zone_connections yes)
			)
		)
		(pad "L9" thru_hole circle
			(at -3 0.74 270)
			(size 0.86 0.86)
			(drill 0.46)
			(layers "*.Cu" "*.Mask")
			(remove_unused_layers no)
			(net 897 "Net-(J2B-RS1)")
			(pinfunction "RS1")
			(pintype "input")
			(teardrops
				(best_length_ratio 0.4)
				(max_length 1)
				(best_width_ratio 0.9)
				(max_width 2)
				(curved_edges yes)
				(filter_ratio 0.9)
				(enabled yes)
				(allow_two_segments yes)
				(prefer_zone_connections yes)
			)
		)
		(pad "L10" thru_hole circle
			(at -3.8 -0.65 270)
			(size 0.86 0.86)
			(drill 0.46)
			(layers "*.Cu" "*.Mask")
			(remove_unused_layers no)
			(net 1 "GND")
			(pinfunction "V_{EE}(R)")
			(pintype "passive")
			(teardrops
				(best_length_ratio 0.4)
				(max_length 1)
				(best_width_ratio 0.9)
				(max_width 2)
				(curved_edges yes)
				(filter_ratio 0.9)
				(enabled yes)
				(allow_two_segments yes)
				(prefer_zone_connections yes)
			)
		)
		(pad "L11" thru_hole circle
			(at -3.4 2.29 270)
			(size 0.86 0.86)
			(drill 0.46)
			(layers "*.Cu" "*.Mask")
			(remove_unused_layers no)
			(net 1 "GND")
			(pinfunction "V_{EE}(R)")
			(pintype "passive")
			(teardrops
				(best_length_ratio 0.4)
				(max_length 1)
				(best_width_ratio 0.9)
				(max_width 2)
				(curved_edges yes)
				(filter_ratio 0.9)
				(enabled yes)
				(allow_two_segments yes)
				(prefer_zone_connections yes)
			)
		)
		(pad "L12" thru_hole circle
			(at -2.6 3.67 270)
			(size 0.86 0.86)
			(drill 0.46)
			(layers "*.Cu" "*.Mask")
			(remove_unused_layers no)
			(net 877 "/2xSFP+/SFI1.RX-")
			(pinfunction "RD-")
			(pintype "output")
			(teardrops
				(best_length_ratio 0.4)
				(max_length 1)
				(best_width_ratio 0.9)
				(max_width 2)
				(curved_edges yes)
				(filter_ratio 0.9)
				(enabled yes)
				(allow_two_segments yes)
				(prefer_zone_connections yes)
			)
		)
		(pad "L13" thru_hole circle
			(at -1.8 2.29 270)
			(size 0.86 0.86)
			(drill 0.46)
			(layers "*.Cu" "*.Mask")
			(remove_unused_layers no)
			(net 878 "/2xSFP+/SFI1.RX+")
			(pinfunction "RD+")
			(pintype "output")
			(teardrops
				(best_length_ratio 0.4)
				(max_length 1)
				(best_width_ratio 0.9)
				(max_width 2)
				(curved_edges yes)
				(filter_ratio 0.9)
				(enabled yes)
				(allow_two_segments yes)
				(prefer_zone_connections yes)
			)
		)
		(pad "L14" thru_hole circle
			(at -1 3.67 270)
			(size 0.86 0.86)
			(drill 0.46)
			(layers "*.Cu" "*.Mask")
			(remove_unused_layers no)
			(net 1 "GND")
			(pinfunction "V_{EE}(R)")
			(pintype "passive")
			(teardrops
				(best_length_ratio 0.4)
				(max_length 1)
				(best_width_ratio 0.9)
				(max_width 2)
				(curved_edges yes)
				(filter_ratio 0.9)
				(enabled yes)
				(allow_two_segments yes)
				(prefer_zone_connections yes)
			)
		)
		(pad "L15" thru_hole circle
			(at -0.2 2.29 270)
			(size 0.86 0.86)
			(drill 0.46)
			(layers "*.Cu" "*.Mask")
			(remove_unused_layers no)
			(net 2 "+3V3")
			(pinfunction "V_{CC}(R)")
			(pintype "power_in")
			(teardrops
				(best_length_ratio 0.4)
				(max_length 1)
				(best_width_ratio 0.9)
				(max_width 2)
				(curved_edges yes)
				(filter_ratio 0.9)
				(enabled yes)
				(allow_two_segments yes)
				(prefer_zone_connections yes)
			)
		)
		(pad "L16" thru_hole circle
			(at 0.6 3.67 270)
			(size 0.86 0.86)
			(drill 0.46)
			(layers "*.Cu" "*.Mask")
			(remove_unused_layers no)
			(net 2 "+3V3")
			(pinfunction "V_{CC}(T)")
			(pintype "power_in")
			(teardrops
				(best_length_ratio 0.4)
				(max_length 1)
				(best_width_ratio 0.9)
				(max_width 2)
				(curved_edges yes)
				(filter_ratio 0.9)
				(enabled yes)
				(allow_two_segments yes)
				(prefer_zone_connections yes)
			)
		)
		(pad "L17" thru_hole circle
			(at 1.4 2.29 270)
			(size 0.86 0.86)
			(drill 0.46)
			(layers "*.Cu" "*.Mask")
			(remove_unused_layers no)
			(net 1 "GND")
			(pinfunction "V_{EE}(T)")
			(pintype "passive")
			(teardrops
				(best_length_ratio 0.4)
				(max_length 1)
				(best_width_ratio 0.9)
				(max_width 2)
				(curved_edges yes)
				(filter_ratio 0.9)
				(enabled yes)
				(allow_two_segments yes)
				(prefer_zone_connections yes)
			)
		)
		(pad "L18" thru_hole circle
			(at 2.2 3.67 270)
			(size 0.86 0.86)
			(drill 0.46)
			(layers "*.Cu" "*.Mask")
			(remove_unused_layers no)
			(net 879 "/2xSFP+/SFI1.TX+")
			(pinfunction "TD+")
			(pintype "input")
			(teardrops
				(best_length_ratio 0.4)
				(max_length 1)
				(best_width_ratio 0.9)
				(max_width 2)
				(curved_edges yes)
				(filter_ratio 0.9)
				(enabled yes)
				(allow_two_segments yes)
				(prefer_zone_connections yes)
			)
		)
		(pad "L19" thru_hole circle
			(at 3 2.29 270)
			(size 0.86 0.86)
			(drill 0.46)
			(layers "*.Cu" "*.Mask")
			(remove_unused_layers no)
			(net 880 "/2xSFP+/SFI1.TX-")
			(pinfunction "TD-")
			(pintype "input")
			(teardrops
				(best_length_ratio 0.4)
				(max_length 1)
				(best_width_ratio 0.9)
				(max_width 2)
				(curved_edges yes)
				(filter_ratio 0.9)
				(enabled yes)
				(allow_two_segments yes)
				(prefer_zone_connections yes)
			)
		)
		(pad "L20" thru_hole circle
			(at 3.8 3.67 270)
			(size 0.86 0.86)
			(drill 0.46)
			(layers "*.Cu" "*.Mask")
			(remove_unused_layers no)
			(net 1 "GND")
			(pinfunction "V_{EE}(T)")
			(pintype "passive")
			(teardrops
				(best_length_ratio 0.4)
				(max_length 1)
				(best_width_ratio 0.9)
				(max_width 2)
				(curved_edges yes)
				(filter_ratio 0.9)
				(enabled yes)
				(allow_two_segments yes)
				(prefer_zone_connections yes)
			)
		)
		(pad "SH" thru_hole circle
			(at -7.125 10.1 270)
			(size 1.5 1.5)
			(drill 1.05)
			(layers "*.Cu" "*.Mask")
			(remove_unused_layers no)
			(net 53 "/2xSFP+/SH")
			(pinfunction "SH")
			(pintype "passive")
			(teardrops
				(best_length_ratio 0.4)
				(max_length 1)
				(best_width_ratio 0.9)
				(max_width 2)
				(curved_edges yes)
				(filter_ratio 0.9)
				(enabled yes)
				(allow_two_segments yes)
				(prefer_zone_connections yes)
			)
		)
		(pad "SH" thru_hole circle
			(at -7.125 18.1 270)
			(size 1.5 1.5)
			(drill 1.05)
			(layers "*.Cu" "*.Mask")
			(remove_unused_layers no)
			(net 53 "/2xSFP+/SH")
			(pinfunction "SH")
			(pintype "passive")
			(teardrops
				(best_length_ratio 0.4)
				(max_length 1)
				(best_width_ratio 0.9)
				(max_width 2)
				(curved_edges yes)
				(filter_ratio 0.9)
				(enabled yes)
				(allow_two_segments yes)
				(prefer_zone_connections yes)
			)
		)
		(pad "SH" thru_hole circle
			(at -7.125 26.1 270)
			(size 1.5 1.5)
			(drill 1.05)
			(layers "*.Cu" "*.Mask")
			(remove_unused_layers no)
			(net 53 "/2xSFP+/SH")
			(pinfunction "SH")
			(pintype "passive")
			(teardrops
				(best_length_ratio 0.4)
				(max_length 1)
				(best_width_ratio 0.9)
				(max_width 2)
				(curved_edges yes)
				(filter_ratio 0.9)
				(enabled yes)
				(allow_two_segments yes)
				(prefer_zone_connections yes)
			)
		)
		(pad "SH" thru_hole circle
			(at -7.125 34.1 270)
			(size 1.5 1.5)
			(drill 1.05)
			(layers "*.Cu" "*.Mask")
			(remove_unused_layers no)
			(net 53 "/2xSFP+/SH")
			(pinfunction "SH")
			(pintype "passive")
			(teardrops
				(best_length_ratio 0.4)
				(max_length 1)
				(best_width_ratio 0.9)
				(max_width 2)
				(curved_edges yes)
				(filter_ratio 0.9)
				(enabled yes)
				(allow_two_segments yes)
				(prefer_zone_connections yes)
			)
		)
		(pad "SH" thru_hole circle
			(at -7.125 42.1 270)
			(size 1.5 1.5)
			(drill 1.05)
			(layers "*.Cu" "*.Mask")
			(remove_unused_layers no)
			(net 53 "/2xSFP+/SH")
			(pinfunction "SH")
			(pintype "passive")
			(teardrops
				(best_length_ratio 0.4)
				(max_length 1)
				(best_width_ratio 0.9)
				(max_width 2)
				(curved_edges yes)
				(filter_ratio 0.9)
				(enabled yes)
				(allow_two_segments yes)
				(prefer_zone_connections yes)
			)
		)
		(pad "SH" thru_hole circle
			(at -4 -9.5 270)
			(size 1.5 1.5)
			(drill 1.05)
			(layers "*.Cu" "*.Mask")
			(remove_unused_layers no)
			(net 53 "/2xSFP+/SH")
			(pinfunction "SH")
			(pintype "passive")
			(teardrops
				(best_length_ratio 0.4)
				(max_length 1)
				(best_width_ratio 0.9)
				(max_width 2)
				(curved_edges yes)
				(filter_ratio 0.9)
				(enabled yes)
				(allow_two_segments yes)
				(prefer_zone_connections yes)
			)
		)
		(pad "SH" thru_hole circle
			(at 0 -9.525 270)
			(size 1.5 1.5)
			(drill 1.05)
			(layers "*.Cu" "*.Mask")
			(remove_unused_layers no)
			(net 53 "/2xSFP+/SH")
			(pinfunction "SH")
			(pintype "passive")
			(teardrops
				(best_length_ratio 0.4)
				(max_length 1)
				(best_width_ratio 0.9)
				(max_width 2)
				(curved_edges yes)
				(filter_ratio 0.9)
				(enabled yes)
				(allow_two_segments yes)
				(prefer_zone_connections yes)
			)
		)
		(pad "SH" thru_hole circle
			(at 4 -9.5 270)
			(size 1.5 1.5)
			(drill 1.05)
			(layers "*.Cu" "*.Mask")
			(remove_unused_layers no)
			(net 53 "/2xSFP+/SH")
			(pinfunction "SH")
			(pintype "passive")
			(teardrops
				(best_length_ratio 0.4)
				(max_length 1)
				(best_width_ratio 0.9)
				(max_width 2)
				(curved_edges yes)
				(filter_ratio 0.9)
				(enabled yes)
				(allow_two_segments yes)
				(prefer_zone_connections yes)
			)
		)
		(pad "SH" thru_hole circle
			(at 7.125 10.1 270)
			(size 1.5 1.5)
			(drill 1.05)
			(layers "*.Cu" "*.Mask")
			(remove_unused_layers no)
			(net 53 "/2xSFP+/SH")
			(pinfunction "SH")
			(pintype "passive")
			(teardrops
				(best_length_ratio 0.4)
				(max_length 1)
				(best_width_ratio 0.9)
				(max_width 2)
				(curved_edges yes)
				(filter_ratio 0.9)
				(enabled yes)
				(allow_two_segments yes)
				(prefer_zone_connections yes)
			)
		)
		(pad "SH" thru_hole circle
			(at 7.125 18.1 270)
			(size 1.5 1.5)
			(drill 1.05)
			(layers "*.Cu" "*.Mask")
			(remove_unused_layers no)
			(net 53 "/2xSFP+/SH")
			(pinfunction "SH")
			(pintype "passive")
			(teardrops
				(best_length_ratio 0.4)
				(max_length 1)
				(best_width_ratio 0.9)
				(max_width 2)
				(curved_edges yes)
				(filter_ratio 0.9)
				(enabled yes)
				(allow_two_segments yes)
				(prefer_zone_connections yes)
			)
		)
		(pad "SH" thru_hole circle
			(at 7.125 26.1 270)
			(size 1.5 1.5)
			(drill 1.05)
			(layers "*.Cu" "*.Mask")
			(remove_unused_layers no)
			(net 53 "/2xSFP+/SH")
			(pinfunction "SH")
			(pintype "passive")
			(teardrops
				(best_length_ratio 0.4)
				(max_length 1)
				(best_width_ratio 0.9)
				(max_width 2)
				(curved_edges yes)
				(filter_ratio 0.9)
				(enabled yes)
				(allow_two_segments yes)
				(prefer_zone_connections yes)
			)
		)
		(pad "SH" thru_hole circle
			(at 7.125 34.1 270)
			(size 1.5 1.5)
			(drill 1.05)
			(layers "*.Cu" "*.Mask")
			(remove_unused_layers no)
			(net 53 "/2xSFP+/SH")
			(pinfunction "SH")
			(pintype "passive")
			(teardrops
				(best_length_ratio 0.4)
				(max_length 1)
				(best_width_ratio 0.9)
				(max_width 2)
				(curved_edges yes)
				(filter_ratio 0.9)
				(enabled yes)
				(allow_two_segments yes)
				(prefer_zone_connections yes)
			)
		)
		(pad "SH" thru_hole circle
			(at 7.125 42.1 270)
			(size 1.5 1.5)
			(drill 1.05)
			(layers "*.Cu" "*.Mask")
			(remove_unused_layers no)
			(net 53 "/2xSFP+/SH")
			(pinfunction "SH")
			(pintype "passive")
			(teardrops
				(best_length_ratio 0.4)
				(max_length 1)
				(best_width_ratio 0.9)
				(max_width 2)
				(curved_edges yes)
				(filter_ratio 0.9)
				(enabled yes)
				(allow_two_segments yes)
				(prefer_zone_connections yes)
			)
		)
		(pad "T1" thru_hole circle
			(at -3.4 -3.58 270)
			(size 0.86 0.86)
			(drill 0.46)
			(layers "*.Cu" "*.Mask")
			(remove_unused_layers no)
			(net 1 "GND")
			(pinfunction "V_{EE}(T)")
			(pintype "passive")
			(teardrops
				(best_length_ratio 0.4)
				(max_length 1)
				(best_width_ratio 0.9)
				(max_width 2)
				(curved_edges yes)
				(filter_ratio 0.9)
				(enabled yes)
				(allow_two_segments yes)
				(prefer_zone_connections yes)
			)
		)
		(pad "T2" thru_hole circle
			(at -2.6 -2.2 270)
			(size 0.86 0.86)
			(drill 0.46)
			(layers "*.Cu" "*.Mask")
			(remove_unused_layers no)
			(net 162 "Net-(J2A-TX_{FAULT})")
			(pinfunction "TX_{FAULT}")
			(pintype "open_collector")
			(teardrops
				(best_length_ratio 0.4)
				(max_length 1)
				(best_width_ratio 0.9)
				(max_width 2)
				(curved_edges yes)
				(filter_ratio 0.9)
				(enabled yes)
				(allow_two_segments yes)
				(prefer_zone_connections yes)
			)
		)
		(pad "T3" thru_hole circle
			(at -1.8 -3.58 270)
			(size 0.86 0.86)
			(drill 0.46)
			(layers "*.Cu" "*.Mask")
			(remove_unused_layers no)
			(net 163 "Net-(J2A-TX_{DISABLE})")
			(pinfunction "TX_{DISABLE}")
			(pintype "input")
			(teardrops
				(best_length_ratio 0.4)
				(max_length 1)
				(best_width_ratio 0.9)
				(max_width 2)
				(curved_edges yes)
				(filter_ratio 0.9)
				(enabled yes)
				(allow_two_segments yes)
				(prefer_zone_connections yes)
			)
		)
		(pad "T4" thru_hole circle
			(at -1 -2.2 270)
			(size 0.86 0.86)
			(drill 0.46)
			(layers "*.Cu" "*.Mask")
			(remove_unused_layers no)
			(net 164 "/2xSFP+/SDA0")
			(pinfunction "SDA")
			(pintype "bidirectional")
			(teardrops
				(best_length_ratio 0.4)
				(max_length 1)
				(best_width_ratio 0.9)
				(max_width 2)
				(curved_edges yes)
				(filter_ratio 0.9)
				(enabled yes)
				(allow_two_segments yes)
				(prefer_zone_connections yes)
			)
		)
		(pad "T5" thru_hole circle
			(at -0.2 -3.58 270)
			(size 0.86 0.86)
			(drill 0.46)
			(layers "*.Cu" "*.Mask")
			(remove_unused_layers no)
			(net 165 "/2xSFP+/SCL0")
			(pinfunction "SCL")
			(pintype "bidirectional")
			(teardrops
				(best_length_ratio 0.4)
				(max_length 1)
				(best_width_ratio 0.9)
				(max_width 2)
				(curved_edges yes)
				(filter_ratio 0.9)
				(enabled yes)
				(allow_two_segments yes)
				(prefer_zone_connections yes)
			)
		)
		(pad "T6" thru_hole circle
			(at 0.6 -2.2 270)
			(size 0.86 0.86)
			(drill 0.46)
			(layers "*.Cu" "*.Mask")
			(remove_unused_layers no)
			(net 166 "Net-(J2A-MOD_{ABS})")
			(pinfunction "MOD_{ABS}")
			(pintype "passive")
			(teardrops
				(best_length_ratio 0.4)
				(max_length 1)
				(best_width_ratio 0.9)
				(max_width 2)
				(curved_edges yes)
				(filter_ratio 0.9)
				(enabled yes)
				(allow_two_segments yes)
				(prefer_zone_connections yes)
			)
		)
		(pad "T7" thru_hole circle
			(at 1.4 -3.58 270)
			(size 0.86 0.86)
			(drill 0.46)
			(layers "*.Cu" "*.Mask")
			(remove_unused_layers no)
			(net 167 "Net-(J2A-RS0)")
			(pinfunction "RS0")
			(pintype "input")
			(teardrops
				(best_length_ratio 0.4)
				(max_length 1)
				(best_width_ratio 0.9)
				(max_width 2)
				(curved_edges yes)
				(filter_ratio 0.9)
				(enabled yes)
				(allow_two_segments yes)
				(prefer_zone_connections yes)
			)
		)
		(pad "T8" thru_hole circle
			(at 2.2 -2.2 270)
			(size 0.86 0.86)
			(drill 0.46)
			(layers "*.Cu" "*.Mask")
			(remove_unused_layers no)
			(net 168 "Net-(J2A-RX_{LOS})")
			(pinfunction "RX_{LOS}")
			(pintype "open_collector")
			(teardrops
				(best_length_ratio 0.4)
				(max_length 1)
				(best_width_ratio 0.9)
				(max_width 2)
				(curved_edges yes)
				(filter_ratio 0.9)
				(enabled yes)
				(allow_two_segments yes)
				(prefer_zone_connections yes)
			)
		)
		(pad "T9" thru_hole circle
			(at 3 -3.58 270)
			(size 0.86 0.86)
			(drill 0.46)
			(layers "*.Cu" "*.Mask")
			(remove_unused_layers no)
			(net 169 "Net-(J2A-RS1)")
			(pinfunction "RS1")
			(pintype "input")
			(teardrops
				(best_length_ratio 0.4)
				(max_length 1)
				(best_width_ratio 0.9)
				(max_width 2)
				(curved_edges yes)
				(filter_ratio 0.9)
				(enabled yes)
				(allow_two_segments yes)
				(prefer_zone_connections yes)
			)
		)
		(pad "T10" thru_hole circle
			(at 3.8 -2.2)
			(size 0.86 0.86)
			(drill 0.46)
			(layers "*.Cu" "*.Mask")
			(remove_unused_layers no)
			(net 1 "GND")
			(pinfunction "V_{EE}(R)")
			(pintype "passive")
			(teardrops
				(best_length_ratio 0.4)
				(max_length 1)
				(best_width_ratio 0.9)
				(max_width 2)
				(curved_edges yes)
				(filter_ratio 0.9)
				(enabled yes)
				(allow_two_segments yes)
				(prefer_zone_connections yes)
			)
		)
		(pad "T11" thru_hole circle
			(at 3.4 -5.13 270)
			(size 0.86 0.86)
			(drill 0.46)
			(layers "*.Cu" "*.Mask")
			(remove_unused_layers no)
			(net 1 "GND")
			(pinfunction "V_{EE}(R)")
			(pintype "passive")
			(teardrops
				(best_length_ratio 0.4)
				(max_length 1)
				(best_width_ratio 0.9)
				(max_width 2)
				(curved_edges yes)
				(filter_ratio 0.9)
				(enabled yes)
				(allow_two_segments yes)
				(prefer_zone_connections yes)
			)
		)
		(pad "T12" thru_hole circle
			(at 2.6 -6.52 270)
			(size 0.86 0.86)
			(drill 0.46)
			(layers "*.Cu" "*.Mask")
			(remove_unused_layers no)
			(net 170 "/2xSFP+/SFI0.RX-")
			(pinfunction "RD-")
			(pintype "output")
			(teardrops
				(best_length_ratio 0.4)
				(max_length 1)
				(best_width_ratio 0.9)
				(max_width 2)
				(curved_edges yes)
				(filter_ratio 0.9)
				(enabled yes)
				(allow_two_segments yes)
				(prefer_zone_connections yes)
			)
		)
		(pad "T13" thru_hole circle
			(at 1.8 -5.13 270)
			(size 0.86 0.86)
			(drill 0.46)
			(layers "*.Cu" "*.Mask")
			(remove_unused_layers no)
			(net 171 "/2xSFP+/SFI0.RX+")
			(pinfunction "RD+")
			(pintype "output")
			(teardrops
				(best_length_ratio 0.4)
				(max_length 1)
				(best_width_ratio 0.9)
				(max_width 2)
				(curved_edges yes)
				(filter_ratio 0.9)
				(enabled yes)
				(allow_two_segments yes)
				(prefer_zone_connections yes)
			)
		)
		(pad "T14" thru_hole circle
			(at 1 -6.52 270)
			(size 0.86 0.86)
			(drill 0.46)
			(layers "*.Cu" "*.Mask")
			(remove_unused_layers no)
			(net 1 "GND")
			(pinfunction "V_{EE}(R)")
			(pintype "passive")
			(teardrops
				(best_length_ratio 0.4)
				(max_length 1)
				(best_width_ratio 0.9)
				(max_width 2)
				(curved_edges yes)
				(filter_ratio 0.9)
				(enabled yes)
				(allow_two_segments yes)
				(prefer_zone_connections yes)
			)
		)
		(pad "T15" thru_hole circle
			(at 0.2 -5.13 270)
			(size 0.86 0.86)
			(drill 0.46)
			(layers "*.Cu" "*.Mask")
			(remove_unused_layers no)
			(net 2 "+3V3")
			(pinfunction "V_{CC}(R)")
			(pintype "power_in")
			(teardrops
				(best_length_ratio 0.4)
				(max_length 1)
				(best_width_ratio 0.9)
				(max_width 2)
				(curved_edges yes)
				(filter_ratio 0.9)
				(enabled yes)
				(allow_two_segments yes)
				(prefer_zone_connections yes)
			)
		)
		(pad "T16" thru_hole circle
			(at -0.6 -6.52 270)
			(size 0.86 0.86)
			(drill 0.46)
			(layers "*.Cu" "*.Mask")
			(remove_unused_layers no)
			(net 2 "+3V3")
			(pinfunction "V_{CC}(T)")
			(pintype "power_in")
			(teardrops
				(best_length_ratio 0.4)
				(max_length 1)
				(best_width_ratio 0.9)
				(max_width 2)
				(curved_edges yes)
				(filter_ratio 0.9)
				(enabled yes)
				(allow_two_segments yes)
				(prefer_zone_connections yes)
			)
		)
		(pad "T17" thru_hole circle
			(at -1.4 -5.13 270)
			(size 0.86 0.86)
			(drill 0.46)
			(layers "*.Cu" "*.Mask")
			(remove_unused_layers no)
			(net 1 "GND")
			(pinfunction "V_{EE}(T)")
			(pintype "passive")
			(teardrops
				(best_length_ratio 0.4)
				(max_length 1)
				(best_width_ratio 0.9)
				(max_width 2)
				(curved_edges yes)
				(filter_ratio 0.9)
				(enabled yes)
				(allow_two_segments yes)
				(prefer_zone_connections yes)
			)
		)
		(pad "T18" thru_hole circle
			(at -2.2 -6.52 270)
			(size 0.86 0.86)
			(drill 0.46)
			(layers "*.Cu" "*.Mask")
			(remove_unused_layers no)
			(net 172 "/2xSFP+/SFI0.TX+")
			(pinfunction "TD+")
			(pintype "input")
			(teardrops
				(best_length_ratio 0.4)
				(max_length 1)
				(best_width_ratio 0.9)
				(max_width 2)
				(curved_edges yes)
				(filter_ratio 0.9)
				(enabled yes)
				(allow_two_segments yes)
				(prefer_zone_connections yes)
			)
		)
		(pad "T19" thru_hole circle
			(at -3 -5.13 270)
			(size 0.86 0.86)
			(drill 0.46)
			(layers "*.Cu" "*.Mask")
			(remove_unused_layers no)
			(net 173 "/2xSFP+/SFI0.TX-")
			(pinfunction "TD-")
			(pintype "input")
			(teardrops
				(best_length_ratio 0.4)
				(max_length 1)
				(best_width_ratio 0.9)
				(max_width 2)
				(curved_edges yes)
				(filter_ratio 0.9)
				(enabled yes)
				(allow_two_segments yes)
				(prefer_zone_connections yes)
			)
		)
		(pad "T20" thru_hole circle
			(at -3.8 -6.52 270)
			(size 0.86 0.86)
			(drill 0.46)
			(layers "*.Cu" "*.Mask")
			(remove_unused_layers no)
			(net 1 "GND")
			(pinfunction "V_{EE}(T)")
			(pintype "passive")
			(teardrops
				(best_length_ratio 0.4)
				(max_length 1)
				(best_width_ratio 0.9)
				(max_width 2)
				(curved_edges yes)
				(filter_ratio 0.9)
				(enabled yes)
				(allow_two_segments yes)
				(prefer_zone_connections yes)
			)
		)
	)
	(footprint "antmicro-footprints:C_0603_1608Metric"
		(layer "F.Cu")
		(at 177.52 97.05)
		(descr "Capacitor SMD 0603")
		(tags "capacitor 0603")
		(property "Reference" "C73"
			(at -3.32 0.46 0)
			(layer "F.SilkS")
			(effects
				(font
					(size 0.7 0.7)
					(thickness 0.15)
				)
				(justify left bottom)
			)
		)
		(property "Value" "C_22u_16V_0603"
			(at -1.42757 1.770288 0)
			(layer "F.Fab")
			(effects
				(font
					(size 0.7 0.7)
					(thickness 0.15)
				)
				(justify left bottom)
			)
		)
		(property "Datasheet" "https://product.samsungsem.com/mlcc/CL10A226MO7JZN.do"
			(at 0 0 0)
			(layer "F.Fab")
			(hide yes)
			(effects
				(font
					(size 1.27 1.27)
					(thickness 0.15)
				)
			)
		)
		(property "Author" "Antmicro"
			(at 0 0 0)
			(layer "F.Fab")
			(hide yes)
			(effects
				(font
					(size 1 1)
					(thickness 0.15)
				)
			)
		)
		(property "Dielectric" ""
			(at 0 0 0)
			(layer "F.Fab")
			(hide yes)
			(effects
				(font
					(size 1 1)
					(thickness 0.15)
				)
			)
		)
		(property "License" "Apache-2.0"
			(at 0 0 0)
			(layer "F.Fab")
			(hide yes)
			(effects
				(font
					(size 1 1)
					(thickness 0.15)
				)
			)
		)
		(property "MPN" "CL10A226MO7JZNC"
			(at 0 0 0)
			(layer "F.Fab")
			(hide yes)
			(effects
				(font
					(size 1 1)
					(thickness 0.15)
				)
			)
		)
		(property "Manufacturer" "Samsung Electro-Mechanics"
			(at 0 0 0)
			(layer "F.Fab")
			(hide yes)
			(effects
				(font
					(size 1 1)
					(thickness 0.15)
				)
			)
		)
		(property "Public" "False"
			(at 0 0 0)
			(layer "F.Fab")
			(hide yes)
			(effects
				(font
					(size 1 1)
					(thickness 0.15)
				)
			)
		)
		(property "Val" "22u"
			(at 0 0 0)
			(layer "F.Fab")
			(hide yes)
			(effects
				(font
					(size 1 1)
					(thickness 0.15)
				)
			)
		)
		(property "Voltage" "16V"
			(at 0 0 0)
			(layer "F.Fab")
			(hide yes)
			(effects
				(font
					(size 1 1)
					(thickness 0.15)
				)
			)
		)
		(sheetname "M.2 key M #1")
		(sheetfile "m2keym_low.kicad_sch")
		(attr smd)
		(fp_line
			(start -0.15 -0.4)
			(end 0.15 -0.4)
			(stroke
				(width 0.15)
				(type solid)
			)
			(layer "F.SilkS")
		)
		(fp_line
			(start -0.15 0.4)
			(end 0.15 0.4)
			(stroke
				(width 0.15)
				(type solid)
			)
			(layer "F.SilkS")
		)
		(fp_rect
			(start -1.25 -0.65)
			(end 1.25 0.65)
			(stroke
				(width 0.05)
				(type solid)
			)
			(fill no)
			(layer "F.CrtYd")
		)
		(fp_rect
			(start -0.8 -0.4)
			(end 0.8 0.4)
			(stroke
				(width 0.15)
				(type solid)
			)
			(fill no)
			(layer "F.Fab")
		)
		(pad "1" smd roundrect
			(at -0.7 0)
			(size 0.8 1)
			(layers "F.Cu" "F.Mask" "F.Paste")
			(roundrect_rratio 0.2)
			(net 1 "GND")
			(pintype "passive")
			(teardrops
				(best_length_ratio 0.2)
				(max_length 1)
				(best_width_ratio 0.9)
				(max_width 2)
				(curved_edges yes)
				(filter_ratio 0.9)
				(enabled yes)
				(allow_two_segments yes)
				(prefer_zone_connections yes)
			)
		)
		(pad "2" smd roundrect
			(at 0.7 0)
			(size 0.8 1)
			(layers "F.Cu" "F.Mask" "F.Paste")
			(roundrect_rratio 0.2)
			(net 969 "/M.2 key M #1/M2_3V3")
			(pintype "passive")
			(teardrops
				(best_length_ratio 0.2)
				(max_length 1)
				(best_width_ratio 0.9)
				(max_width 2)
				(curved_edges yes)
				(filter_ratio 0.9)
				(enabled yes)
				(allow_two_segments yes)
				(prefer_zone_connections yes)
			)
		)
	)
	(footprint "antmicro-footprints:Vishay_PowerPAK_1212-8_Single"
		(layer "F.Cu")
		(at 306.125 142.285 180)
		(descr "PowerPAK 1212-8 Single")
		(tags "Vishay PowerPAK 1212-8 Single")
		(property "Reference" "Q2"
			(at 2.125 -0.275 90)
			(layer "F.SilkS")
			(effects
				(font
					(size 0.7 0.7)
					(thickness 0.15)
				)
				(justify right bottom)
			)
		)
		(property "Value" "SI7613DN-T1-GE3"
			(at 0 2.7 0)
			(layer "F.Fab")
			(effects
				(font
					(size 0.7 0.7)
					(thickness 0.15)
				)
				(justify right bottom)
			)
		)
		(property "Datasheet" "https://www.vishay.com/docs/64809/si7613dn.pdf"
			(at 0 0 180)
			(layer "F.Fab")
			(hide yes)
			(effects
				(font
					(size 1.27 1.27)
					(thickness 0.15)
				)
			)
		)
		(property "Author" "Antmicro"
			(at 612.25 284.57 0)
			(layer "F.Fab")
			(hide yes)
			(effects
				(font
					(size 1 1)
					(thickness 0.15)
				)
			)
		)
		(property "License" "Apache-2.0"
			(at 612.25 284.57 0)
			(layer "F.Fab")
			(hide yes)
			(effects
				(font
					(size 1 1)
					(thickness 0.15)
				)
			)
		)
		(property "MPN" "SI7613DN-T1-GE3"
			(at 612.25 284.57 0)
			(layer "F.Fab")
			(hide yes)
			(effects
				(font
					(size 1 1)
					(thickness 0.15)
				)
			)
		)
		(property "Manufacturer" "Vishay"
			(at 612.25 284.57 0)
			(layer "F.Fab")
			(hide yes)
			(effects
				(font
					(size 1 1)
					(thickness 0.15)
				)
			)
		)
		(sheetname "Power")
		(sheetfile "power.kicad_sch")
		(attr smd)
		(fp_line
			(start 1.648 -1.651)
			(end 1.648 -1.317)
			(stroke
				(width 0.15)
				(type solid)
			)
			(layer "F.SilkS")
		)
		(fp_line
			(start 1.634 1.3)
			(end 1.634 1.634)
			(stroke
				(width 0.15)
				(type solid)
			)
			(layer "F.SilkS")
		)
		(fp_line
			(start -1.635 1.634)
			(end 1.634 1.634)
			(stroke
				(width 0.15)
				(type solid)
			)
			(layer "F.SilkS")
		)
		(fp_line
			(start -1.635 1.3)
			(end -1.635 1.634)
			(stroke
				(width 0.15)
				(type solid)
			)
			(layer "F.SilkS")
		)
		(fp_line
			(start -1.651 -1.651)
			(end 1.648 -1.651)
			(stroke
				(width 0.15)
				(type solid)
			)
			(layer "F.SilkS")
		)
		(fp_line
			(start -1.651 -1.651)
			(end -1.651 -1.317)
			(stroke
				(width 0.15)
				(type solid)
			)
			(layer "F.SilkS")
		)
		(fp_circle
			(center -1.9 -1.4)
			(end -1.85 -1.4)
			(stroke
				(width 0.15)
				(type solid)
			)
			(fill yes)
			(layer "F.SilkS")
		)
		(fp_rect
			(start -2 -1.8)
			(end 2 1.798)
			(stroke
				(width 0.05)
				(type solid)
			)
			(fill no)
			(layer "F.CrtYd")
		)
		(fp_line
			(start -1.6425 -1.4175)
			(end -1.4175 -1.6425)
			(stroke
				(width 0.15)
				(type solid)
			)
			(layer "F.Fab")
		)
		(fp_rect
			(start -1.651 -1.651)
			(end 1.648 1.648)
			(stroke
				(width 0.15)
				(type solid)
			)
			(fill no)
			(layer "F.Fab")
		)
		(pad "1" smd rect
			(at -1.436 -0.99 180)
			(size 0.99 0.405)
			(layers "F.Cu" "F.Mask" "F.Paste")
			(net 62 "+12V_AON")
			(pinfunction "S")
			(pintype "passive")
			(teardrops
				(best_length_ratio 0.2)
				(max_length 1)
				(best_width_ratio 0.9)
				(max_width 2)
				(curved_edges yes)
				(filter_ratio 0.9)
				(enabled yes)
				(allow_two_segments yes)
				(prefer_zone_connections yes)
			)
		)
		(pad "2" smd rect
			(at -1.436 -0.332 180)
			(size 0.99 0.405)
			(layers "F.Cu" "F.Mask" "F.Paste")
			(net 62 "+12V_AON")
			(pinfunction "S")
			(pintype "passive")
			(teardrops
				(best_length_ratio 0.2)
				(max_length 1)
				(best_width_ratio 0.9)
				(max_width 2)
				(curved_edges yes)
				(filter_ratio 0.9)
				(enabled yes)
				(allow_two_segments yes)
				(prefer_zone_connections yes)
			)
		)
		(pad "3" smd rect
			(at -1.436 0.33 180)
			(size 0.99 0.405)
			(layers "F.Cu" "F.Mask" "F.Paste")
			(net 62 "+12V_AON")
			(pinfunction "S")
			(pintype "passive")
			(teardrops
				(best_length_ratio 0.2)
				(max_length 1)
				(best_width_ratio 0.9)
				(max_width 2)
				(curved_edges yes)
				(filter_ratio 0.9)
				(enabled yes)
				(allow_two_segments yes)
				(prefer_zone_connections yes)
			)
		)
		(pad "4" smd rect
			(at -1.436 0.988 180)
			(size 0.99 0.405)
			(layers "F.Cu" "F.Mask" "F.Paste")
			(net 534 "Net-(Q1-D)")
			(pinfunction "G")
			(pintype "passive")
			(teardrops
				(best_length_ratio 0.2)
				(max_length 1)
				(best_width_ratio 0.9)
				(max_width 2)
				(curved_edges yes)
				(filter_ratio 0.9)
				(enabled yes)
				(allow_two_segments yes)
				(prefer_zone_connections yes)
			)
		)
		(pad "5" smd custom
			(at 0.557 0 180)
			(size 1.725 2.235)
			(layers "F.Cu" "F.Mask" "F.Paste")
			(net 65 "+12V")
			(pinfunction "D")
			(pintype "passive")
			(zone_connect 2)
			(options
				(clearance outline)
				(anchor rect)
			)
			(primitives
				(gr_poly
					(pts
						(xy 0.8625 0.1275) (xy 0.8625 -0.1275) (xy 1.3725 -0.1275) (xy 1.3725 -0.5325) (xy 0.8625 -0.5325)
						(xy 0.8625 -0.7875) (xy 1.3725 -0.7875) (xy 1.3725 -1.195) (xy 0.6125 -1.195) (xy 0.6125 1.195)
						(xy 1.3725 1.195) (xy 1.3725 0.7875) (xy 0.8625 0.7875) (xy 0.8625 0.5325) (xy 1.3725 0.5325)
						(xy 1.3725 0.1275)
					)
					(width 0)
					(fill yes)
				)
			)
			(teardrops
				(best_length_ratio 0.2)
				(max_length 1)
				(best_width_ratio 0.9)
				(max_width 2)
				(curved_edges yes)
				(filter_ratio 0.9)
				(enabled yes)
				(allow_two_segments yes)
				(prefer_zone_connections yes)
			)
		)
	)
	(footprint "antmicro-footprints:TP_SMD_0.75mm"
		(layer "F.Cu")
		(at 134.29 129.56)
		(property "Reference" "TP82"
			(at 0.46 -1.25 90)
			(layer "F.SilkS")
			(effects
				(font
					(size 0.7 0.7)
					(thickness 0.15)
				)
				(justify left bottom)
			)
		)
		(property "Value" "TP_0.75mm_SMD"
			(at 0 1.2 0)
			(layer "F.Fab")
			(effects
				(font
					(size 0.7 0.7)
					(thickness 0.15)
				)
				(justify left bottom)
			)
		)
		(property "Author" "Antmicro"
			(at 0 0 0)
			(layer "F.Fab")
			(hide yes)
			(effects
				(font
					(size 1 1)
					(thickness 0.15)
				)
			)
		)
		(property "License" "Apache-2.0"
			(at 0 0 0)
			(layer "F.Fab")
			(hide yes)
			(effects
				(font
					(size 1 1)
					(thickness 0.15)
				)
			)
		)
		(property "MPN" ""
			(at 0 0 0)
			(layer "F.Fab")
			(hide yes)
			(effects
				(font
					(size 1 1)
					(thickness 0.15)
				)
			)
		)
		(property "Manufacturer" ""
			(at 0 0 0)
			(layer "F.Fab")
			(hide yes)
			(effects
				(font
					(size 1 1)
					(thickness 0.15)
				)
			)
		)
		(property "Public" "False"
			(at 0 0 0)
			(layer "F.Fab")
			(hide yes)
			(effects
				(font
					(size 1 1)
					(thickness 0.15)
				)
			)
		)
		(sheetname "KR to SFI #2")
		(sheetfile "kr_sfi.kicad_sch")
		(attr exclude_from_pos_files exclude_from_bom)
		(fp_circle
			(center 0 0)
			(end 0.475 0)
			(stroke
				(width 0.05)
				(type default)
			)
			(fill no)
			(layer "F.CrtYd")
		)
		(pad "1" smd circle
			(at 0 0)
			(size 0.75 0.75)
			(layers "F.Cu" "F.Mask")
			(net 745 "/2xSFP+/KR to SFI #2/TCK")
			(pinfunction "1")
			(pintype "passive")
			(teardrops
				(best_length_ratio 0.4)
				(max_length 1)
				(best_width_ratio 0.9)
				(max_width 2)
				(curved_edges yes)
				(filter_ratio 0.9)
				(enabled yes)
				(allow_two_segments yes)
				(prefer_zone_connections yes)
			)
		)
	)
	(footprint "antmicro-footprints:USON-10_2.5x1mm_P0.5mm"
		(layer "F.Cu")
		(at 314.75 160.91)
		(descr "USON-10 2.5x1mm_ Pitch 0.5mm")
		(tags "USON-10 2.5x1mm Pitch 0.5mm")
		(property "Reference" "U16"
			(at -0.9 1.1 90)
			(layer "F.SilkS")
			(effects
				(font
					(size 0.7 0.7)
					(thickness 0.15)
				)
				(justify left bottom)
			)
		)
		(property "Value" "ESD204DQAR"
			(at 0.018 2.499 0)
			(layer "F.Fab")
			(effects
				(font
					(size 0.7 0.7)
					(thickness 0.15)
				)
				(justify left bottom)
			)
		)
		(property "Datasheet" "https://www.ti.com/lit/ds/symlink/esd204.pdf?ts=1706004844383&ref_url=https%253A%252F%252Fwww.ti.com%252Finterface%252Fdiodes%252Fesd-protection-diodes%252Fproducts.html"
			(at 0 0 0)
			(layer "F.Fab")
			(hide yes)
			(effects
				(font
					(size 1.27 1.27)
					(thickness 0.15)
				)
			)
		)
		(property "Author" "Antmicro"
			(at 0 0 0)
			(layer "F.Fab")
			(hide yes)
			(effects
				(font
					(size 1 1)
					(thickness 0.15)
				)
			)
		)
		(property "License" "Apache-2.0"
			(at 0 0 0)
			(layer "F.Fab")
			(hide yes)
			(effects
				(font
					(size 1 1)
					(thickness 0.15)
				)
			)
		)
		(property "MPN" "ESD204DQAR"
			(at 0 0 0)
			(layer "F.Fab")
			(hide yes)
			(effects
				(font
					(size 1 1)
					(thickness 0.15)
				)
			)
		)
		(property "Manufacturer" "Texas Instruments"
			(at 0 0 0)
			(layer "F.Fab")
			(hide yes)
			(effects
				(font
					(size 1 1)
					(thickness 0.15)
				)
			)
		)
		(sheetname "Backplane")
		(sheetfile "backplane.kicad_sch")
		(attr smd)
		(fp_line
			(start 0.498 -1.401)
			(end -0.5 -1.401)
			(stroke
				(width 0.15)
				(type solid)
			)
			(layer "F.SilkS")
		)
		(fp_line
			(start 0.498 1.398)
			(end -0.5 1.398)
			(stroke
				(width 0.15)
				(type solid)
			)
			(layer "F.SilkS")
		)
		(fp_circle
			(center -0.68 -1.27)
			(end -0.63 -1.27)
			(stroke
				(width 0.15)
				(type solid)
			)
			(fill yes)
			(layer "F.SilkS")
		)
		(fp_rect
			(start -0.8 -1.5)
			(end 0.8 1.499)
			(stroke
				(width 0.05)
				(type solid)
			)
			(fill no)
			(layer "F.CrtYd")
		)
		(fp_line
			(start -0.5 -1)
			(end -0.5 1.249)
			(stroke
				(width 0.15)
				(type solid)
			)
			(layer "F.Fab")
		)
		(fp_line
			(start -0.5 1.249)
			(end 0.498 1.249)
			(stroke
				(width 0.15)
				(type solid)
			)
			(layer "F.Fab")
		)
		(fp_line
			(start -0.25 -1.25)
			(end -0.5 -1)
			(stroke
				(width 0.15)
				(type solid)
			)
			(layer "F.Fab")
		)
		(fp_line
			(start 0.498 -1.25)
			(end -0.25 -1.25)
			(stroke
				(width 0.15)
				(type solid)
			)
			(layer "F.Fab")
		)
		(fp_line
			(start 0.498 -1.25)
			(end 0.498 1.249)
			(stroke
				(width 0.15)
				(type solid)
			)
			(layer "F.Fab")
		)
		(pad "1" smd roundrect
			(at -0.387 -1 270)
			(size 0.25 0.55)
			(layers "F.Cu" "F.Mask" "F.Paste")
			(roundrect_rratio 0.25)
			(net 532 "/Backplane/PCIe_{x2}.RX0+")
			(pintype "passive")
			(teardrops
				(best_length_ratio 0.2)
				(max_length 1)
				(best_width_ratio 0.9)
				(max_width 2)
				(curved_edges yes)
				(filter_ratio 0.9)
				(enabled yes)
				(allow_two_segments yes)
				(prefer_zone_connections yes)
			)
		)
		(pad "2" smd roundrect
			(at -0.387 -0.5 270)
			(size 0.25 0.55)
			(layers "F.Cu" "F.Mask" "F.Paste")
			(roundrect_rratio 0.25)
			(net 537 "/Backplane/PCIe_{x2}.RX0-")
			(pintype "passive")
			(teardrops
				(best_length_ratio 0.2)
				(max_length 1)
				(best_width_ratio 0.9)
				(max_width 2)
				(curved_edges yes)
				(filter_ratio 0.9)
				(enabled yes)
				(allow_two_segments yes)
				(prefer_zone_connections yes)
			)
		)
		(pad "3" smd roundrect
			(at -0.387 0 270)
			(size 0.4 0.55)
			(layers "F.Cu" "F.Mask" "F.Paste")
			(roundrect_rratio 0.25)
			(net 1 "GND")
			(pintype "power_in")
			(teardrops
				(best_length_ratio 0.2)
				(max_length 1)
				(best_width_ratio 0.9)
				(max_width 2)
				(curved_edges yes)
				(filter_ratio 0.9)
				(enabled yes)
				(allow_two_segments yes)
				(prefer_zone_connections yes)
			)
		)
		(pad "4" smd roundrect
			(at -0.387 0.498 270)
			(size 0.25 0.55)
			(layers "F.Cu" "F.Mask" "F.Paste")
			(roundrect_rratio 0.25)
			(net 771 "/Backplane/PCIe_{x2}.RX1+")
			(pintype "passive")
			(teardrops
				(best_length_ratio 0.2)
				(max_length 1)
				(best_width_ratio 0.9)
				(max_width 2)
				(curved_edges yes)
				(filter_ratio 0.9)
				(enabled yes)
				(allow_two_segments yes)
				(prefer_zone_connections yes)
			)
		)
		(pad "5" smd roundrect
			(at -0.387 0.998 270)
			(size 0.25 0.55)
			(layers "F.Cu" "F.Mask" "F.Paste")
			(roundrect_rratio 0.25)
			(net 772 "/Backplane/PCIe_{x2}.RX1-")
			(pintype "passive")
			(teardrops
				(best_length_ratio 0.2)
				(max_length 1)
				(best_width_ratio 0.9)
				(max_width 2)
				(curved_edges yes)
				(filter_ratio 0.9)
				(enabled yes)
				(allow_two_segments yes)
				(prefer_zone_connections yes)
			)
		)
		(pad "6" smd roundrect
			(at 0.385 0.998 270)
			(size 0.25 0.55)
			(layers "F.Cu" "F.Mask" "F.Paste")
			(roundrect_rratio 0.25)
			(net 772 "/Backplane/PCIe_{x2}.RX1-")
			(pintype "passive")
			(teardrops
				(best_length_ratio 0.2)
				(max_length 1)
				(best_width_ratio 0.9)
				(max_width 2)
				(curved_edges yes)
				(filter_ratio 0.9)
				(enabled yes)
				(allow_two_segments yes)
				(prefer_zone_connections yes)
			)
		)
		(pad "7" smd roundrect
			(at 0.385 0.498 270)
			(size 0.25 0.55)
			(layers "F.Cu" "F.Mask" "F.Paste")
			(roundrect_rratio 0.25)
			(net 771 "/Backplane/PCIe_{x2}.RX1+")
			(pintype "passive")
			(teardrops
				(best_length_ratio 0.2)
				(max_length 1)
				(best_width_ratio 0.9)
				(max_width 2)
				(curved_edges yes)
				(filter_ratio 0.9)
				(enabled yes)
				(allow_two_segments yes)
				(prefer_zone_connections yes)
			)
		)
		(pad "8" smd roundrect
			(at 0.385 0 270)
			(size 0.4 0.55)
			(layers "F.Cu" "F.Mask" "F.Paste")
			(roundrect_rratio 0.25)
			(net 1 "GND")
			(pintype "passive")
			(teardrops
				(best_length_ratio 0.2)
				(max_length 1)
				(best_width_ratio 0.9)
				(max_width 2)
				(curved_edges yes)
				(filter_ratio 0.9)
				(enabled yes)
				(allow_two_segments yes)
				(prefer_zone_connections yes)
			)
		)
		(pad "9" smd roundrect
			(at 0.385 -0.5 270)
			(size 0.25 0.55)
			(layers "F.Cu" "F.Mask" "F.Paste")
			(roundrect_rratio 0.25)
			(net 537 "/Backplane/PCIe_{x2}.RX0-")
			(pintype "passive")
			(teardrops
				(best_length_ratio 0.2)
				(max_length 1)
				(best_width_ratio 0.9)
				(max_width 2)
				(curved_edges yes)
				(filter_ratio 0.9)
				(enabled yes)
				(allow_two_segments yes)
				(prefer_zone_connections yes)
			)
		)
		(pad "10" smd roundrect
			(at 0.385 -1 270)
			(size 0.25 0.55)
			(layers "F.Cu" "F.Mask" "F.Paste")
			(roundrect_rratio 0.25)
			(net 532 "/Backplane/PCIe_{x2}.RX0+")
			(pintype "passive")
			(teardrops
				(best_length_ratio 0.2)
				(max_length 1)
				(best_width_ratio 0.9)
				(max_width 2)
				(curved_edges yes)
				(filter_ratio 0.9)
				(enabled yes)
				(allow_two_segments yes)
				(prefer_zone_connections yes)
			)
		)
	)
	(footprint "antmicro-footprints:R_0402_1005Metric"
		(layer "F.Cu")
		(at 222.68 128.2 180)
		(descr "Resistor SMD 0402")
		(tags "resistor SMD 0402")
		(property "Reference" "R317"
			(at -3.62 -0.41 0)
			(layer "F.SilkS")
			(effects
				(font
					(size 0.7 0.7)
					(thickness 0.15)
				)
				(justify right bottom)
			)
		)
		(property "Value" "R_0R_0402"
			(at -1.011843 1.772047 0)
			(layer "F.Fab")
			(effects
				(font
					(size 0.7 0.7)
					(thickness 0.15)
				)
				(justify right bottom)
			)
		)
		(property "Datasheet" "https://industrial.panasonic.com/cdbs/www-data/pdf/RDA0000/AOA0000C301.pdf"
			(at 0 0 180)
			(layer "F.Fab")
			(hide yes)
			(effects
				(font
					(size 1.27 1.27)
					(thickness 0.15)
				)
			)
		)
		(property "Author" "Antmicro"
			(at 445.36 256.4 0)
			(layer "F.Fab")
			(hide yes)
			(effects
				(font
					(size 1 1)
					(thickness 0.15)
				)
			)
		)
		(property "Current" "1A"
			(at 445.36 256.4 0)
			(layer "F.Fab")
			(hide yes)
			(effects
				(font
					(size 1 1)
					(thickness 0.15)
				)
			)
		)
		(property "License" "Apache-2.0"
			(at 445.36 256.4 0)
			(layer "F.Fab")
			(hide yes)
			(effects
				(font
					(size 1 1)
					(thickness 0.15)
				)
			)
		)
		(property "MPN" "ERJ2GE0R00X"
			(at 445.36 256.4 0)
			(layer "F.Fab")
			(hide yes)
			(effects
				(font
					(size 1 1)
					(thickness 0.15)
				)
			)
		)
		(property "Manufacturer" "Panasonic"
			(at 445.36 256.4 0)
			(layer "F.Fab")
			(hide yes)
			(effects
				(font
					(size 1 1)
					(thickness 0.15)
				)
			)
		)
		(property "Public" "False"
			(at 445.36 256.4 0)
			(layer "F.Fab")
			(hide yes)
			(effects
				(font
					(size 1 1)
					(thickness 0.15)
				)
			)
		)
		(property "Tolerance" ""
			(at 445.36 256.4 0)
			(layer "F.Fab")
			(hide yes)
			(effects
				(font
					(size 1 1)
					(thickness 0.15)
				)
			)
		)
		(property "Val" "0R"
			(at 445.36 256.4 0)
			(layer "F.Fab")
			(hide yes)
			(effects
				(font
					(size 1 1)
					(thickness 0.15)
				)
			)
		)
		(sheetname "PCIe misc")
		(sheetfile "pcie_misc.kicad_sch")
		(attr smd dnp)
		(fp_rect
			(start -0.925 -0.47)
			(end 0.925 0.47)
			(stroke
				(width 0.05)
				(type default)
			)
			(fill no)
			(layer "F.CrtYd")
		)
		(fp_rect
			(start -0.5 -0.25)
			(end 0.5 0.25)
			(stroke
				(width 0.15)
				(type solid)
			)
			(fill no)
			(layer "F.Fab")
		)
		(pad "1" smd roundrect
			(at -0.48 0 180)
			(size 0.59 0.64)
			(layers "F.Cu" "F.Mask" "F.Paste")
			(roundrect_rratio 0.25)
			(net 530 "/M.2 key M #2/~{CLKREQ}")
			(pintype "passive")
			(teardrops
				(best_length_ratio 0.2)
				(max_length 1)
				(best_width_ratio 0.9)
				(max_width 2)
				(curved_edges yes)
				(filter_ratio 0.9)
				(enabled yes)
				(allow_two_segments yes)
				(prefer_zone_connections yes)
			)
		)
		(pad "2" smd roundrect
			(at 0.48 0 180)
			(size 0.59 0.64)
			(layers "F.Cu" "F.Mask" "F.Paste")
			(roundrect_rratio 0.25)
			(net 606 "Net-(U37-~{OE4})")
			(pintype "passive")
			(teardrops
				(best_length_ratio 0.2)
				(max_length 1)
				(best_width_ratio 0.9)
				(max_width 2)
				(curved_edges yes)
				(filter_ratio 0.9)
				(enabled yes)
				(allow_two_segments yes)
				(prefer_zone_connections yes)
			)
		)
	)
	(footprint "antmicro-footprints:R_0402_1005Metric"
		(layer "F.Cu")
		(at 124.84 135.88 180)
		(descr "Resistor SMD 0402")
		(tags "resistor SMD 0402")
		(property "Reference" "R280"
			(at 0.79 -0.43 0)
			(layer "F.SilkS")
			(effects
				(font
					(size 0.7 0.7)
					(thickness 0.15)
				)
				(justify right bottom)
			)
		)
		(property "Value" "R_100k_0402"
			(at -1.011843 1.772047 0)
			(layer "F.Fab")
			(effects
				(font
					(size 0.7 0.7)
					(thickness 0.15)
				)
				(justify right bottom)
			)
		)
		(property "Datasheet" "https://www.bourns.com/docs/product-datasheets/cr.pdf"
			(at 0 0 180)
			(layer "F.Fab")
			(hide yes)
			(effects
				(font
					(size 1.27 1.27)
					(thickness 0.15)
				)
			)
		)
		(property "Author" "Antmicro"
			(at 249.68 271.76 0)
			(layer "F.Fab")
			(hide yes)
			(effects
				(font
					(size 1 1)
					(thickness 0.15)
				)
			)
		)
		(property "License" "Apache-2.0"
			(at 249.68 271.76 0)
			(layer "F.Fab")
			(hide yes)
			(effects
				(font
					(size 1 1)
					(thickness 0.15)
				)
			)
		)
		(property "MPN" "CR0402-FX-1003GLF"
			(at 249.68 271.76 0)
			(layer "F.Fab")
			(hide yes)
			(effects
				(font
					(size 1 1)
					(thickness 0.15)
				)
			)
		)
		(property "Manufacturer" "Bourns"
			(at 249.68 271.76 0)
			(layer "F.Fab")
			(hide yes)
			(effects
				(font
					(size 1 1)
					(thickness 0.15)
				)
			)
		)
		(property "Public" "False"
			(at 249.68 271.76 0)
			(layer "F.Fab")
			(hide yes)
			(effects
				(font
					(size 1 1)
					(thickness 0.15)
				)
			)
		)
		(property "Tolerance" "1%"
			(at 249.68 271.76 0)
			(layer "F.Fab")
			(hide yes)
			(effects
				(font
					(size 1 1)
					(thickness 0.15)
				)
			)
		)
		(property "Val" "100k"
			(at 249.68 271.76 0)
			(layer "F.Fab")
			(hide yes)
			(effects
				(font
					(size 1 1)
					(thickness 0.15)
				)
			)
		)
		(sheetname "KR to SFI #2")
		(sheetfile "kr_sfi.kicad_sch")
		(attr smd)
		(fp_rect
			(start -0.925 -0.47)
			(end 0.925 0.47)
			(stroke
				(width 0.05)
				(type default)
			)
			(fill no)
			(layer "F.CrtYd")
		)
		(fp_rect
			(start -0.5 -0.25)
			(end 0.5 0.25)
			(stroke
				(width 0.15)
				(type solid)
			)
			(fill no)
			(layer "F.Fab")
		)
		(pad "1" smd roundrect
			(at -0.48 0 180)
			(size 0.59 0.64)
			(layers "F.Cu" "F.Mask" "F.Paste")
			(roundrect_rratio 0.25)
			(net 2 "+3V3")
			(pintype "passive")
			(teardrops
				(best_length_ratio 0.2)
				(max_length 1)
				(best_width_ratio 0.9)
				(max_width 2)
				(curved_edges yes)
				(filter_ratio 0.9)
				(enabled yes)
				(allow_two_segments yes)
				(prefer_zone_connections yes)
			)
		)
		(pad "2" smd roundrect
			(at 0.48 0 180)
			(size 0.59 0.64)
			(layers "F.Cu" "F.Mask" "F.Paste")
			(roundrect_rratio 0.25)
			(net 668 "Net-(Y3-EN)")
			(pintype "passive")
			(teardrops
				(best_length_ratio 0.2)
				(max_length 1)
				(best_width_ratio 0.9)
				(max_width 2)
				(curved_edges yes)
				(filter_ratio 0.9)
				(enabled yes)
				(allow_two_segments yes)
				(prefer_zone_connections yes)
			)
		)
	)
	(footprint "antmicro-footprints:R_0402_1005Metric"
		(layer "F.Cu")
		(at 298.2 84.01 -90)
		(descr "Resistor SMD 0402")
		(tags "resistor SMD 0402")
		(property "Reference" "R127"
			(at 0.85 -0.45 90)
			(layer "F.SilkS")
			(effects
				(font
					(size 0.7 0.7)
					(thickness 0.15)
				)
				(justify right bottom)
			)
		)
		(property "Value" "R_10k_0402"
			(at -1.011843 1.772047 90)
			(layer "F.Fab")
			(effects
				(font
					(size 0.7 0.7)
					(thickness 0.15)
				)
				(justify right bottom)
			)
		)
		(property "Datasheet" "https://www.bourns.com/docs/product-datasheets/cr.pdf"
			(at 0 0 270)
			(layer "F.Fab")
			(hide yes)
			(effects
				(font
					(size 1.27 1.27)
					(thickness 0.15)
				)
			)
		)
		(property "Author" "Antmicro"
			(at 214.19 382.21 0)
			(layer "F.Fab")
			(hide yes)
			(effects
				(font
					(size 1 1)
					(thickness 0.15)
				)
			)
		)
		(property "License" "Apache-2.0"
			(at 214.19 382.21 0)
			(layer "F.Fab")
			(hide yes)
			(effects
				(font
					(size 1 1)
					(thickness 0.15)
				)
			)
		)
		(property "MPN" "CR0402-FX-1002GLF"
			(at 214.19 382.21 0)
			(layer "F.Fab")
			(hide yes)
			(effects
				(font
					(size 1 1)
					(thickness 0.15)
				)
			)
		)
		(property "Manufacturer" "Bourns"
			(at 214.19 382.21 0)
			(layer "F.Fab")
			(hide yes)
			(effects
				(font
					(size 1 1)
					(thickness 0.15)
				)
			)
		)
		(property "Public" "False"
			(at 214.19 382.21 0)
			(layer "F.Fab")
			(hide yes)
			(effects
				(font
					(size 1 1)
					(thickness 0.15)
				)
			)
		)
		(property "Tolerance" "1%"
			(at 214.19 382.21 0)
			(layer "F.Fab")
			(hide yes)
			(effects
				(font
					(size 1 1)
					(thickness 0.15)
				)
			)
		)
		(property "Val" "10k"
			(at 214.19 382.21 0)
			(layer "F.Fab")
			(hide yes)
			(effects
				(font
					(size 1 1)
					(thickness 0.15)
				)
			)
		)
		(sheetname "M.2 key M #2")
		(sheetfile "m2keym.kicad_sch")
		(attr smd dnp)
		(fp_rect
			(start -0.925 -0.47)
			(end 0.925 0.47)
			(stroke
				(width 0.05)
				(type default)
			)
			(fill no)
			(layer "F.CrtYd")
		)
		(fp_rect
			(start -0.5 -0.25)
			(end 0.5 0.25)
			(stroke
				(width 0.15)
				(type solid)
			)
			(fill no)
			(layer "F.Fab")
		)
		(pad "1" smd roundrect
			(at -0.48 0 270)
			(size 0.59 0.64)
			(layers "F.Cu" "F.Mask" "F.Paste")
			(roundrect_rratio 0.25)
			(net 270 "/M.2 key M #2/~{PERST_D}")
			(pintype "passive")
			(teardrops
				(best_length_ratio 0.2)
				(max_length 1)
				(best_width_ratio 0.9)
				(max_width 2)
				(curved_edges yes)
				(filter_ratio 0.9)
				(enabled yes)
				(allow_two_segments yes)
				(prefer_zone_connections yes)
			)
		)
		(pad "2" smd roundrect
			(at 0.48 0 270)
			(size 0.59 0.64)
			(layers "F.Cu" "F.Mask" "F.Paste")
			(roundrect_rratio 0.25)
			(net 2 "+3V3")
			(pintype "passive")
			(teardrops
				(best_length_ratio 0.2)
				(max_length 1)
				(best_width_ratio 0.9)
				(max_width 2)
				(curved_edges yes)
				(filter_ratio 0.9)
				(enabled yes)
				(allow_two_segments yes)
				(prefer_zone_connections yes)
			)
		)
	)
	(footprint "antmicro-footprints:R_0402_1005Metric"
		(layer "F.Cu")
		(at 314.075499 136.46 -90)
		(descr "Resistor SMD 0402")
		(tags "resistor SMD 0402")
		(property "Reference" "R112"
			(at -3.05 -5.574501 90)
			(layer "F.SilkS")
			(effects
				(font
					(size 0.7 0.7)
					(thickness 0.15)
				)
				(justify right bottom)
			)
		)
		(property "Value" "R_15k_0402"
			(at -1.011843 1.772047 90)
			(layer "F.Fab")
			(effects
				(font
					(size 0.7 0.7)
					(thickness 0.15)
				)
				(justify right bottom)
			)
		)
		(property "Datasheet" "https://www.bourns.com/docs/product-datasheets/cr.pdf"
			(at 0 0 270)
			(layer "F.Fab")
			(hide yes)
			(effects
				(font
					(size 1.27 1.27)
					(thickness 0.15)
				)
			)
		)
		(property "Author" "Antmicro"
			(at 177.615499 450.535499 0)
			(layer "F.Fab")
			(hide yes)
			(effects
				(font
					(size 1 1)
					(thickness 0.15)
				)
			)
		)
		(property "License" "Apache-2.0"
			(at 177.615499 450.535499 0)
			(layer "F.Fab")
			(hide yes)
			(effects
				(font
					(size 1 1)
					(thickness 0.15)
				)
			)
		)
		(property "MPN" "CR0402-FX-1502GLF"
			(at 177.615499 450.535499 0)
			(layer "F.Fab")
			(hide yes)
			(effects
				(font
					(size 1 1)
					(thickness 0.15)
				)
			)
		)
		(property "Manufacturer" "Bourns"
			(at 177.615499 450.535499 0)
			(layer "F.Fab")
			(hide yes)
			(effects
				(font
					(size 1 1)
					(thickness 0.15)
				)
			)
		)
		(property "Public" "False"
			(at 177.615499 450.535499 0)
			(layer "F.Fab")
			(hide yes)
			(effects
				(font
					(size 1 1)
					(thickness 0.15)
				)
			)
		)
		(property "Tolerance" "1%"
			(at 177.615499 450.535499 0)
			(layer "F.Fab")
			(hide yes)
			(effects
				(font
					(size 1 1)
					(thickness 0.15)
				)
			)
		)
		(property "Val" "15k"
			(at 177.615499 450.535499 0)
			(layer "F.Fab")
			(hide yes)
			(effects
				(font
					(size 1 1)
					(thickness 0.15)
				)
			)
		)
		(sheetname "Power")
		(sheetfile "power.kicad_sch")
		(attr smd)
		(fp_rect
			(start -0.925 -0.47)
			(end 0.925 0.47)
			(stroke
				(width 0.05)
				(type default)
			)
			(fill no)
			(layer "F.CrtYd")
		)
		(fp_rect
			(start -0.5 -0.25)
			(end 0.5 0.25)
			(stroke
				(width 0.15)
				(type solid)
			)
			(fill no)
			(layer "F.Fab")
		)
		(pad "1" smd roundrect
			(at -0.48 0 270)
			(size 0.59 0.64)
			(layers "F.Cu" "F.Mask" "F.Paste")
			(roundrect_rratio 0.25)
			(net 1 "GND")
			(pintype "passive")
			(teardrops
				(best_length_ratio 0.2)
				(max_length 1)
				(best_width_ratio 0.9)
				(max_width 2)
				(curved_edges yes)
				(filter_ratio 0.9)
				(enabled yes)
				(allow_two_segments yes)
				(prefer_zone_connections yes)
			)
		)
		(pad "2" smd roundrect
			(at 0.48 0 270)
			(size 0.59 0.64)
			(layers "F.Cu" "F.Mask" "F.Paste")
			(roundrect_rratio 0.25)
			(net 586 "Net-(U22-FB)")
			(pintype "passive")
			(teardrops
				(best_length_ratio 0.2)
				(max_length 1)
				(best_width_ratio 0.9)
				(max_width 2)
				(curved_edges yes)
				(filter_ratio 0.9)
				(enabled yes)
				(allow_two_segments yes)
				(prefer_zone_connections yes)
			)
		)
	)
	(footprint "antmicro-footprints:C_Pol_EIA-D"
		(layer "F.Cu")
		(at 313.95 140.26)
		(property "Reference" "C43"
			(at 1.15 -2.35 0)
			(layer "F.SilkS")
			(effects
				(font
					(size 0.7 0.7)
					(thickness 0.15)
				)
				(justify left bottom)
			)
		)
		(property "Value" "C_Pol_68u_16V_Panasonic-TQC-D"
			(at 0 3.4 0)
			(layer "F.Fab")
			(effects
				(font
					(size 0.7 0.7)
					(thickness 0.15)
				)
				(justify left bottom)
			)
		)
		(property "Datasheet" "https://industrial.panasonic.com/sa/products/pt/aluminum-cap-smd/models/16TQC68MYF"
			(at 0 0 0)
			(layer "F.Fab")
			(hide yes)
			(effects
				(font
					(size 1.27 1.27)
					(thickness 0.15)
				)
			)
		)
		(property "Author" "Antmicro"
			(at 0 0 0)
			(layer "F.Fab")
			(hide yes)
			(effects
				(font
					(size 1 1)
					(thickness 0.15)
				)
			)
		)
		(property "Dielectric" "template_dielectric"
			(at 0 0 0)
			(layer "F.Fab")
			(hide yes)
			(effects
				(font
					(size 1 1)
					(thickness 0.15)
				)
			)
		)
		(property "License" "Apache-2.0"
			(at 0 0 0)
			(layer "F.Fab")
			(hide yes)
			(effects
				(font
					(size 1 1)
					(thickness 0.15)
				)
			)
		)
		(property "MPN" "16TQC68MYF"
			(at 0 0 0)
			(layer "F.Fab")
			(hide yes)
			(effects
				(font
					(size 1 1)
					(thickness 0.15)
				)
			)
		)
		(property "Manufacturer" "Panasonic"
			(at 0 0 0)
			(layer "F.Fab")
			(hide yes)
			(effects
				(font
					(size 1 1)
					(thickness 0.15)
				)
			)
		)
		(property "Public" "False"
			(at 0 0 0)
			(layer "F.Fab")
			(hide yes)
			(effects
				(font
					(size 1 1)
					(thickness 0.15)
				)
			)
		)
		(property "Val" "68u"
			(at 0 0 0)
			(layer "F.Fab")
			(hide yes)
			(effects
				(font
					(size 1 1)
					(thickness 0.15)
				)
			)
		)
		(property "Voltage" "16V"
			(at 0 0 0)
			(layer "F.Fab")
			(hide yes)
			(effects
				(font
					(size 1 1)
					(thickness 0.15)
				)
			)
		)
		(sheetname "Power")
		(sheetfile "power.kicad_sch")
		(attr smd)
		(fp_line
			(start -4.3 -1.825)
			(end -3.9 -1.825)
			(stroke
				(width 0.12)
				(type solid)
			)
			(layer "F.SilkS")
		)
		(fp_line
			(start -4.1 -2.025)
			(end -4.1 -1.625)
			(stroke
				(width 0.12)
				(type solid)
			)
			(layer "F.SilkS")
		)
		(fp_line
			(start -3.58 -2.2)
			(end 3.6 -2.2)
			(stroke
				(width 0.15)
				(type solid)
			)
			(layer "F.SilkS")
		)
		(fp_line
			(start -3.58 -1.6)
			(end -3.58 -2.2)
			(stroke
				(width 0.15)
				(type solid)
			)
			(layer "F.SilkS")
		)
		(fp_line
			(start -3.58 2.2)
			(end -3.58 1.6)
			(stroke
				(width 0.15)
				(type solid)
			)
			(layer "F.SilkS")
		)
		(fp_line
			(start 3.6 -2.2)
			(end 3.6 -1.6)
			(stroke
				(width 0.15)
				(type solid)
			)
			(layer "F.SilkS")
		)
		(fp_line
			(start 3.6 1.6)
			(end 3.6 2.2)
			(stroke
				(width 0.15)
				(type solid)
			)
			(layer "F.SilkS")
		)
		(fp_line
			(start 3.6 2.2)
			(end -3.58 2.2)
			(stroke
				(width 0.15)
				(type solid)
			)
			(layer "F.SilkS")
		)
		(fp_line
			(start -4.505 1.51)
			(end -4.505 -1.5)
			(stroke
				(width 0.05)
				(type solid)
			)
			(layer "F.CrtYd")
		)
		(fp_line
			(start -3.775 -2.4)
			(end -3.775 -1.5)
			(stroke
				(width 0.05)
				(type solid)
			)
			(layer "F.CrtYd")
		)
		(fp_line
			(start -3.775 -2.4)
			(end 3.77 -2.4)
			(stroke
				(width 0.05)
				(type solid)
			)
			(layer "F.CrtYd")
		)
		(fp_line
			(start -3.775 -1.5)
			(end -4.505 -1.5)
			(stroke
				(width 0.05)
				(type solid)
			)
			(layer "F.CrtYd")
		)
		(fp_line
			(start -3.77 1.51)
			(end -4.505 1.51)
			(stroke
				(width 0.05)
				(type solid)
			)
			(layer "F.CrtYd")
		)
		(fp_line
			(start -3.77 2.4)
			(end -3.77 1.51)
			(stroke
				(width 0.05)
				(type solid)
			)
			(layer "F.CrtYd")
		)
		(fp_line
			(start 3.77 -2.4)
			(end 3.77 -1.51)
			(stroke
				(width 0.05)
				(type solid)
			)
			(layer "F.CrtYd")
		)
		(fp_line
			(start 3.77 -1.51)
			(end 4.505 -1.51)
			(stroke
				(width 0.05)
				(type solid)
			)
			(layer "F.CrtYd")
		)
		(fp_line
			(start 3.77 1.51)
			(end 3.77 2.4)
			(stroke
				(width 0.05)
				(type solid)
			)
			(layer "F.CrtYd")
		)
		(fp_line
			(start 3.77 2.4)
			(end -3.77 2.4)
			(stroke
				(width 0.05)
				(type solid)
			)
			(layer "F.CrtYd")
		)
		(fp_line
			(start 4.505 -1.51)
			(end 4.505 1.5)
			(stroke
				(width 0.05)
				(type solid)
			)
			(layer "F.CrtYd")
		)
		(fp_line
			(start 4.505 1.51)
			(end 3.77 1.51)
			(stroke
				(width 0.05)
				(type solid)
			)
			(layer "F.CrtYd")
		)
		(fp_rect
			(start -3.65 -2.15)
			(end 3.65 2.15)
			(stroke
				(width 0.15)
				(type solid)
			)
			(fill no)
			(layer "F.Fab")
		)
		(pad "1" smd roundrect
			(at -3.1 0)
			(size 2.31 2.52)
			(layers "F.Cu" "F.Mask" "F.Paste")
			(roundrect_rratio 0.1)
			(net 62 "+12V_AON")
			(pintype "passive")
			(teardrops
				(best_length_ratio 0.2)
				(max_length 1)
				(best_width_ratio 0.9)
				(max_width 2)
				(curved_edges yes)
				(filter_ratio 0.9)
				(enabled yes)
				(allow_two_segments yes)
				(prefer_zone_connections yes)
			)
		)
		(pad "2" smd roundrect
			(at 3.1 0)
			(size 2.31 2.52)
			(layers "F.Cu" "F.Mask" "F.Paste")
			(roundrect_rratio 0.1)
			(net 1 "GND")
			(pintype "passive")
			(teardrops
				(best_length_ratio 0.2)
				(max_length 1)
				(best_width_ratio 0.9)
				(max_width 2)
				(curved_edges yes)
				(filter_ratio 0.9)
				(enabled yes)
				(allow_two_segments yes)
				(prefer_zone_connections yes)
			)
		)
	)
	(footprint "antmicro-footprints:R_0402_1005Metric"
		(layer "F.Cu")
		(at 193.757107 130.907107 -135)
		(descr "Resistor SMD 0402")
		(tags "resistor SMD 0402")
		(property "Reference" "R226"
			(at -3.65 -0.4 45)
			(layer "F.SilkS")
			(effects
				(font
					(size 0.7 0.7)
					(thickness 0.15)
				)
				(justify right bottom)
			)
		)
		(property "Value" "R_1k_0402"
			(at -1.011843 1.772046 45)
			(layer "F.Fab")
			(effects
				(font
					(size 0.7 0.7)
					(thickness 0.15)
				)
				(justify right bottom)
			)
		)
		(property "Datasheet" "https://www.bourns.com/docs/product-datasheets/cr.pdf"
			(at 0 0 45)
			(layer "F.Fab")
			(hide yes)
			(effects
				(font
					(size 1.27 1.27)
					(thickness 0.15)
				)
			)
		)
		(property "Author" "Antmicro"
			(at 389.1 265.22 45)
			(layer "F.Fab")
			(hide yes)
			(effects
				(font
					(size 1 1)
					(thickness 0.15)
				)
			)
		)
		(property "License" "Apache-2.0"
			(at 389.1 265.22 45)
			(layer "F.Fab")
			(hide yes)
			(effects
				(font
					(size 1 1)
					(thickness 0.15)
				)
			)
		)
		(property "MPN" "CR0402-FX-1001GLF"
			(at 389.1 265.22 45)
			(layer "F.Fab")
			(hide yes)
			(effects
				(font
					(size 1 1)
					(thickness 0.15)
				)
			)
		)
		(property "Manufacturer" "Bourns"
			(at 389.1 265.22 45)
			(layer "F.Fab")
			(hide yes)
			(effects
				(font
					(size 1 1)
					(thickness 0.15)
				)
			)
		)
		(property "Public" "False"
			(at 389.1 265.22 45)
			(layer "F.Fab")
			(hide yes)
			(effects
				(font
					(size 1 1)
					(thickness 0.15)
				)
			)
		)
		(property "Tolerance" "1%"
			(at 389.1 265.22 45)
			(layer "F.Fab")
			(hide yes)
			(effects
				(font
					(size 1 1)
					(thickness 0.15)
				)
			)
		)
		(property "Val" "1k"
			(at 389.1 265.22 45)
			(layer "F.Fab")
			(hide yes)
			(effects
				(font
					(size 1 1)
					(thickness 0.15)
				)
			)
		)
		(sheetname "PCIe redriver")
		(sheetfile "pcie_redriver.kicad_sch")
		(attr smd dnp)
		(fp_poly
			(pts
				(xy -0.925 -0.47) (xy 0.925 -0.47) (xy 0.925 0.47) (xy -0.925 0.47)
			)
			(stroke
				(width 0.05)
				(type default)
			)
			(fill no)
			(layer "F.CrtYd")
		)
		(fp_poly
			(pts
				(xy -0.5 -0.25) (xy 0.5 -0.25) (xy 0.5 0.25) (xy -0.5 0.25)
			)
			(stroke
				(width 0.15)
				(type solid)
			)
			(fill no)
			(layer "F.Fab")
		)
		(pad "1" smd roundrect
			(at -0.48 0 225)
			(size 0.59 0.64)
			(layers "F.Cu" "F.Mask" "F.Paste")
			(roundrect_rratio 0.25)
			(net 1 "GND")
			(pintype "passive")
			(teardrops
				(best_length_ratio 0.2)
				(max_length 1)
				(best_width_ratio 0.9)
				(max_width 2)
				(curved_edges yes)
				(filter_ratio 0.9)
				(enabled yes)
				(allow_two_segments yes)
				(prefer_zone_connections yes)
			)
		)
		(pad "2" smd roundrect
			(at 0.48 0 225)
			(size 0.59 0.64)
			(layers "F.Cu" "F.Mask" "F.Paste")
			(roundrect_rratio 0.25)
			(net 976 "/PCIe redriver/RX_EQ2")
			(pintype "passive")
			(teardrops
				(best_length_ratio 0.2)
				(max_length 1)
				(best_width_ratio 0.9)
				(max_width 2)
				(curved_edges yes)
				(filter_ratio 0.9)
				(enabled yes)
				(allow_two_segments yes)
				(prefer_zone_connections yes)
			)
		)
	)
	(footprint "antmicro-footprints:R_0402_1005Metric"
		(layer "F.Cu")
		(at 212.59 133.26 180)
		(descr "Resistor SMD 0402")
		(tags "resistor SMD 0402")
		(property "Reference" "R183"
			(at 0.79 -0.42 0)
			(layer "F.SilkS")
			(effects
				(font
					(size 0.7 0.7)
					(thickness 0.15)
				)
				(justify right bottom)
			)
		)
		(property "Value" "R_1k_0402"
			(at -1.011843 1.772047 0)
			(layer "F.Fab")
			(effects
				(font
					(size 0.7 0.7)
					(thickness 0.15)
				)
				(justify right bottom)
			)
		)
		(property "Datasheet" "https://www.bourns.com/docs/product-datasheets/cr.pdf"
			(at 0 0 180)
			(layer "F.Fab")
			(hide yes)
			(effects
				(font
					(size 1.27 1.27)
					(thickness 0.15)
				)
			)
		)
		(property "Author" "Antmicro"
			(at 425.18 266.52 0)
			(layer "F.Fab")
			(hide yes)
			(effects
				(font
					(size 1 1)
					(thickness 0.15)
				)
			)
		)
		(property "License" "Apache-2.0"
			(at 425.18 266.52 0)
			(layer "F.Fab")
			(hide yes)
			(effects
				(font
					(size 1 1)
					(thickness 0.15)
				)
			)
		)
		(property "MPN" "CR0402-FX-1001GLF"
			(at 425.18 266.52 0)
			(layer "F.Fab")
			(hide yes)
			(effects
				(font
					(size 1 1)
					(thickness 0.15)
				)
			)
		)
		(property "Manufacturer" "Bourns"
			(at 425.18 266.52 0)
			(layer "F.Fab")
			(hide yes)
			(effects
				(font
					(size 1 1)
					(thickness 0.15)
				)
			)
		)
		(property "Public" "False"
			(at 425.18 266.52 0)
			(layer "F.Fab")
			(hide yes)
			(effects
				(font
					(size 1 1)
					(thickness 0.15)
				)
			)
		)
		(property "Tolerance" "1%"
			(at 425.18 266.52 0)
			(layer "F.Fab")
			(hide yes)
			(effects
				(font
					(size 1 1)
					(thickness 0.15)
				)
			)
		)
		(property "Val" "1k"
			(at 425.18 266.52 0)
			(layer "F.Fab")
			(hide yes)
			(effects
				(font
					(size 1 1)
					(thickness 0.15)
				)
			)
		)
		(sheetname "PCIe misc")
		(sheetfile "pcie_misc.kicad_sch")
		(attr smd)
		(fp_rect
			(start -0.925 -0.47)
			(end 0.925 0.47)
			(stroke
				(width 0.05)
				(type default)
			)
			(fill no)
			(layer "F.CrtYd")
		)
		(fp_rect
			(start -0.5 -0.25)
			(end 0.5 0.25)
			(stroke
				(width 0.15)
				(type solid)
			)
			(fill no)
			(layer "F.Fab")
		)
		(pad "1" smd roundrect
			(at -0.48 0 180)
			(size 0.59 0.64)
			(layers "F.Cu" "F.Mask" "F.Paste")
			(roundrect_rratio 0.25)
			(net 603 "Net-(U37-~{OE1})")
			(pintype "passive")
			(teardrops
				(best_length_ratio 0.2)
				(max_length 1)
				(best_width_ratio 0.9)
				(max_width 2)
				(curved_edges yes)
				(filter_ratio 0.9)
				(enabled yes)
				(allow_two_segments yes)
				(prefer_zone_connections yes)
			)
		)
		(pad "2" smd roundrect
			(at 0.48 0 180)
			(size 0.59 0.64)
			(layers "F.Cu" "F.Mask" "F.Paste")
			(roundrect_rratio 0.25)
			(net 1 "GND")
			(pintype "passive")
			(teardrops
				(best_length_ratio 0.2)
				(max_length 1)
				(best_width_ratio 0.9)
				(max_width 2)
				(curved_edges yes)
				(filter_ratio 0.9)
				(enabled yes)
				(allow_two_segments yes)
				(prefer_zone_connections yes)
			)
		)
	)
	(footprint "antmicro-footprints:C_0603_1608Metric"
		(layer "F.Cu")
		(at 177.52 110.61)
		(descr "Capacitor SMD 0603")
		(tags "capacitor 0603")
		(property "Reference" "C74"
			(at -3.37 0.55 0)
			(layer "F.SilkS")
			(effects
				(font
					(size 0.7 0.7)
					(thickness 0.15)
				)
				(justify left bottom)
			)
		)
		(property "Value" "C_22u_16V_0603"
			(at -1.42757 1.770288 0)
			(layer "F.Fab")
			(effects
				(font
					(size 0.7 0.7)
					(thickness 0.15)
				)
				(justify left bottom)
			)
		)
		(property "Datasheet" "https://product.samsungsem.com/mlcc/CL10A226MO7JZN.do"
			(at 0 0 0)
			(layer "F.Fab")
			(hide yes)
			(effects
				(font
					(size 1.27 1.27)
					(thickness 0.15)
				)
			)
		)
		(property "Author" "Antmicro"
			(at 0 0 0)
			(layer "F.Fab")
			(hide yes)
			(effects
				(font
					(size 1 1)
					(thickness 0.15)
				)
			)
		)
		(property "Dielectric" ""
			(at 0 0 0)
			(layer "F.Fab")
			(hide yes)
			(effects
				(font
					(size 1 1)
					(thickness 0.15)
				)
			)
		)
		(property "License" "Apache-2.0"
			(at 0 0 0)
			(layer "F.Fab")
			(hide yes)
			(effects
				(font
					(size 1 1)
					(thickness 0.15)
				)
			)
		)
		(property "MPN" "CL10A226MO7JZNC"
			(at 0 0 0)
			(layer "F.Fab")
			(hide yes)
			(effects
				(font
					(size 1 1)
					(thickness 0.15)
				)
			)
		)
		(property "Manufacturer" "Samsung Electro-Mechanics"
			(at 0 0 0)
			(layer "F.Fab")
			(hide yes)
			(effects
				(font
					(size 1 1)
					(thickness 0.15)
				)
			)
		)
		(property "Public" "False"
			(at 0 0 0)
			(layer "F.Fab")
			(hide yes)
			(effects
				(font
					(size 1 1)
					(thickness 0.15)
				)
			)
		)
		(property "Val" "22u"
			(at 0 0 0)
			(layer "F.Fab")
			(hide yes)
			(effects
				(font
					(size 1 1)
					(thickness 0.15)
				)
			)
		)
		(property "Voltage" "16V"
			(at 0 0 0)
			(layer "F.Fab")
			(hide yes)
			(effects
				(font
					(size 1 1)
					(thickness 0.15)
				)
			)
		)
		(sheetname "M.2 key M #1")
		(sheetfile "m2keym_low.kicad_sch")
		(attr smd)
		(fp_line
			(start -0.15 -0.4)
			(end 0.15 -0.4)
			(stroke
				(width 0.15)
				(type solid)
			)
			(layer "F.SilkS")
		)
		(fp_line
			(start -0.15 0.4)
			(end 0.15 0.4)
			(stroke
				(width 0.15)
				(type solid)
			)
			(layer "F.SilkS")
		)
		(fp_rect
			(start -1.25 -0.65)
			(end 1.25 0.65)
			(stroke
				(width 0.05)
				(type solid)
			)
			(fill no)
			(layer "F.CrtYd")
		)
		(fp_rect
			(start -0.8 -0.4)
			(end 0.8 0.4)
			(stroke
				(width 0.15)
				(type solid)
			)
			(fill no)
			(layer "F.Fab")
		)
		(pad "1" smd roundrect
			(at -0.7 0)
			(size 0.8 1)
			(layers "F.Cu" "F.Mask" "F.Paste")
			(roundrect_rratio 0.2)
			(net 1 "GND")
			(pintype "passive")
			(teardrops
				(best_length_ratio 0.2)
				(max_length 1)
				(best_width_ratio 0.9)
				(max_width 2)
				(curved_edges yes)
				(filter_ratio 0.9)
				(enabled yes)
				(allow_two_segments yes)
				(prefer_zone_connections yes)
			)
		)
		(pad "2" smd roundrect
			(at 0.7 0)
			(size 0.8 1)
			(layers "F.Cu" "F.Mask" "F.Paste")
			(roundrect_rratio 0.2)
			(net 969 "/M.2 key M #1/M2_3V3")
			(pintype "passive")
			(teardrops
				(best_length_ratio 0.2)
				(max_length 1)
				(best_width_ratio 0.9)
				(max_width 2)
				(curved_edges yes)
				(filter_ratio 0.9)
				(enabled yes)
				(allow_two_segments yes)
				(prefer_zone_connections yes)
			)
		)
	)
	(footprint "antmicro-footprints:R_0402_1005Metric"
		(layer "F.Cu")
		(at 239.000001 78.5 90)
		(descr "Resistor SMD 0402")
		(tags "resistor SMD 0402")
		(property "Reference" "R163"
			(at -1.1 -0.400001 90)
			(layer "F.SilkS")
			(effects
				(font
					(size 0.7 0.7)
					(thickness 0.15)
				)
				(justify right top)
			)
		)
		(property "Value" "R_5k1_0402"
			(at -4.236842 54.437047 90)
			(layer "F.Fab")
			(hide yes)
			(effects
				(font
					(size 0.7 0.7)
					(thickness 0.15)
				)
				(justify left bottom)
			)
		)
		(property "Datasheet" "https://www.bourns.com/docs/product-datasheets/cr.pdf"
			(at 0 0 90)
			(layer "F.Fab")
			(hide yes)
			(effects
				(font
					(size 1.27 1.27)
					(thickness 0.15)
				)
			)
		)
		(property "Author" "Antmicro"
			(at 0 0 90)
			(layer "F.Fab")
			(hide yes)
			(effects
				(font
					(size 1 1)
					(thickness 0.15)
				)
			)
		)
		(property "License" "Apache-2.0"
			(at 0 0 90)
			(layer "F.Fab")
			(hide yes)
			(effects
				(font
					(size 1 1)
					(thickness 0.15)
				)
			)
		)
		(property "MPN" "CR0402-FX-5101GLF"
			(at 0 0 90)
			(layer "F.Fab")
			(hide yes)
			(effects
				(font
					(size 1 1)
					(thickness 0.15)
				)
			)
		)
		(property "Manufacturer" "Bourns"
			(at 0 0 90)
			(layer "F.Fab")
			(hide yes)
			(effects
				(font
					(size 1 1)
					(thickness 0.15)
				)
			)
		)
		(property "Public" "False"
			(at 0 0 90)
			(layer "F.Fab")
			(hide yes)
			(effects
				(font
					(size 1 1)
					(thickness 0.15)
				)
			)
		)
		(property "Tolerance" "1%"
			(at 0 0 90)
			(layer "F.Fab")
			(hide yes)
			(effects
				(font
					(size 1 1)
					(thickness 0.15)
				)
			)
		)
		(property "Val" "5k1"
			(at 0 0 90)
			(layer "F.Fab")
			(hide yes)
			(effects
				(font
					(size 1 1)
					(thickness 0.15)
				)
			)
		)
		(sheetname "Com Express 7 MGMT")
		(sheetfile "com_express_7_mgmt.kicad_sch")
		(attr smd)
		(fp_rect
			(start -0.925 -0.47)
			(end 0.925 0.47)
			(stroke
				(width 0.05)
				(type default)
			)
			(fill no)
			(layer "F.CrtYd")
		)
		(fp_rect
			(start -0.5 -0.25)
			(end 0.5 0.25)
			(stroke
				(width 0.15)
				(type solid)
			)
			(fill no)
			(layer "F.Fab")
		)
		(pad "1" smd roundrect
			(at -0.48 0 90)
			(size 0.59 0.64)
			(layers "F.Cu" "F.Mask" "F.Paste")
			(roundrect_rratio 0.25)
			(net 401 "/Com Express 7 MGMT/FAM_TACH")
			(pintype "passive")
			(teardrops
				(best_length_ratio 0.2)
				(max_length 1)
				(best_width_ratio 0.9)
				(max_width 2)
				(curved_edges yes)
				(filter_ratio 0.9)
				(enabled yes)
				(allow_two_segments yes)
				(prefer_zone_connections yes)
			)
		)
		(pad "2" smd roundrect
			(at 0.48 0 90)
			(size 0.59 0.64)
			(layers "F.Cu" "F.Mask" "F.Paste")
			(roundrect_rratio 0.25)
			(net 2 "+3V3")
			(pintype "passive")
			(teardrops
				(best_length_ratio 0.2)
				(max_length 1)
				(best_width_ratio 0.9)
				(max_width 2)
				(curved_edges yes)
				(filter_ratio 0.9)
				(enabled yes)
				(allow_two_segments yes)
				(prefer_zone_connections yes)
			)
		)
	)
	(footprint "antmicro-footprints:R_0402_1005Metric"
		(layer "F.Cu")
		(at 189.347802 138.065006 -135)
		(descr "Resistor SMD 0402")
		(tags "resistor SMD 0402")
		(property "Reference" "R230"
			(at 1.069205 -0.465818 45)
			(layer "F.SilkS")
			(effects
				(font
					(size 0.7 0.7)
					(thickness 0.15)
				)
				(justify right bottom)
			)
		)
		(property "Value" "R_1k_0402"
			(at -1.011843 1.772046 45)
			(layer "F.Fab")
			(effects
				(font
					(size 0.7 0.7)
					(thickness 0.15)
				)
				(justify right bottom)
			)
		)
		(property "Datasheet" "https://www.bourns.com/docs/product-datasheets/cr.pdf"
			(at 0 0 45)
			(layer "B.Fab")
			(hide yes)
			(effects
				(font
					(size 1.27 1.27)
					(thickness 0.15)
				)
				(justify mirror)
			)
		)
		(property "Author" "Antmicro"
			(at 0 0 45)
			(layer "F.Fab")
			(hide yes)
			(effects
				(font
					(size 1 1)
					(thickness 0.15)
				)
			)
		)
		(property "License" "Apache-2.0"
			(at 0 0 45)
			(layer "F.Fab")
			(hide yes)
			(effects
				(font
					(size 1 1)
					(thickness 0.15)
				)
			)
		)
		(property "MPN" "CR0402-FX-1001GLF"
			(at 0 0 45)
			(layer "F.Fab")
			(hide yes)
			(effects
				(font
					(size 1 1)
					(thickness 0.15)
				)
			)
		)
		(property "Manufacturer" "Bourns"
			(at 0 0 45)
			(layer "F.Fab")
			(hide yes)
			(effects
				(font
					(size 1 1)
					(thickness 0.15)
				)
			)
		)
		(property "Public" "False"
			(at 0 0 45)
			(layer "F.Fab")
			(hide yes)
			(effects
				(font
					(size 1 1)
					(thickness 0.15)
				)
			)
		)
		(property "Tolerance" "1%"
			(at 0 0 45)
			(layer "F.Fab")
			(hide yes)
			(effects
				(font
					(size 1 1)
					(thickness 0.15)
				)
			)
		)
		(property "Val" "1k"
			(at 0 0 45)
			(layer "F.Fab")
			(hide yes)
			(effects
				(font
					(size 1 1)
					(thickness 0.15)
				)
			)
		)
		(sheetname "PCIe redriver")
		(sheetfile "pcie_redriver.kicad_sch")
		(attr smd dnp)
		(fp_poly
			(pts
				(xy -0.925 -0.47) (xy 0.925 -0.47) (xy 0.925 0.47) (xy -0.925 0.47)
			)
			(stroke
				(width 0.05)
				(type default)
			)
			(fill no)
			(layer "F.CrtYd")
		)
		(fp_poly
			(pts
				(xy -0.5 -0.25) (xy 0.5 -0.25) (xy 0.5 0.25) (xy -0.5 0.25)
			)
			(stroke
				(width 0.15)
				(type solid)
			)
			(fill no)
			(layer "F.Fab")
		)
		(pad "1" smd roundrect
			(at -0.48 0 225)
			(size 0.59 0.64)
			(layers "F.Cu" "F.Mask" "F.Paste")
			(roundrect_rratio 0.25)
			(net 1 "GND")
			(pintype "passive")
			(teardrops
				(best_length_ratio 0.2)
				(max_length 1)
				(best_width_ratio 0.9)
				(max_width 2)
				(curved_edges yes)
				(filter_ratio 0.9)
				(enabled yes)
				(allow_two_segments yes)
				(prefer_zone_connections yes)
			)
		)
		(pad "2" smd roundrect
			(at 0.48 0 225)
			(size 0.59 0.64)
			(layers "F.Cu" "F.Mask" "F.Paste")
			(roundrect_rratio 0.25)
			(net 978 "/PCIe redriver/RX_EQ0")
			(pintype "passive")
			(teardrops
				(best_length_ratio 0.2)
				(max_length 1)
				(best_width_ratio 0.9)
				(max_width 2)
				(curved_edges yes)
				(filter_ratio 0.9)
				(enabled yes)
				(allow_two_segments yes)
				(prefer_zone_connections yes)
			)
		)
	)
	(footprint "antmicro-footprints:TP_SMD_0.75mm"
		(layer "F.Cu")
		(at 154.4 128.71)
		(property "Reference" "TP66"
			(at 0.4 -3.3 90)
			(layer "F.SilkS")
			(effects
				(font
					(size 0.7 0.7)
					(thickness 0.15)
				)
				(justify left bottom)
			)
		)
		(property "Value" "TP_0.75mm_SMD"
			(at 0 1.2 0)
			(layer "F.Fab")
			(effects
				(font
					(size 0.7 0.7)
					(thickness 0.15)
				)
				(justify left bottom)
			)
		)
		(property "Author" "Antmicro"
			(at 0 0 0)
			(layer "F.Fab")
			(hide yes)
			(effects
				(font
					(size 1 1)
					(thickness 0.15)
				)
			)
		)
		(property "License" "Apache-2.0"
			(at 0 0 0)
			(layer "F.Fab")
			(hide yes)
			(effects
				(font
					(size 1 1)
					(thickness 0.15)
				)
			)
		)
		(property "MPN" ""
			(at 0 0 0)
			(layer "F.Fab")
			(hide yes)
			(effects
				(font
					(size 1 1)
					(thickness 0.15)
				)
			)
		)
		(property "Manufacturer" ""
			(at 0 0 0)
			(layer "F.Fab")
			(hide yes)
			(effects
				(font
					(size 1 1)
					(thickness 0.15)
				)
			)
		)
		(property "Public" "False"
			(at 0 0 0)
			(layer "F.Fab")
			(hide yes)
			(effects
				(font
					(size 1 1)
					(thickness 0.15)
				)
			)
		)
		(sheetname "KR to SFI #1")
		(sheetfile "kr_sfi.kicad_sch")
		(attr exclude_from_pos_files exclude_from_bom)
		(fp_circle
			(center 0 0)
			(end 0.475 0)
			(stroke
				(width 0.05)
				(type default)
			)
			(fill no)
			(layer "F.CrtYd")
		)
		(pad "1" smd circle
			(at 0 0)
			(size 0.75 0.75)
			(layers "F.Cu" "F.Mask")
			(net 729 "Net-(U43C-AMUXB)")
			(pinfunction "1")
			(pintype "passive")
			(teardrops
				(best_length_ratio 0.4)
				(max_length 1)
				(best_width_ratio 0.9)
				(max_width 2)
				(curved_edges yes)
				(filter_ratio 0.9)
				(enabled yes)
				(allow_two_segments yes)
				(prefer_zone_connections yes)
			)
		)
	)
	(footprint "antmicro-footprints:C_0402_1005Metric"
		(layer "F.Cu")
		(at 143 141.86)
		(descr "Capacitor SMD 0402")
		(tags "capacitor SMD 0402")
		(property "Reference" "C152"
			(at -3.55 0.4 0)
			(layer "F.SilkS")
			(effects
				(font
					(size 0.7 0.7)
					(thickness 0.15)
				)
				(justify left bottom)
			)
		)
		(property "Value" "C_100n_0402"
			(at -1.022927 2.155213 0)
			(layer "F.Fab")
			(effects
				(font
					(size 0.7 0.7)
					(thickness 0.15)
				)
				(justify left bottom)
			)
		)
		(property "Datasheet" "https://www.murata.com/products/productdetail?partno=GRM155R61H104KE14%23"
			(at 0 0 0)
			(layer "F.Fab")
			(hide yes)
			(effects
				(font
					(size 1.27 1.27)
					(thickness 0.15)
				)
			)
		)
		(property "Author" "Antmicro"
			(at 0 0 0)
			(layer "F.Fab")
			(hide yes)
			(effects
				(font
					(size 1 1)
					(thickness 0.15)
				)
			)
		)
		(property "Dielectric" "X5R"
			(at 0 0 0)
			(layer "F.Fab")
			(hide yes)
			(effects
				(font
					(size 1 1)
					(thickness 0.15)
				)
			)
		)
		(property "License" "Apache-2.0"
			(at 0 0 0)
			(layer "F.Fab")
			(hide yes)
			(effects
				(font
					(size 1 1)
					(thickness 0.15)
				)
			)
		)
		(property "MPN" "GRM155R61H104KE14D"
			(at 0 0 0)
			(layer "F.Fab")
			(hide yes)
			(effects
				(font
					(size 1 1)
					(thickness 0.15)
				)
			)
		)
		(property "Manufacturer" "Murata"
			(at 0 0 0)
			(layer "F.Fab")
			(hide yes)
			(effects
				(font
					(size 1 1)
					(thickness 0.15)
				)
			)
		)
		(property "Public" "False"
			(at 0 0 0)
			(layer "F.Fab")
			(hide yes)
			(effects
				(font
					(size 1 1)
					(thickness 0.15)
				)
			)
		)
		(property "Val" "100n"
			(at 0 0 0)
			(layer "F.Fab")
			(hide yes)
			(effects
				(font
					(size 1 1)
					(thickness 0.15)
				)
			)
		)
		(property "Voltage" "50V"
			(at 0 0 0)
			(layer "F.Fab")
			(hide yes)
			(effects
				(font
					(size 1 1)
					(thickness 0.15)
				)
			)
		)
		(sheetname "KR to SFI #1")
		(sheetfile "kr_sfi.kicad_sch")
		(attr smd)
		(fp_rect
			(start -0.925 -0.47)
			(end 0.925 0.47)
			(stroke
				(width 0.05)
				(type default)
			)
			(fill no)
			(layer "F.CrtYd")
		)
		(fp_line
			(start -0.494 -0.25)
			(end 0.504 -0.25)
			(stroke
				(width 0.15)
				(type solid)
			)
			(layer "F.Fab")
		)
		(fp_line
			(start -0.494 0.248)
			(end -0.494 -0.25)
			(stroke
				(width 0.15)
				(type solid)
			)
			(layer "F.Fab")
		)
		(fp_line
			(start 0.504 -0.25)
			(end 0.504 0.248)
			(stroke
				(width 0.15)
				(type solid)
			)
			(layer "F.Fab")
		)
		(fp_line
			(start 0.504 0.248)
			(end -0.494 0.248)
			(stroke
				(width 0.15)
				(type solid)
			)
			(layer "F.Fab")
		)
		(pad "1" smd roundrect
			(at -0.48 0)
			(size 0.59 0.64)
			(layers "F.Cu" "F.Mask" "F.Paste")
			(roundrect_rratio 0.25)
			(net 107 "/2xSFP+/KR to SFI #1/CLK+")
			(pintype "passive")
			(teardrops
				(best_length_ratio 0.2)
				(max_length 1)
				(best_width_ratio 0.9)
				(max_width 2)
				(curved_edges yes)
				(filter_ratio 0.9)
				(enabled yes)
				(allow_two_segments yes)
				(prefer_zone_connections yes)
			)
		)
		(pad "2" smd roundrect
			(at 0.48 0)
			(size 0.59 0.64)
			(layers "F.Cu" "F.Mask" "F.Paste")
			(roundrect_rratio 0.25)
			(net 110 "/2xSFP+/KR to SFI #1/REFCLK-")
			(pintype "passive")
			(teardrops
				(best_length_ratio 0.2)
				(max_length 1)
				(best_width_ratio 0.9)
				(max_width 2)
				(curved_edges yes)
				(filter_ratio 0.9)
				(enabled yes)
				(allow_two_segments yes)
				(prefer_zone_connections yes)
			)
		)
	)
	(footprint "antmicro-footprints:F_1206_3216Metric"
		(layer "F.Cu")
		(at 298.9 142.21 180)
		(property "Reference" "F3"
			(at -0.7 1.2 0)
			(layer "F.SilkS")
			(effects
				(font
					(size 0.7 0.7)
					(thickness 0.15)
				)
				(justify right bottom)
			)
		)
		(property "Value" "PTC_4.5A_1206"
			(at 0 2 0)
			(layer "F.Fab")
			(effects
				(font
					(size 0.7 0.7)
					(thickness 0.15)
				)
				(justify right bottom)
			)
		)
		(property "Datasheet" "http://www.farnell.com/datasheets/2282556.pdf"
			(at 0 0 180)
			(layer "F.Fab")
			(hide yes)
			(effects
				(font
					(size 1.27 1.27)
					(thickness 0.15)
				)
			)
		)
		(property "Author" "Antmicro"
			(at 597.8 284.42 0)
			(layer "F.Fab")
			(hide yes)
			(effects
				(font
					(size 1 1)
					(thickness 0.15)
				)
			)
		)
		(property "License" "Apache-2.0"
			(at 597.8 284.42 0)
			(layer "F.Fab")
			(hide yes)
			(effects
				(font
					(size 1 1)
					(thickness 0.15)
				)
			)
		)
		(property "MPN" "1206L450SLWR"
			(at 597.8 284.42 0)
			(layer "F.Fab")
			(hide yes)
			(effects
				(font
					(size 1 1)
					(thickness 0.15)
				)
			)
		)
		(property "Manufacturer" "Littelfuse"
			(at 597.8 284.42 0)
			(layer "F.Fab")
			(hide yes)
			(effects
				(font
					(size 1 1)
					(thickness 0.15)
				)
			)
		)
		(sheetname "Misc")
		(sheetfile "misc.kicad_sch")
		(attr smd)
		(fp_line
			(start 0.8 0.901)
			(end -0.8 0.901)
			(stroke
				(width 0.15)
				(type solid)
			)
			(layer "F.SilkS")
		)
		(fp_line
			(start 0.8 -0.899)
			(end -0.8 -0.899)
			(stroke
				(width 0.15)
				(type solid)
			)
			(layer "F.SilkS")
		)
		(fp_rect
			(start -2.325 -1.15)
			(end 2.325 1.15)
			(stroke
				(width 0.05)
				(type default)
			)
			(fill no)
			(layer "F.CrtYd")
		)
		(fp_line
			(start 1.624 0.792)
			(end -1.677 0.792)
			(stroke
				(width 0.15)
				(type solid)
			)
			(layer "F.Fab")
		)
		(fp_line
			(start 1.624 -0.861)
			(end 1.624 0.792)
			(stroke
				(width 0.15)
				(type solid)
			)
			(layer "F.Fab")
		)
		(fp_line
			(start -1.677 0.792)
			(end -1.677 -0.861)
			(stroke
				(width 0.15)
				(type solid)
			)
			(layer "F.Fab")
		)
		(fp_line
			(start -1.677 -0.861)
			(end 1.624 -0.861)
			(stroke
				(width 0.15)
				(type solid)
			)
			(layer "F.Fab")
		)
		(pad "1" smd roundrect
			(at -1.5 0.001 180)
			(size 1.15 1.8)
			(layers "F.Cu" "F.Mask" "F.Paste")
			(roundrect_rratio 0.25)
			(net 65 "+12V")
			(pintype "passive")
			(teardrops
				(best_length_ratio 0.2)
				(max_length 1)
				(best_width_ratio 0.9)
				(max_width 2)
				(curved_edges yes)
				(filter_ratio 0.9)
				(enabled yes)
				(allow_two_segments yes)
				(prefer_zone_connections yes)
			)
		)
		(pad "2" smd roundrect
			(at 1.5 0.001 180)
			(size 1.15 1.8)
			(layers "F.Cu" "F.Mask" "F.Paste")
			(roundrect_rratio 0.25)
			(net 81 "/Misc/FAN_12V")
			(pintype "passive")
			(teardrops
				(best_length_ratio 0.2)
				(max_length 1)
				(best_width_ratio 0.9)
				(max_width 2)
				(curved_edges yes)
				(filter_ratio 0.9)
				(enabled yes)
				(allow_two_segments yes)
				(prefer_zone_connections yes)
			)
		)
	)
	(footprint "antmicro-footprints:Choke_0805_2012Metric"
		(layer "F.Cu")
		(at 127.25 101.61 180)
		(property "Reference" "T4"
			(at 1.65 -1.85 0)
			(unlocked yes)
			(layer "F.SilkS")
			(effects
				(font
					(size 0.7 0.7)
					(thickness 0.15)
				)
				(justify left bottom)
			)
		)
		(property "Value" "Choke_SRF2012A-801Y"
			(at 0 -7 180)
			(unlocked yes)
			(layer "F.Fab")
			(effects
				(font
					(size 0.7 0.7)
					(thickness 0.15)
				)
				(justify left bottom)
			)
		)
		(property "Datasheet" "https://www.bourns.com/docs/product-datasheets/srf2012a-801y.pdf"
			(at 0 0 180)
			(layer "F.Fab")
			(hide yes)
			(effects
				(font
					(size 1.27 1.27)
					(thickness 0.15)
				)
			)
		)
		(property "Author" "Antmicro"
			(at 254.5 203.22 0)
			(layer "F.Fab")
			(hide yes)
			(effects
				(font
					(size 1 1)
					(thickness 0.15)
				)
			)
		)
		(property "IMax" "0.3 A"
			(at 254.5 203.22 0)
			(layer "F.Fab")
			(hide yes)
			(effects
				(font
					(size 1 1)
					(thickness 0.15)
				)
			)
		)
		(property "License" "Apache-2.0"
			(at 254.5 203.22 0)
			(layer "F.Fab")
			(hide yes)
			(effects
				(font
					(size 1 1)
					(thickness 0.15)
				)
			)
		)
		(property "MPN" "SRF2012A-801Y"
			(at 254.5 203.22 0)
			(layer "F.Fab")
			(hide yes)
			(effects
				(font
					(size 1 1)
					(thickness 0.15)
				)
			)
		)
		(property "Manufacturer" "Bourns"
			(at 254.5 203.22 0)
			(layer "F.Fab")
			(hide yes)
			(effects
				(font
					(size 1 1)
					(thickness 0.15)
				)
			)
		)
		(property "Public" "False"
			(at 254.5 203.22 0)
			(layer "F.Fab")
			(hide yes)
			(effects
				(font
					(size 1 1)
					(thickness 0.15)
				)
			)
		)
		(property ki_fp_filters "IND_ACM9070_TDK")
		(sheetname "2xUSB3.0+RJ45")
		(sheetfile "usb3+rj45.kicad_sch")
		(attr smd)
		(fp_rect
			(start -1.5 -0.9)
			(end 1.5 0.9)
			(stroke
				(width 0.05)
				(type solid)
			)
			(fill no)
			(layer "F.CrtYd")
		)
		(pad "1" smd roundrect
			(at -0.96 -0.46 180)
			(size 0.675 0.475)
			(layers "F.Cu" "F.Mask" "F.Paste")
			(roundrect_rratio 0.25)
			(net 695 "/2xUSB3.0+RJ45/DD_FL+")
			(pinfunction "1")
			(pintype "passive")
			(teardrops
				(best_length_ratio 0.2)
				(max_length 1)
				(best_width_ratio 0.9)
				(max_width 2)
				(curved_edges yes)
				(filter_ratio 0.9)
				(enabled yes)
				(allow_two_segments yes)
				(prefer_zone_connections yes)
			)
		)
		(pad "2" smd roundrect
			(at 0.96 -0.46 180)
			(size 0.675 0.475)
			(layers "F.Cu" "F.Mask" "F.Paste")
			(roundrect_rratio 0.25)
			(net 152 "/2xUSB3.0+RJ45/DD+")
			(pinfunction "2")
			(pintype "passive")
			(teardrops
				(best_length_ratio 0.2)
				(max_length 1)
				(best_width_ratio 0.9)
				(max_width 2)
				(curved_edges yes)
				(filter_ratio 0.9)
				(enabled yes)
				(allow_two_segments yes)
				(prefer_zone_connections yes)
			)
		)
		(pad "3" smd roundrect
			(at 0.96 0.46 180)
			(size 0.675 0.475)
			(layers "F.Cu" "F.Mask" "F.Paste")
			(roundrect_rratio 0.25)
			(net 153 "/2xUSB3.0+RJ45/DD-")
			(pinfunction "3")
			(pintype "passive")
			(teardrops
				(best_length_ratio 0.2)
				(max_length 1)
				(best_width_ratio 0.9)
				(max_width 2)
				(curved_edges yes)
				(filter_ratio 0.9)
				(enabled yes)
				(allow_two_segments yes)
				(prefer_zone_connections yes)
			)
		)
		(pad "4" smd roundrect
			(at -0.96 0.46 180)
			(size 0.675 0.475)
			(layers "F.Cu" "F.Mask" "F.Paste")
			(roundrect_rratio 0.25)
			(net 696 "/2xUSB3.0+RJ45/DD_FL-")
			(pinfunction "4")
			(pintype "passive")
			(teardrops
				(best_length_ratio 0.2)
				(max_length 1)
				(best_width_ratio 0.9)
				(max_width 2)
				(curved_edges yes)
				(filter_ratio 0.9)
				(enabled yes)
				(allow_two_segments yes)
				(prefer_zone_connections yes)
			)
		)
	)
	(footprint "antmicro-footprints:R_0201"
		(layer "F.Cu")
		(at 138.172 147.935 -90)
		(descr "Resistor SMD 0201")
		(tags "resistor SMD 0201")
		(property "Reference" "R288"
			(at 6.476 -0.578 270)
			(layer "F.SilkS")
			(effects
				(font
					(size 0.7 0.7)
					(thickness 0.15)
				)
				(justify left bottom)
			)
		)
		(property "Value" "R_0R_0201"
			(at 0 1.25 270)
			(layer "F.Fab")
			(effects
				(font
					(size 0.7 0.7)
					(thickness 0.15)
				)
				(justify left bottom)
			)
		)
		(property "Datasheet" "https://www.bourns.com/docs/product-datasheets/cr.pdf"
			(at 0 0 270)
			(layer "F.Fab")
			(hide yes)
			(effects
				(font
					(size 1.27 1.27)
					(thickness 0.15)
				)
			)
		)
		(property "Author" "Antmicro"
			(at -9.763 286.107 0)
			(layer "F.Fab")
			(hide yes)
			(effects
				(font
					(size 1 1)
					(thickness 0.15)
				)
			)
		)
		(property "License" "Apache-2.0"
			(at -9.763 286.107 0)
			(layer "F.Fab")
			(hide yes)
			(effects
				(font
					(size 1 1)
					(thickness 0.15)
				)
			)
		)
		(property "MPN" "CR0201-FX-0R00GLF"
			(at -9.763 286.107 0)
			(layer "F.Fab")
			(hide yes)
			(effects
				(font
					(size 1 1)
					(thickness 0.15)
				)
			)
		)
		(property "Manufacturer" "Bourns"
			(at -9.763 286.107 0)
			(layer "F.Fab")
			(hide yes)
			(effects
				(font
					(size 1 1)
					(thickness 0.15)
				)
			)
		)
		(property "Tolerance" "1%"
			(at -9.763 286.107 0)
			(layer "F.Fab")
			(hide yes)
			(effects
				(font
					(size 1 1)
					(thickness 0.15)
				)
			)
		)
		(property "Val" "0R"
			(at -9.763 286.107 0)
			(layer "F.Fab")
			(hide yes)
			(effects
				(font
					(size 1 1)
					(thickness 0.15)
				)
			)
		)
		(sheetname "KR to SFI #2")
		(sheetfile "kr_sfi.kicad_sch")
		(attr smd dnp)
		(fp_rect
			(start -0.7 -0.35)
			(end 0.7 0.35)
			(stroke
				(width 0.05)
				(type default)
			)
			(fill no)
			(layer "F.CrtYd")
		)
		(fp_rect
			(start -0.3 -0.15)
			(end 0.298 0.148)
			(stroke
				(width 0.15)
				(type solid)
			)
			(fill no)
			(layer "F.Fab")
		)
		(pad "" smd roundrect
			(at -0.346 0 270)
			(size 0.318 0.36)
			(layers "F.Paste")
			(roundrect_rratio 0.25)
			(teardrops
				(best_length_ratio 0.2)
				(max_length 1)
				(best_width_ratio 0.9)
				(max_width 2)
				(curved_edges yes)
				(filter_ratio 0.9)
				(enabled yes)
				(allow_two_segments yes)
				(prefer_zone_connections yes)
			)
		)
		(pad "" smd roundrect
			(at 0.344 0 270)
			(size 0.318 0.36)
			(layers "F.Paste")
			(roundrect_rratio 0.25)
			(teardrops
				(best_length_ratio 0.2)
				(max_length 1)
				(best_width_ratio 0.9)
				(max_width 2)
				(curved_edges yes)
				(filter_ratio 0.9)
				(enabled yes)
				(allow_two_segments yes)
				(prefer_zone_connections yes)
			)
		)
		(pad "1" smd roundrect
			(at -0.32 0 270)
			(size 0.46 0.4)
			(layers "F.Cu" "F.Mask")
			(roundrect_rratio 0.25)
			(net 121 "/2xSFP+/10GKR_SFP1.TX-")
			(pintype "passive")
			(teardrops
				(best_length_ratio 0.2)
				(max_length 1)
				(best_width_ratio 0.9)
				(max_width 2)
				(curved_edges yes)
				(filter_ratio 0.9)
				(enabled yes)
				(allow_two_segments yes)
				(prefer_zone_connections yes)
			)
		)
		(pad "2" smd roundrect
			(at 0.32 0 270)
			(size 0.46 0.4)
			(layers "F.Cu" "F.Mask")
			(roundrect_rratio 0.25)
			(net 951 "/2xSFP+/KR to SFI #2/BYP_TX-")
			(pintype "passive")
			(teardrops
				(best_length_ratio 0.2)
				(max_length 1)
				(best_width_ratio 0.9)
				(max_width 2)
				(curved_edges yes)
				(filter_ratio 0.9)
				(enabled yes)
				(allow_two_segments yes)
				(prefer_zone_connections yes)
			)
		)
	)
	(footprint "antmicro-footprints:LED_0603_1608Metric_G"
		(layer "F.Cu")
		(at 110.9 69.86 90)
		(descr "LED SMD 0603 Green")
		(tags "LED SMD 0603 Green")
		(property "Reference" "D12"
			(at -3.45 0.4 90)
			(layer "F.SilkS")
			(effects
				(font
					(size 0.7 0.7)
					(thickness 0.15)
				)
				(justify left bottom)
			)
		)
		(property "Value" "LED_G_0603_LTST-C190GKT"
			(at -0.001 1.599 90)
			(layer "F.Fab")
			(effects
				(font
					(size 0.7 0.7)
					(thickness 0.15)
				)
				(justify left bottom)
			)
		)
		(property "Datasheet" "https://media.digikey.com/pdf/Data%20Sheets/Lite-On%20PDFs/LTST-C190GKT.pdf"
			(at 0 0 90)
			(layer "F.Fab")
			(hide yes)
			(effects
				(font
					(size 1.27 1.27)
					(thickness 0.15)
				)
			)
		)
		(property "Author" "Antmicro"
			(at 180.76 -41.04 0)
			(layer "F.Fab")
			(hide yes)
			(effects
				(font
					(size 1 1)
					(thickness 0.15)
				)
			)
		)
		(property "Color" "Green"
			(at 180.76 -41.04 0)
			(layer "F.Fab")
			(hide yes)
			(effects
				(font
					(size 1 1)
					(thickness 0.15)
				)
			)
		)
		(property "License" "Apache-2.0"
			(at 180.76 -41.04 0)
			(layer "F.Fab")
			(hide yes)
			(effects
				(font
					(size 1 1)
					(thickness 0.15)
				)
			)
		)
		(property "MPN" "LTST-C190GKT"
			(at 180.76 -41.04 0)
			(layer "F.Fab")
			(hide yes)
			(effects
				(font
					(size 1 1)
					(thickness 0.15)
				)
			)
		)
		(property "Manufacturer" "Lite-On"
			(at 180.76 -41.04 0)
			(layer "F.Fab")
			(hide yes)
			(effects
				(font
					(size 1 1)
					(thickness 0.15)
				)
			)
		)
		(property "Public" "False"
			(at 180.76 -41.04 0)
			(layer "F.Fab")
			(hide yes)
			(effects
				(font
					(size 1 1)
					(thickness 0.15)
				)
			)
		)
		(sheetname "USB-C console")
		(sheetfile "usb-c_console.kicad_sch")
		(attr smd)
		(fp_line
			(start 0.22 -0.35)
			(end -0.22 -0.35)
			(stroke
				(width 0.15)
				(type solid)
			)
			(layer "F.SilkS")
		)
		(fp_line
			(start -1.18 -0.319)
			(end -1.18 0.321)
			(stroke
				(width 0.15)
				(type solid)
			)
			(layer "F.SilkS")
		)
		(fp_line
			(start 0.105328 0.001008)
			(end 0.24 0.001)
			(stroke
				(width 0.1)
				(type solid)
			)
			(layer "F.SilkS")
		)
		(fp_line
			(start -0.094672 0.001008)
			(end 0.105328 -0.198992)
			(stroke
				(width 0.1)
				(type solid)
			)
			(layer "F.SilkS")
		)
		(fp_line
			(start -0.094672 0.001008)
			(end -0.24 0.001008)
			(stroke
				(width 0.1)
				(type solid)
			)
			(layer "F.SilkS")
		)
		(fp_line
			(start 0.105328 0.201008)
			(end 0.105328 -0.198992)
			(stroke
				(width 0.1)
				(type solid)
			)
			(layer "F.SilkS")
		)
		(fp_line
			(start 0.105328 0.201008)
			(end -0.094672 0.001008)
			(stroke
				(width 0.1)
				(type solid)
			)
			(layer "F.SilkS")
		)
		(fp_line
			(start -0.094672 0.201008)
			(end -0.094672 -0.198992)
			(stroke
				(width 0.1)
				(type solid)
			)
			(layer "F.SilkS")
		)
		(fp_line
			(start 0.22 0.35)
			(end -0.22 0.35)
			(stroke
				(width 0.15)
				(type solid)
			)
			(layer "F.SilkS")
		)
		(fp_rect
			(start 1.25 0.65)
			(end -1.25 -0.65)
			(stroke
				(width 0.05)
				(type solid)
			)
			(fill no)
			(layer "F.CrtYd")
		)
		(fp_line
			(start 0.201 -0.202)
			(end -0.101 0)
			(stroke
				(width 0.15)
				(type solid)
			)
			(layer "F.Fab")
		)
		(fp_line
			(start -0.199 -0.202)
			(end -0.199 0.1)
			(stroke
				(width 0.15)
				(type solid)
			)
			(layer "F.Fab")
		)
		(fp_line
			(start 0.599 0)
			(end 0.201 0)
			(stroke
				(width 0.15)
				(type solid)
			)
			(layer "F.Fab")
		)
		(fp_line
			(start 0.201 0)
			(end 0.201 -0.202)
			(stroke
				(width 0.15)
				(type solid)
			)
			(layer "F.Fab")
		)
		(fp_line
			(start -0.101 0)
			(end 0.201 0.2)
			(stroke
				(width 0.15)
				(type solid)
			)
			(layer "F.Fab")
		)
		(fp_line
			(start -0.199 0)
			(end -0.597 0)
			(stroke
				(width 0.15)
				(type solid)
			)
			(layer "F.Fab")
		)
		(fp_line
			(start 0.201 0.2)
			(end 0.201 0)
			(stroke
				(width 0.15)
				(type solid)
			)
			(layer "F.Fab")
		)
		(fp_line
			(start -0.199 0.2)
			(end -0.199 0.1)
			(stroke
				(width 0.15)
				(type solid)
			)
			(layer "F.Fab")
		)
		(fp_rect
			(start 0.848 0.4)
			(end -0.85 -0.402)
			(stroke
				(width 0.15)
				(type solid)
			)
			(fill no)
			(layer "F.Fab")
		)
		(pad "1" smd roundrect
			(at -0.7 0 270)
			(size 0.8 1)
			(layers "F.Cu" "F.Mask" "F.Paste")
			(roundrect_rratio 0.2)
			(net 128 "/USB-C console/FTDI_LED_TX")
			(pinfunction "C")
			(pintype "passive")
			(teardrops
				(best_length_ratio 0.2)
				(max_length 1)
				(best_width_ratio 0.9)
				(max_width 2)
				(curved_edges yes)
				(filter_ratio 0.9)
				(enabled yes)
				(allow_two_segments yes)
				(prefer_zone_connections yes)
			)
		)
		(pad "2" smd roundrect
			(at 0.7 0 270)
			(size 0.8 1)
			(layers "F.Cu" "F.Mask" "F.Paste")
			(roundrect_rratio 0.2)
			(net 934 "Net-(D12-A)")
			(pinfunction "A")
			(pintype "passive")
			(teardrops
				(best_length_ratio 0.2)
				(max_length 1)
				(best_width_ratio 0.9)
				(max_width 2)
				(curved_edges yes)
				(filter_ratio 0.9)
				(enabled yes)
				(allow_two_segments yes)
				(prefer_zone_connections yes)
			)
		)
	)
	(footprint "antmicro-footprints:USB-C_Receptacle_Kycon_KUSBX-SL2-CS1N24-B-TR"
		(layer "F.Cu")
		(at 98.575 84.947 -90)
		(descr "USB-C (USB TYPE-C) USB 3.2 Gen 2 (USB 3.1 Gen 2, Superspeed + (USB 3.1)) Receptacle Connector 24 Position Through Hole, Right Angle")
		(tags "CONNECTOR, USB")
		(property "Reference" "J3"
			(at 4.013 -2.675 180)
			(layer "F.SilkS")
			(effects
				(font
					(size 0.7 0.7)
					(thickness 0.15)
				)
				(justify right bottom)
			)
		)
		(property "Value" "USB-C_Kycon_KUSBX-SL2-CS1N24-B-TR"
			(at 0 7.5 90)
			(layer "F.Fab")
			(effects
				(font
					(size 0.7 0.7)
					(thickness 0.15)
				)
				(justify left bottom)
			)
		)
		(property "Datasheet" "https://www.kycon.com/Pub_Eng_Draw/KUSBX-SL2-CS1N24-B-TR.pdf"
			(at 0 0 270)
			(layer "F.Fab")
			(hide yes)
			(effects
				(font
					(size 1.27 1.27)
					(thickness 0.15)
				)
			)
		)
		(property "Author" "Antmicro"
			(at 13.628 183.522 0)
			(layer "F.Fab")
			(hide yes)
			(effects
				(font
					(size 1 1)
					(thickness 0.15)
				)
			)
		)
		(property "License" "Apache-2.0"
			(at 13.628 183.522 0)
			(layer "F.Fab")
			(hide yes)
			(effects
				(font
					(size 1 1)
					(thickness 0.15)
				)
			)
		)
		(property "MPN" "KUSBX-SL2-CS1N24-B-TR"
			(at 13.628 183.522 0)
			(layer "F.Fab")
			(hide yes)
			(effects
				(font
					(size 1 1)
					(thickness 0.15)
				)
			)
		)
		(property "Manufacturer" "Kycon"
			(at 13.628 183.522 0)
			(layer "F.Fab")
			(hide yes)
			(effects
				(font
					(size 1 1)
					(thickness 0.15)
				)
			)
		)
		(sheetname "USB-C console")
		(sheetfile "usb-c_console.kicad_sch")
		(attr smd)
		(fp_line
			(start -1 -8.8)
			(end -1 -8.8)
			(stroke
				(width 0.15)
				(type solid)
			)
			(layer "F.SilkS")
		)
		(fp_line
			(start -1 -8.8)
			(end 1 -8.8)
			(stroke
				(width 0.15)
				(type solid)
			)
			(layer "F.SilkS")
		)
		(fp_line
			(start 1 -8.8)
			(end -1 -8.8)
			(stroke
				(width 0.15)
				(type solid)
			)
			(layer "F.SilkS")
		)
		(fp_line
			(start 1 -8.8)
			(end 1 -8.8)
			(stroke
				(width 0.15)
				(type solid)
			)
			(layer "F.SilkS")
		)
		(fp_rect
			(start -4 -9.4)
			(end 4 5.65)
			(stroke
				(width 0.05)
				(type solid)
			)
			(fill no)
			(layer "F.CrtYd")
		)
		(fp_line
			(start -2.25 5.5)
			(end 2.25 5.5)
			(stroke
				(width 0.15)
				(type solid)
			)
			(layer "F.Fab")
		)
		(fp_line
			(start 2.25 5.5)
			(end 2.25 -8.8)
			(stroke
				(width 0.15)
				(type solid)
			)
			(layer "F.Fab")
		)
		(fp_line
			(start -2.25 -8.8)
			(end -2.25 5.5)
			(stroke
				(width 0.15)
				(type solid)
			)
			(layer "F.Fab")
		)
		(fp_line
			(start 2.25 -8.8)
			(end -2.25 -8.8)
			(stroke
				(width 0.15)
				(type solid)
			)
			(layer "F.Fab")
		)
		(pad "" np_thru_hole circle
			(at 0 -7.6 270)
			(size 1.1 1.1)
			(drill 1.1)
			(layers "F&B.Cu" "*.Mask")
		)
		(pad "" np_thru_hole circle
			(at 0 0 270)
			(size 1 1)
			(drill 1)
			(layers "F&B.Cu" "*.Mask")
		)
		(pad "A1" smd rect
			(at 1.1375 -6.525)
			(size 0.25 1.625)
			(layers "F.Cu" "F.Mask" "F.Paste")
			(net 1 "GND")
			(pinfunction "GND")
			(pintype "power_in")
			(teardrops
				(best_length_ratio 0.2)
				(max_length 1)
				(best_width_ratio 0.9)
				(max_width 2)
				(curved_edges yes)
				(filter_ratio 0.9)
				(enabled yes)
				(allow_two_segments yes)
				(prefer_zone_connections yes)
			)
		)
		(pad "A2" smd rect
			(at 1.1375 -6.025)
			(size 0.25 1.625)
			(layers "F.Cu" "F.Mask" "F.Paste")
			(net 174 "unconnected-(J3-TX_{1}+-PadA2)")
			(pinfunction "TX_{1}+")
			(pintype "bidirectional+no_connect")
			(teardrops
				(best_length_ratio 0.2)
				(max_length 1)
				(best_width_ratio 0.9)
				(max_width 2)
				(curved_edges yes)
				(filter_ratio 0.9)
				(enabled yes)
				(allow_two_segments yes)
				(prefer_zone_connections yes)
			)
		)
		(pad "A3" smd rect
			(at 1.1375 -5.525)
			(size 0.25 1.625)
			(layers "F.Cu" "F.Mask" "F.Paste")
			(net 175 "unconnected-(J3-TX_{1}--PadA3)")
			(pinfunction "TX_{1}-")
			(pintype "bidirectional+no_connect")
			(teardrops
				(best_length_ratio 0.2)
				(max_length 1)
				(best_width_ratio 0.9)
				(max_width 2)
				(curved_edges yes)
				(filter_ratio 0.9)
				(enabled yes)
				(allow_two_segments yes)
				(prefer_zone_connections yes)
			)
		)
		(pad "A4" smd rect
			(at 1.1375 -5.025)
			(size 0.25 1.625)
			(layers "F.Cu" "F.Mask" "F.Paste")
			(net 58 "/USB-C console/VBUS_FTDI")
			(pinfunction "VBUS")
			(pintype "passive")
			(teardrops
				(best_length_ratio 0.2)
				(max_length 1)
				(best_width_ratio 0.9)
				(max_width 2)
				(curved_edges yes)
				(filter_ratio 0.9)
				(enabled yes)
				(allow_two_segments yes)
				(prefer_zone_connections yes)
			)
		)
		(pad "A5" smd rect
			(at 1.1375 -4.525)
			(size 0.25 1.625)
			(layers "F.Cu" "F.Mask" "F.Paste")
			(net 176 "Net-(J3-CC_{1})")
			(pinfunction "CC_{1}")
			(pintype "bidirectional")
			(teardrops
				(best_length_ratio 0.2)
				(max_length 1)
				(best_width_ratio 0.9)
				(max_width 2)
				(curved_edges yes)
				(filter_ratio 0.9)
				(enabled yes)
				(allow_two_segments yes)
				(prefer_zone_connections yes)
			)
		)
		(pad "A6" smd rect
			(at 1.1375 -4.025)
			(size 0.25 1.625)
			(layers "F.Cu" "F.Mask" "F.Paste")
			(net 55 "/USB-C console/USB_D+")
			(pinfunction "D_{A}+")
			(pintype "bidirectional")
			(teardrops
				(best_length_ratio 0.2)
				(max_length 1)
				(best_width_ratio 0.9)
				(max_width 2)
				(curved_edges yes)
				(filter_ratio 0.9)
				(enabled yes)
				(allow_two_segments yes)
				(prefer_zone_connections yes)
			)
		)
		(pad "A7" smd rect
			(at 1.1375 -3.525)
			(size 0.25 1.625)
			(layers "F.Cu" "F.Mask" "F.Paste")
			(net 56 "/USB-C console/USB_D-")
			(pinfunction "D_{A}-")
			(pintype "bidirectional")
			(teardrops
				(best_length_ratio 0.2)
				(max_length 1)
				(best_width_ratio 0.9)
				(max_width 2)
				(curved_edges yes)
				(filter_ratio 0.9)
				(enabled yes)
				(allow_two_segments yes)
				(prefer_zone_connections yes)
			)
		)
		(pad "A8" smd rect
			(at 1.1375 -3.025)
			(size 0.25 1.625)
			(layers "F.Cu" "F.Mask" "F.Paste")
			(net 177 "unconnected-(J3-SBU_{1}-PadA8)")
			(pinfunction "SBU_{1}")
			(pintype "bidirectional+no_connect")
			(teardrops
				(best_length_ratio 0.2)
				(max_length 1)
				(best_width_ratio 0.9)
				(max_width 2)
				(curved_edges yes)
				(filter_ratio 0.9)
				(enabled yes)
				(allow_two_segments yes)
				(prefer_zone_connections yes)
			)
		)
		(pad "A9" smd rect
			(at 1.1375 -2.525)
			(size 0.25 1.625)
			(layers "F.Cu" "F.Mask" "F.Paste")
			(net 58 "/USB-C console/VBUS_FTDI")
			(pinfunction "VBUS")
			(pintype "passive")
			(teardrops
				(best_length_ratio 0.2)
				(max_length 1)
				(best_width_ratio 0.9)
				(max_width 2)
				(curved_edges yes)
				(filter_ratio 0.9)
				(enabled yes)
				(allow_two_segments yes)
				(prefer_zone_connections yes)
			)
		)
		(pad "A10" smd rect
			(at 1.1375 -2.025)
			(size 0.25 1.625)
			(layers "F.Cu" "F.Mask" "F.Paste")
			(net 178 "unconnected-(J3-RX_{2}--PadA10)")
			(pinfunction "RX_{2}-")
			(pintype "bidirectional+no_connect")
			(teardrops
				(best_length_ratio 0.2)
				(max_length 1)
				(best_width_ratio 0.9)
				(max_width 2)
				(curved_edges yes)
				(filter_ratio 0.9)
				(enabled yes)
				(allow_two_segments yes)
				(prefer_zone_connections yes)
			)
		)
		(pad "A11" smd rect
			(at 1.1375 -1.525)
			(size 0.25 1.625)
			(layers "F.Cu" "F.Mask" "F.Paste")
			(net 179 "unconnected-(J3-RX_{2}+-PadA11)")
			(pinfunction "RX_{2}+")
			(pintype "bidirectional+no_connect")
			(teardrops
				(best_length_ratio 0.2)
				(max_length 1)
				(best_width_ratio 0.9)
				(max_width 2)
				(curved_edges yes)
				(filter_ratio 0.9)
				(enabled yes)
				(allow_two_segments yes)
				(prefer_zone_connections yes)
			)
		)
		(pad "A12" smd rect
			(at 1.1375 -1.025)
			(size 0.25 1.625)
			(layers "F.Cu" "F.Mask" "F.Paste")
			(net 1 "GND")
			(pinfunction "GND")
			(pintype "passive")
			(teardrops
				(best_length_ratio 0.2)
				(max_length 1)
				(best_width_ratio 0.9)
				(max_width 2)
				(curved_edges yes)
				(filter_ratio 0.9)
				(enabled yes)
				(allow_two_segments yes)
				(prefer_zone_connections yes)
			)
		)
		(pad "B1" smd rect
			(at -1.1375 -1.025)
			(size 0.25 1.625)
			(layers "F.Cu" "F.Mask" "F.Paste")
			(net 1 "GND")
			(pinfunction "GND")
			(pintype "passive")
			(teardrops
				(best_length_ratio 0.2)
				(max_length 1)
				(best_width_ratio 0.9)
				(max_width 2)
				(curved_edges yes)
				(filter_ratio 0.9)
				(enabled yes)
				(allow_two_segments yes)
				(prefer_zone_connections yes)
			)
		)
		(pad "B2" smd rect
			(at -1.1375 -1.525)
			(size 0.25 1.625)
			(layers "F.Cu" "F.Mask" "F.Paste")
			(net 180 "unconnected-(J3-TX_{2}+-PadB2)")
			(pinfunction "TX_{2}+")
			(pintype "bidirectional+no_connect")
			(teardrops
				(best_length_ratio 0.2)
				(max_length 1)
				(best_width_ratio 0.9)
				(max_width 2)
				(curved_edges yes)
				(filter_ratio 0.9)
				(enabled yes)
				(allow_two_segments yes)
				(prefer_zone_connections yes)
			)
		)
		(pad "B3" smd rect
			(at -1.1375 -2.025)
			(size 0.25 1.625)
			(layers "F.Cu" "F.Mask" "F.Paste")
			(net 181 "unconnected-(J3-TX_{2}--PadB3)")
			(pinfunction "TX_{2}-")
			(pintype "bidirectional+no_connect")
			(teardrops
				(best_length_ratio 0.2)
				(max_length 1)
				(best_width_ratio 0.9)
				(max_width 2)
				(curved_edges yes)
				(filter_ratio 0.9)
				(enabled yes)
				(allow_two_segments yes)
				(prefer_zone_connections yes)
			)
		)
		(pad "B4" smd rect
			(at -1.1375 -2.525)
			(size 0.25 1.625)
			(layers "F.Cu" "F.Mask" "F.Paste")
			(net 58 "/USB-C console/VBUS_FTDI")
			(pinfunction "VBUS")
			(pintype "passive")
			(teardrops
				(best_length_ratio 0.2)
				(max_length 1)
				(best_width_ratio 0.9)
				(max_width 2)
				(curved_edges yes)
				(filter_ratio 0.9)
				(enabled yes)
				(allow_two_segments yes)
				(prefer_zone_connections yes)
			)
		)
		(pad "B5" smd rect
			(at -1.1375 -3.025)
			(size 0.25 1.625)
			(layers "F.Cu" "F.Mask" "F.Paste")
			(net 182 "Net-(J3-CC_{2})")
			(pinfunction "CC_{2}")
			(pintype "bidirectional")
			(teardrops
				(best_length_ratio 0.2)
				(max_length 1)
				(best_width_ratio 0.9)
				(max_width 2)
				(curved_edges yes)
				(filter_ratio 0.9)
				(enabled yes)
				(allow_two_segments yes)
				(prefer_zone_connections yes)
			)
		)
		(pad "B6" smd rect
			(at -1.1375 -3.525)
			(size 0.25 1.625)
			(layers "F.Cu" "F.Mask" "F.Paste")
			(net 55 "/USB-C console/USB_D+")
			(pinfunction "D_{B}+")
			(pintype "bidirectional")
			(teardrops
				(best_length_ratio 0.2)
				(max_length 1)
				(best_width_ratio 0.9)
				(max_width 2)
				(curved_edges yes)
				(filter_ratio 0.9)
				(enabled yes)
				(allow_two_segments yes)
				(prefer_zone_connections yes)
			)
		)
		(pad "B7" smd rect
			(at -1.1375 -4.025)
			(size 0.25 1.625)
			(layers "F.Cu" "F.Mask" "F.Paste")
			(net 56 "/USB-C console/USB_D-")
			(pinfunction "D_{B}-")
			(pintype "bidirectional")
			(teardrops
				(best_length_ratio 0.2)
				(max_length 1)
				(best_width_ratio 0.9)
				(max_width 2)
				(curved_edges yes)
				(filter_ratio 0.9)
				(enabled yes)
				(allow_two_segments yes)
				(prefer_zone_connections yes)
			)
		)
		(pad "B8" smd rect
			(at -1.1375 -4.525)
			(size 0.25 1.625)
			(layers "F.Cu" "F.Mask" "F.Paste")
			(net 183 "unconnected-(J3-SBU_{2}-PadB8)")
			(pinfunction "SBU_{2}")
			(pintype "bidirectional+no_connect")
			(teardrops
				(best_length_ratio 0.2)
				(max_length 1)
				(best_width_ratio 0.9)
				(max_width 2)
				(curved_edges yes)
				(filter_ratio 0.9)
				(enabled yes)
				(allow_two_segments yes)
				(prefer_zone_connections yes)
			)
		)
		(pad "B9" smd rect
			(at -1.1375 -5.025)
			(size 0.25 1.625)
			(layers "F.Cu" "F.Mask" "F.Paste")
			(net 58 "/USB-C console/VBUS_FTDI")
			(pinfunction "VBUS")
			(pintype "passive")
			(teardrops
				(best_length_ratio 0.2)
				(max_length 1)
				(best_width_ratio 0.9)
				(max_width 2)
				(curved_edges yes)
				(filter_ratio 0.9)
				(enabled yes)
				(allow_two_segments yes)
				(prefer_zone_connections yes)
			)
		)
		(pad "B10" smd rect
			(at -1.1375 -5.525)
			(size 0.25 1.625)
			(layers "F.Cu" "F.Mask" "F.Paste")
			(net 184 "unconnected-(J3-RX_{1}--PadB10)")
			(pinfunction "RX_{1}-")
			(pintype "bidirectional+no_connect")
			(teardrops
				(best_length_ratio 0.2)
				(max_length 1)
				(best_width_ratio 0.9)
				(max_width 2)
				(curved_edges yes)
				(filter_ratio 0.9)
				(enabled yes)
				(allow_two_segments yes)
				(prefer_zone_connections yes)
			)
		)
		(pad "B11" smd rect
			(at -1.1375 -6.025)
			(size 0.25 1.625)
			(layers "F.Cu" "F.Mask" "F.Paste")
			(net 185 "unconnected-(J3-RX_{1}+-PadB11)")
			(pinfunction "RX_{1}+")
			(pintype "bidirectional+no_connect")
			(teardrops
				(best_length_ratio 0.2)
				(max_length 1)
				(best_width_ratio 0.9)
				(max_width 2)
				(curved_edges yes)
				(filter_ratio 0.9)
				(enabled yes)
				(allow_two_segments yes)
				(prefer_zone_connections yes)
			)
		)
		(pad "B12" smd rect
			(at -1.1375 -6.525)
			(size 0.25 1.625)
			(layers "F.Cu" "F.Mask" "F.Paste")
			(net 1 "GND")
			(pinfunction "GND")
			(pintype "passive")
			(teardrops
				(best_length_ratio 0.2)
				(max_length 1)
				(best_width_ratio 0.9)
				(max_width 2)
				(curved_edges yes)
				(filter_ratio 0.9)
				(enabled yes)
				(allow_two_segments yes)
				(prefer_zone_connections yes)
			)
		)
		(pad "SH" thru_hole oval
			(at -3 -7.849 270)
			(size 1 2.05)
			(drill oval 0.6 1.65)
			(layers "*.Cu" "*.Mask")
			(remove_unused_layers no)
			(net 54 "/USB-C console/SH")
			(pinfunction "SH")
			(pintype "passive")
			(teardrops
				(best_length_ratio 0.2)
				(max_length 1)
				(best_width_ratio 0.9)
				(max_width 2)
				(curved_edges yes)
				(filter_ratio 0.9)
				(enabled yes)
				(allow_two_segments yes)
				(prefer_zone_connections yes)
			)
		)
		(pad "SH" thru_hole oval
			(at -3 0.25 270)
			(size 1 2.05)
			(drill oval 0.6 1.65)
			(layers "*.Cu" "*.Mask")
			(remove_unused_layers no)
			(net 54 "/USB-C console/SH")
			(pinfunction "SH")
			(pintype "passive")
			(teardrops
				(best_length_ratio 0.2)
				(max_length 1)
				(best_width_ratio 0.9)
				(max_width 2)
				(curved_edges yes)
				(filter_ratio 0.9)
				(enabled yes)
				(allow_two_segments yes)
				(prefer_zone_connections yes)
			)
		)
		(pad "SH" thru_hole oval
			(at 3 -7.849 270)
			(size 1 2.05)
			(drill oval 0.6 1.65)
			(layers "*.Cu" "*.Mask")
			(remove_unused_layers no)
			(net 54 "/USB-C console/SH")
			(pinfunction "SH")
			(pintype "passive")
			(teardrops
				(best_length_ratio 0.2)
				(max_length 1)
				(best_width_ratio 0.9)
				(max_width 2)
				(curved_edges yes)
				(filter_ratio 0.9)
				(enabled yes)
				(allow_two_segments yes)
				(prefer_zone_connections yes)
			)
		)
		(pad "SH" thru_hole oval
			(at 3 0.25 270)
			(size 1 2.05)
			(drill oval 0.6 1.65)
			(layers "*.Cu" "*.Mask")
			(remove_unused_layers no)
			(net 54 "/USB-C console/SH")
			(pinfunction "SH")
			(pintype "passive")
			(teardrops
				(best_length_ratio 0.2)
				(max_length 1)
				(best_width_ratio 0.9)
				(max_width 2)
				(curved_edges yes)
				(filter_ratio 0.9)
				(enabled yes)
				(allow_two_segments yes)
				(prefer_zone_connections yes)
			)
		)
	)
	(footprint "antmicro-footprints:QFN-20-1EP_3x3mm_P0.45mm_TPS56xxxx"
		(layer "F.Cu")
		(at 311.714999 104.748999 180)
		(property "Reference" "U19"
			(at -1.885001 1.838999 0)
			(layer "F.SilkS")
			(effects
				(font
					(size 0.7 0.7)
					(thickness 0.15)
				)
				(justify right bottom)
			)
		)
		(property "Value" "TPS56C230"
			(at 0 2.898 0)
			(layer "F.Fab")
			(effects
				(font
					(size 0.7 0.7)
					(thickness 0.15)
				)
				(justify right bottom)
			)
		)
		(property "Datasheet" "https://www.ti.com/lit/ds/symlink/tps56c230.pdf?ts=1672843259715&ref_url=https%253A%252F%252Fwww.ti.com%252Fproduct%252FTPS56C230"
			(at 0 0 180)
			(layer "F.Fab")
			(hide yes)
			(effects
				(font
					(size 1.27 1.27)
					(thickness 0.15)
				)
			)
		)
		(property "Author" "Antmicro"
			(at 623.429998 209.497998 0)
			(layer "F.Fab")
			(hide yes)
			(effects
				(font
					(size 1 1)
					(thickness 0.15)
				)
			)
		)
		(property "License" "Apache-2.0"
			(at 623.429998 209.497998 0)
			(layer "F.Fab")
			(hide yes)
			(effects
				(font
					(size 1 1)
					(thickness 0.15)
				)
			)
		)
		(property "MPN" "TPS56C230RJER"
			(at 623.429998 209.497998 0)
			(layer "F.Fab")
			(hide yes)
			(effects
				(font
					(size 1 1)
					(thickness 0.15)
				)
			)
		)
		(property "Manufacturer" "Texas Instruments"
			(at 623.429998 209.497998 0)
			(layer "F.Fab")
			(hide yes)
			(effects
				(font
					(size 1 1)
					(thickness 0.15)
				)
			)
		)
		(sheetname "Power")
		(sheetfile "power.kicad_sch")
		(attr smd)
		(fp_line
			(start 1.5 -1.5)
			(end 1.5 -1.2)
			(stroke
				(width 0.15)
				(type solid)
			)
			(layer "F.SilkS")
		)
		(fp_line
			(start 1.499 1.5)
			(end 1.499 1.202)
			(stroke
				(width 0.15)
				(type solid)
			)
			(layer "F.SilkS")
		)
		(fp_line
			(start 1.202 -1.5)
			(end 1.5 -1.5)
			(stroke
				(width 0.15)
				(type solid)
			)
			(layer "F.SilkS")
		)
		(fp_line
			(start 1.201 1.5)
			(end 1.499 1.5)
			(stroke
				(width 0.15)
				(type solid)
			)
			(layer "F.SilkS")
		)
		(fp_line
			(start -1.2 1.498)
			(end -1.5 1.498)
			(stroke
				(width 0.15)
				(type solid)
			)
			(layer "F.SilkS")
		)
		(fp_line
			(start -1.5 1.498)
			(end -1.5 1.2)
			(stroke
				(width 0.15)
				(type solid)
			)
			(layer "F.SilkS")
		)
		(fp_line
			(start -1.5 -1.201)
			(end -1.5 -1.499)
			(stroke
				(width 0.15)
				(type solid)
			)
			(layer "F.SilkS")
		)
		(fp_line
			(start -1.5 -1.499)
			(end -1.2 -1.499)
			(stroke
				(width 0.15)
				(type solid)
			)
			(layer "F.SilkS")
		)
		(fp_circle
			(center -1.8 -1.15)
			(end -1.75 -1.15)
			(stroke
				(width 0.15)
				(type solid)
			)
			(fill yes)
			(layer "F.SilkS")
		)
		(fp_rect
			(start -1.8 -1.8)
			(end 1.8 1.8)
			(stroke
				(width 0.05)
				(type solid)
			)
			(fill no)
			(layer "F.CrtYd")
		)
		(fp_line
			(start 1.499 1.499)
			(end 1.499 -1.5)
			(stroke
				(width 0.15)
				(type solid)
			)
			(layer "F.Fab")
		)
		(fp_line
			(start 1.499 -1.5)
			(end -0.5 -1.5)
			(stroke
				(width 0.15)
				(type solid)
			)
			(layer "F.Fab")
		)
		(fp_line
			(start -0.5 -1.5)
			(end -1.5 -0.5)
			(stroke
				(width 0.15)
				(type solid)
			)
			(layer "F.Fab")
		)
		(fp_line
			(start -1.5 1.499)
			(end 1.499 1.499)
			(stroke
				(width 0.15)
				(type solid)
			)
			(layer "F.Fab")
		)
		(fp_line
			(start -1.5 -0.5)
			(end -1.5 1.499)
			(stroke
				(width 0.15)
				(type solid)
			)
			(layer "F.Fab")
		)
		(pad "1" smd oval
			(at -1.4 -0.905 270)
			(size 0.2 0.6)
			(layers "F.Cu" "F.Mask" "F.Paste")
			(net 68 "Net-(U19-BST)")
			(pinfunction "BST")
			(pintype "passive")
			(teardrops
				(best_length_ratio 0.2)
				(max_length 1)
				(best_width_ratio 0.9)
				(max_width 2)
				(curved_edges yes)
				(filter_ratio 0.9)
				(enabled yes)
				(allow_two_segments yes)
				(prefer_zone_connections yes)
			)
		)
		(pad "2" smd oval
			(at -1.4 -0.455 270)
			(size 0.2 0.6)
			(layers "F.Cu" "F.Mask" "F.Paste")
			(net 62 "+12V_AON")
			(pinfunction "V_{IN}")
			(pintype "power_in")
			(teardrops
				(best_length_ratio 0.2)
				(max_length 1)
				(best_width_ratio 0.9)
				(max_width 2)
				(curved_edges yes)
				(filter_ratio 0.9)
				(enabled yes)
				(allow_two_segments yes)
				(prefer_zone_connections yes)
			)
		)
		(pad "3" smd oval
			(at -1.4 0 270)
			(size 0.2 0.6)
			(layers "F.Cu" "F.Mask" "F.Paste")
			(net 62 "+12V_AON")
			(pinfunction "V_{IN}")
			(pintype "passive")
			(teardrops
				(best_length_ratio 0.2)
				(max_length 1)
				(best_width_ratio 0.9)
				(max_width 2)
				(curved_edges yes)
				(filter_ratio 0.9)
				(enabled yes)
				(allow_two_segments yes)
				(prefer_zone_connections yes)
			)
		)
		(pad "4" smd oval
			(at -1.4 0.45 270)
			(size 0.2 0.6)
			(layers "F.Cu" "F.Mask" "F.Paste")
			(net 62 "+12V_AON")
			(pinfunction "V_{IN}")
			(pintype "passive")
			(teardrops
				(best_length_ratio 0.2)
				(max_length 1)
				(best_width_ratio 0.9)
				(max_width 2)
				(curved_edges yes)
				(filter_ratio 0.9)
				(enabled yes)
				(allow_two_segments yes)
				(prefer_zone_connections yes)
			)
		)
		(pad "5" smd oval
			(at -1.4 0.9 270)
			(size 0.2 0.6)
			(layers "F.Cu" "F.Mask" "F.Paste")
			(net 62 "+12V_AON")
			(pinfunction "V_{IN}")
			(pintype "passive")
			(teardrops
				(best_length_ratio 0.2)
				(max_length 1)
				(best_width_ratio 0.9)
				(max_width 2)
				(curved_edges yes)
				(filter_ratio 0.9)
				(enabled yes)
				(allow_two_segments yes)
				(prefer_zone_connections yes)
			)
		)
		(pad "6" smd oval
			(at -0.905 1.4 180)
			(size 0.2 0.6)
			(layers "F.Cu" "F.Mask" "F.Paste")
			(net 69 "Net-(C48-Pad2)")
			(pinfunction "SW")
			(pintype "passive")
			(teardrops
				(best_length_ratio 0.2)
				(max_length 1)
				(best_width_ratio 0.9)
				(max_width 2)
				(curved_edges yes)
				(filter_ratio 0.9)
				(enabled yes)
				(allow_two_segments yes)
				(prefer_zone_connections yes)
			)
		)
		(pad "7" smd oval
			(at -0.455 1.4 180)
			(size 0.2 0.6)
			(layers "F.Cu" "F.Mask" "F.Paste")
			(net 1 "GND")
			(pinfunction "PGND")
			(pintype "passive")
			(teardrops
				(best_length_ratio 0.2)
				(max_length 1)
				(best_width_ratio 0.9)
				(max_width 2)
				(curved_edges yes)
				(filter_ratio 0.9)
				(enabled yes)
				(allow_two_segments yes)
				(prefer_zone_connections yes)
			)
		)
		(pad "8" smd oval
			(at 0 1.4 180)
			(size 0.2 0.6)
			(layers "F.Cu" "F.Mask" "F.Paste")
			(net 1 "GND")
			(pinfunction "PGND")
			(pintype "passive")
			(teardrops
				(best_length_ratio 0.2)
				(max_length 1)
				(best_width_ratio 0.9)
				(max_width 2)
				(curved_edges yes)
				(filter_ratio 0.9)
				(enabled yes)
				(allow_two_segments yes)
				(prefer_zone_connections yes)
			)
		)
		(pad "9" smd oval
			(at 0.45 1.4 180)
			(size 0.2 0.6)
			(layers "F.Cu" "F.Mask" "F.Paste")
			(net 889 "/Power/PG_{3V3}")
			(pinfunction "PG")
			(pintype "passive")
			(teardrops
				(best_length_ratio 0.2)
				(max_length 1)
				(best_width_ratio 0.9)
				(max_width 2)
				(curved_edges yes)
				(filter_ratio 0.9)
				(enabled yes)
				(allow_two_segments yes)
				(prefer_zone_connections yes)
			)
		)
		(pad "10" smd oval
			(at 0.9 1.4 180)
			(size 0.2 0.6)
			(layers "F.Cu" "F.Mask" "F.Paste")
			(net 776 "unconnected-(U19-NC-Pad10)")
			(pinfunction "NC")
			(pintype "no_connect")
			(teardrops
				(best_length_ratio 0.2)
				(max_length 1)
				(best_width_ratio 0.9)
				(max_width 2)
				(curved_edges yes)
				(filter_ratio 0.9)
				(enabled yes)
				(allow_two_segments yes)
				(prefer_zone_connections yes)
			)
		)
		(pad "11" smd oval
			(at 1.4 0.9 270)
			(size 0.2 0.6)
			(layers "F.Cu" "F.Mask" "F.Paste")
			(net 777 "unconnected-(U19-SS-Pad11)")
			(pinfunction "SS")
			(pintype "passive+no_connect")
			(teardrops
				(best_length_ratio 0.2)
				(max_length 1)
				(best_width_ratio 0.9)
				(max_width 2)
				(curved_edges yes)
				(filter_ratio 0.9)
				(enabled yes)
				(allow_two_segments yes)
				(prefer_zone_connections yes)
			)
		)
		(pad "12" smd oval
			(at 1.4 0.45 270)
			(size 0.2 0.6)
			(layers "F.Cu" "F.Mask" "F.Paste")
			(net 574 "Net-(U19-EN)")
			(pinfunction "EN")
			(pintype "passive")
			(teardrops
				(best_length_ratio 0.2)
				(max_length 1)
				(best_width_ratio 0.9)
				(max_width 2)
				(curved_edges yes)
				(filter_ratio 0.9)
				(enabled yes)
				(allow_two_segments yes)
				(prefer_zone_connections yes)
			)
		)
		(pad "13" smd oval
			(at 1.4 0 270)
			(size 0.2 0.6)
			(layers "F.Cu" "F.Mask" "F.Paste")
			(net 1 "GND")
			(pinfunction "AGND")
			(pintype "passive")
			(teardrops
				(best_length_ratio 0.2)
				(max_length 1)
				(best_width_ratio 0.9)
				(max_width 2)
				(curved_edges yes)
				(filter_ratio 0.9)
				(enabled yes)
				(allow_two_segments yes)
				(prefer_zone_connections yes)
			)
		)
		(pad "14" smd oval
			(at 1.4 -0.455 270)
			(size 0.2 0.6)
			(layers "F.Cu" "F.Mask" "F.Paste")
			(net 581 "Net-(U19-FB)")
			(pinfunction "FB")
			(pintype "passive")
			(teardrops
				(best_length_ratio 0.2)
				(max_length 1)
				(best_width_ratio 0.9)
				(max_width 2)
				(curved_edges yes)
				(filter_ratio 0.9)
				(enabled yes)
				(allow_two_segments yes)
				(prefer_zone_connections yes)
			)
		)
		(pad "15" smd oval
			(at 1.4 -0.905 270)
			(size 0.2 0.6)
			(layers "F.Cu" "F.Mask" "F.Paste")
			(net 576 "Net-(U19-MODE)")
			(pinfunction "MODE")
			(pintype "passive")
			(teardrops
				(best_length_ratio 0.2)
				(max_length 1)
				(best_width_ratio 0.9)
				(max_width 2)
				(curved_edges yes)
				(filter_ratio 0.9)
				(enabled yes)
				(allow_two_segments yes)
				(prefer_zone_connections yes)
			)
		)
		(pad "16" smd oval
			(at 0.9 -1.4 180)
			(size 0.2 0.6)
			(layers "F.Cu" "F.Mask" "F.Paste")
			(net 778 "unconnected-(U19-NC-Pad16)")
			(pinfunction "NC")
			(pintype "no_connect")
			(teardrops
				(best_length_ratio 0.2)
				(max_length 1)
				(best_width_ratio 0.9)
				(max_width 2)
				(curved_edges yes)
				(filter_ratio 0.9)
				(enabled yes)
				(allow_two_segments yes)
				(prefer_zone_connections yes)
			)
		)
		(pad "17" smd oval
			(at 0.45 -1.4 180)
			(size 0.2 0.6)
			(layers "F.Cu" "F.Mask" "F.Paste")
			(net 64 "Net-(U19-V_{CC})")
			(pinfunction "V_{CC}")
			(pintype "passive")
			(teardrops
				(best_length_ratio 0.2)
				(max_length 1)
				(best_width_ratio 0.9)
				(max_width 2)
				(curved_edges yes)
				(filter_ratio 0.9)
				(enabled yes)
				(allow_two_segments yes)
				(prefer_zone_connections yes)
			)
		)
		(pad "18" smd oval
			(at 0 -1.4 180)
			(size 0.2 0.6)
			(layers "F.Cu" "F.Mask" "F.Paste")
			(net 1 "GND")
			(pinfunction "PGND")
			(pintype "passive")
			(teardrops
				(best_length_ratio 0.2)
				(max_length 1)
				(best_width_ratio 0.9)
				(max_width 2)
				(curved_edges yes)
				(filter_ratio 0.9)
				(enabled yes)
				(allow_two_segments yes)
				(prefer_zone_connections yes)
			)
		)
		(pad "19" smd oval
			(at -0.455 -1.4 180)
			(size 0.2 0.6)
			(layers "F.Cu" "F.Mask" "F.Paste")
			(net 69 "Net-(C48-Pad2)")
			(pinfunction "SW")
			(pintype "passive")
			(teardrops
				(best_length_ratio 0.2)
				(max_length 1)
				(best_width_ratio 0.9)
				(max_width 2)
				(curved_edges yes)
				(filter_ratio 0.9)
				(enabled yes)
				(allow_two_segments yes)
				(prefer_zone_connections yes)
			)
		)
		(pad "20" smd oval
			(at -0.905 -1.4 180)
			(size 0.2 0.6)
			(layers "F.Cu" "F.Mask" "F.Paste")
			(net 69 "Net-(C48-Pad2)")
			(pinfunction "SW")
			(pintype "passive")
			(teardrops
				(best_length_ratio 0.2)
				(max_length 1)
				(best_width_ratio 0.9)
				(max_width 2)
				(curved_edges yes)
				(filter_ratio 0.9)
				(enabled yes)
				(allow_two_segments yes)
				(prefer_zone_connections yes)
			)
		)
		(pad "21" smd roundrect
			(at -0.06 0.018 180)
			(size 0.775 0.86)
			(layers "F.Cu" "F.Mask" "F.Paste")
			(roundrect_rratio 0.1)
			(net 1 "GND")
			(pinfunction "PGND")
			(pintype "passive")
			(solder_mask_margin -0.05)
			(solder_paste_margin -0.05)
			(teardrops
				(best_length_ratio 0.2)
				(max_length 1)
				(best_width_ratio 0.9)
				(max_width 2)
				(curved_edges yes)
				(filter_ratio 0.9)
				(enabled yes)
				(allow_two_segments yes)
				(prefer_zone_connections yes)
			)
		)
	)
	(footprint "antmicro-footprints:R_0402_1005Metric"
		(layer "F.Cu")
		(at 219.73 123.9 180)
		(descr "Resistor SMD 0402")
		(tags "resistor SMD 0402")
		(property "Reference" "R187"
			(at -3.62 -0.46 0)
			(layer "F.SilkS")
			(effects
				(font
					(size 0.7 0.7)
					(thickness 0.15)
				)
				(justify right bottom)
			)
		)
		(property "Value" "R_1k_0402"
			(at -1.011843 1.772047 0)
			(layer "F.Fab")
			(effects
				(font
					(size 0.7 0.7)
					(thickness 0.15)
				)
				(justify right bottom)
			)
		)
		(property "Datasheet" "https://www.bourns.com/docs/product-datasheets/cr.pdf"
			(at 0 0 180)
			(layer "F.Fab")
			(hide yes)
			(effects
				(font
					(size 1.27 1.27)
					(thickness 0.15)
				)
			)
		)
		(property "Author" "Antmicro"
			(at 439.46 247.8 0)
			(layer "F.Fab")
			(hide yes)
			(effects
				(font
					(size 1 1)
					(thickness 0.15)
				)
			)
		)
		(property "License" "Apache-2.0"
			(at 439.46 247.8 0)
			(layer "F.Fab")
			(hide yes)
			(effects
				(font
					(size 1 1)
					(thickness 0.15)
				)
			)
		)
		(property "MPN" "CR0402-FX-1001GLF"
			(at 439.46 247.8 0)
			(layer "F.Fab")
			(hide yes)
			(effects
				(font
					(size 1 1)
					(thickness 0.15)
				)
			)
		)
		(property "Manufacturer" "Bourns"
			(at 439.46 247.8 0)
			(layer "F.Fab")
			(hide yes)
			(effects
				(font
					(size 1 1)
					(thickness 0.15)
				)
			)
		)
		(property "Public" "False"
			(at 439.46 247.8 0)
			(layer "F.Fab")
			(hide yes)
			(effects
				(font
					(size 1 1)
					(thickness 0.15)
				)
			)
		)
		(property "Tolerance" "1%"
			(at 439.46 247.8 0)
			(layer "F.Fab")
			(hide yes)
			(effects
				(font
					(size 1 1)
					(thickness 0.15)
				)
			)
		)
		(property "Val" "1k"
			(at 439.46 247.8 0)
			(layer "F.Fab")
			(hide yes)
			(effects
				(font
					(size 1 1)
					(thickness 0.15)
				)
			)
		)
		(sheetname "PCIe misc")
		(sheetfile "pcie_misc.kicad_sch")
		(attr smd)
		(fp_rect
			(start -0.925 -0.47)
			(end 0.925 0.47)
			(stroke
				(width 0.05)
				(type default)
			)
			(fill no)
			(layer "F.CrtYd")
		)
		(fp_rect
			(start -0.5 -0.25)
			(end 0.5 0.25)
			(stroke
				(width 0.15)
				(type solid)
			)
			(fill no)
			(layer "F.Fab")
		)
		(pad "1" smd roundrect
			(at -0.48 0 180)
			(size 0.59 0.64)
			(layers "F.Cu" "F.Mask" "F.Paste")
			(roundrect_rratio 0.25)
			(net 2 "+3V3")
			(pintype "passive")
			(teardrops
				(best_length_ratio 0.2)
				(max_length 1)
				(best_width_ratio 0.9)
				(max_width 2)
				(curved_edges yes)
				(filter_ratio 0.9)
				(enabled yes)
				(allow_two_segments yes)
				(prefer_zone_connections yes)
			)
		)
		(pad "2" smd roundrect
			(at 0.48 0 180)
			(size 0.59 0.64)
			(layers "F.Cu" "F.Mask" "F.Paste")
			(roundrect_rratio 0.25)
			(net 607 "Net-(U37-~{HIBW_BYPM_LOBW})")
			(pintype "passive")
			(teardrops
				(best_length_ratio 0.2)
				(max_length 1)
				(best_width_ratio 0.9)
				(max_width 2)
				(curved_edges yes)
				(filter_ratio 0.9)
				(enabled yes)
				(allow_two_segments yes)
				(prefer_zone_connections yes)
			)
		)
	)
	(footprint "antmicro-footprints:Trans_Eth_4.7x3.3mm"
		(layer "F.Cu")
		(at 130.63 112.16)
		(property "Reference" "T5"
			(at 4.97 0.25 0)
			(unlocked yes)
			(layer "F.SilkS")
			(effects
				(font
					(size 0.7 0.7)
					(thickness 0.15)
				)
				(justify left bottom)
			)
		)
		(property "Value" "Trans_SM453229-381N7Y"
			(at 2.39 11.52 0)
			(unlocked yes)
			(layer "F.Fab")
			(effects
				(font
					(size 0.7 0.7)
					(thickness 0.15)
				)
				(justify left bottom)
			)
		)
		(property "Datasheet" "https://eu.mouser.com/datasheet/2/54/bourns_02132019_SM453229-381N7Y_datasheet-1532071.pdf"
			(at 0 0 0)
			(layer "F.Fab")
			(hide yes)
			(effects
				(font
					(size 1.27 1.27)
					(thickness 0.15)
				)
			)
		)
		(property "Author" "Antmicro"
			(at 0 0 0)
			(layer "F.Fab")
			(hide yes)
			(effects
				(font
					(size 1 1)
					(thickness 0.15)
				)
			)
		)
		(property "License" "Apache-2.0"
			(at 0 0 0)
			(layer "F.Fab")
			(hide yes)
			(effects
				(font
					(size 1 1)
					(thickness 0.15)
				)
			)
		)
		(property "MPN" "SM453229-381N7Y"
			(at 0 0 0)
			(layer "F.Fab")
			(hide yes)
			(effects
				(font
					(size 1 1)
					(thickness 0.15)
				)
			)
		)
		(property "Manufacturer" "Bourns"
			(at 0 0 0)
			(layer "F.Fab")
			(hide yes)
			(effects
				(font
					(size 1 1)
					(thickness 0.15)
				)
			)
		)
		(sheetname "2xUSB3.0+RJ45")
		(sheetfile "usb3+rj45.kicad_sch")
		(attr smd)
		(fp_line
			(start -0.15 -0.6)
			(end -0.15 0.55)
			(stroke
				(width 0.1)
				(type default)
			)
			(layer "F.SilkS")
		)
		(fp_line
			(start 3.4 -1.6)
			(end 1 -1.6)
			(stroke
				(width 0.1)
				(type default)
			)
			(layer "F.SilkS")
		)
		(fp_line
			(start 3.4 1.7)
			(end 1 1.7)
			(stroke
				(width 0.1)
				(type default)
			)
			(layer "F.SilkS")
		)
		(fp_line
			(start 4.55 -0.25)
			(end 4.55 0.9)
			(stroke
				(width 0.1)
				(type default)
			)
			(layer "F.SilkS")
		)
		(fp_circle
			(center 0.1 2.3)
			(end 0.15 2.3)
			(stroke
				(width 0.15)
				(type solid)
			)
			(fill yes)
			(layer "F.SilkS")
		)
		(fp_rect
			(start -0.6 -1.9)
			(end 4.94 1.9)
			(stroke
				(width 0.05)
				(type solid)
			)
			(fill no)
			(layer "F.CrtYd")
		)
		(pad "1" smd roundrect
			(at 0.17 1.5)
			(size 0.96 0.27)
			(layers "F.Cu" "F.Mask" "F.Paste")
			(roundrect_rratio 0.25)
			(net 689 "/2xUSB3.0+RJ45/DA_FL+")
			(pinfunction "1")
			(pintype "passive")
			(teardrops
				(best_length_ratio 0.2)
				(max_length 1)
				(best_width_ratio 0.9)
				(max_width 2)
				(curved_edges yes)
				(filter_ratio 0.9)
				(enabled yes)
				(allow_two_segments yes)
				(prefer_zone_connections yes)
			)
		)
		(pad "2" smd roundrect
			(at 0.115 0.855)
			(size 0.85 0.28)
			(layers "F.Cu" "F.Mask" "F.Paste")
			(roundrect_rratio 0.25)
			(net 690 "/2xUSB3.0+RJ45/DA_FL-")
			(pinfunction "2")
			(pintype "passive")
			(teardrops
				(best_length_ratio 0.2)
				(max_length 1)
				(best_width_ratio 0.9)
				(max_width 2)
				(curved_edges yes)
				(filter_ratio 0.9)
				(enabled yes)
				(allow_two_segments yes)
				(prefer_zone_connections yes)
			)
		)
		(pad "3" smd roundrect
			(at 0.14 -1.21)
			(size 0.9 0.77)
			(layers "F.Cu" "F.Mask" "F.Paste")
			(roundrect_rratio 0.1)
			(net 51 "Net-(C13-Pad1)")
			(pinfunction "3")
			(pintype "passive")
			(teardrops
				(best_length_ratio 0.2)
				(max_length 1)
				(best_width_ratio 0.9)
				(max_width 2)
				(curved_edges yes)
				(filter_ratio 0.9)
				(enabled yes)
				(allow_two_segments yes)
				(prefer_zone_connections yes)
			)
		)
		(pad "5" smd roundrect
			(at 4.215 1.385)
			(size 0.95 0.5)
			(layers "F.Cu" "F.Mask" "F.Paste")
			(roundrect_rratio 0.1)
			(net 549 "Net-(R14-Pad2)")
			(pinfunction "5")
			(pintype "passive")
			(teardrops
				(best_length_ratio 0.2)
				(max_length 1)
				(best_width_ratio 0.9)
				(max_width 2)
				(curved_edges yes)
				(filter_ratio 0.9)
				(enabled yes)
				(allow_two_segments yes)
				(prefer_zone_connections yes)
			)
		)
		(pad "6" smd roundrect
			(at 4.265 -0.645)
			(size 0.85 0.34)
			(layers "F.Cu" "F.Mask" "F.Paste")
			(roundrect_rratio 0.1)
			(net 295 "/2xUSB3.0+RJ45/GbE.MDI0+")
			(pinfunction "6")
			(pintype "passive")
			(teardrops
				(best_length_ratio 0.2)
				(max_length 1)
				(best_width_ratio 0.9)
				(max_width 2)
				(curved_edges yes)
				(filter_ratio 0.9)
				(enabled yes)
				(allow_two_segments yes)
				(prefer_zone_connections yes)
			)
		)
		(pad "7" smd roundrect
			(at 4.205 -1.43)
			(size 0.97 0.33)
			(layers "F.Cu" "F.Mask" "F.Paste")
			(roundrect_rratio 0.1)
			(net 294 "/2xUSB3.0+RJ45/GbE.MDI0-")
			(pinfunction "7")
			(pintype "passive")
			(teardrops
				(best_length_ratio 0.2)
				(max_length 1)
				(best_width_ratio 0.9)
				(max_width 2)
				(curved_edges yes)
				(filter_ratio 0.9)
				(enabled yes)
				(allow_two_segments yes)
				(prefer_zone_connections yes)
			)
		)
	)
	(footprint "antmicro-footprints:C_0402_1005Metric"
		(layer "F.Cu")
		(at 300.55 102.81 90)
		(descr "Capacitor SMD 0402")
		(tags "capacitor SMD 0402")
		(property "Reference" "C57"
			(at -3 0.45 90)
			(layer "F.SilkS")
			(effects
				(font
					(size 0.7 0.7)
					(thickness 0.15)
				)
				(justify left bottom)
			)
		)
		(property "Value" "C_1u_0402"
			(at -1.022927 2.155213 90)
			(layer "F.Fab")
			(effects
				(font
					(size 0.7 0.7)
					(thickness 0.15)
				)
				(justify left bottom)
			)
		)
		(property "Datasheet" "https://product.tdk.com/en/search/capacitor/ceramic/mlcc/info?part_no=C1005X6S1A105K050BC"
			(at 0 0 90)
			(layer "F.Fab")
			(hide yes)
			(effects
				(font
					(size 1.27 1.27)
					(thickness 0.15)
				)
			)
		)
		(property "Author" "Antmicro"
			(at 403.36 -197.74 0)
			(layer "F.Fab")
			(hide yes)
			(effects
				(font
					(size 1 1)
					(thickness 0.15)
				)
			)
		)
		(property "Dielectric" ""
			(at 403.36 -197.74 0)
			(layer "F.Fab")
			(hide yes)
			(effects
				(font
					(size 1 1)
					(thickness 0.15)
				)
			)
		)
		(property "License" "Apache-2.0"
			(at 403.36 -197.74 0)
			(layer "F.Fab")
			(hide yes)
			(effects
				(font
					(size 1 1)
					(thickness 0.15)
				)
			)
		)
		(property "MPN" "C1005X6S1A105K050BC"
			(at 403.36 -197.74 0)
			(layer "F.Fab")
			(hide yes)
			(effects
				(font
					(size 1 1)
					(thickness 0.15)
				)
			)
		)
		(property "Manufacturer" "TDK"
			(at 403.36 -197.74 0)
			(layer "F.Fab")
			(hide yes)
			(effects
				(font
					(size 1 1)
					(thickness 0.15)
				)
			)
		)
		(property "Public" "False"
			(at 403.36 -197.74 0)
			(layer "F.Fab")
			(hide yes)
			(effects
				(font
					(size 1 1)
					(thickness 0.15)
				)
			)
		)
		(property "Val" "1u"
			(at 403.36 -197.74 0)
			(layer "F.Fab")
			(hide yes)
			(effects
				(font
					(size 1 1)
					(thickness 0.15)
				)
			)
		)
		(property "Voltage" ""
			(at 403.36 -197.74 0)
			(layer "F.Fab")
			(hide yes)
			(effects
				(font
					(size 1 1)
					(thickness 0.15)
				)
			)
		)
		(sheetname "Power")
		(sheetfile "power.kicad_sch")
		(attr smd)
		(fp_rect
			(start -0.925 -0.47)
			(end 0.925 0.47)
			(stroke
				(width 0.05)
				(type default)
			)
			(fill no)
			(layer "F.CrtYd")
		)
		(fp_line
			(start 0.504 -0.25)
			(end 0.504 0.248)
			(stroke
				(width 0.15)
				(type solid)
			)
			(layer "F.Fab")
		)
		(fp_line
			(start -0.494 -0.25)
			(end 0.504 -0.25)
			(stroke
				(width 0.15)
				(type solid)
			)
			(layer "F.Fab")
		)
		(fp_line
			(start 0.504 0.248)
			(end -0.494 0.248)
			(stroke
				(width 0.15)
				(type solid)
			)
			(layer "F.Fab")
		)
		(fp_line
			(start -0.494 0.248)
			(end -0.494 -0.25)
			(stroke
				(width 0.15)
				(type solid)
			)
			(layer "F.Fab")
		)
		(pad "1" smd roundrect
			(at -0.48 0 90)
			(size 0.59 0.64)
			(layers "F.Cu" "F.Mask" "F.Paste")
			(roundrect_rratio 0.25)
			(net 1 "GND")
			(pintype "passive")
			(teardrops
				(best_length_ratio 0.2)
				(max_length 1)
				(best_width_ratio 0.9)
				(max_width 2)
				(curved_edges yes)
				(filter_ratio 0.9)
				(enabled yes)
				(allow_two_segments yes)
				(prefer_zone_connections yes)
			)
		)
		(pad "2" smd roundrect
			(at 0.48 0 90)
			(size 0.59 0.64)
			(layers "F.Cu" "F.Mask" "F.Paste")
			(roundrect_rratio 0.25)
			(net 2 "+3V3")
			(pintype "passive")
			(teardrops
				(best_length_ratio 0.2)
				(max_length 1)
				(best_width_ratio 0.9)
				(max_width 2)
				(curved_edges yes)
				(filter_ratio 0.9)
				(enabled yes)
				(allow_two_segments yes)
				(prefer_zone_connections yes)
			)
		)
	)
	(footprint "antmicro-footprints:TP_SMD_0.75mm"
		(layer "F.Cu")
		(at 144.65 129.56)
		(property "Reference" "TP58"
			(at 0.45 -1.25 90)
			(layer "F.SilkS")
			(effects
				(font
					(size 0.7 0.7)
					(thickness 0.15)
				)
				(justify left bottom)
			)
		)
		(property "Value" "TP_0.75mm_SMD"
			(at 0 1.2 0)
			(layer "F.Fab")
			(effects
				(font
					(size 0.7 0.7)
					(thickness 0.15)
				)
				(justify left bottom)
			)
		)
		(property "Author" "Antmicro"
			(at 0 0 0)
			(layer "F.Fab")
			(hide yes)
			(effects
				(font
					(size 1 1)
					(thickness 0.15)
				)
			)
		)
		(property "License" "Apache-2.0"
			(at 0 0 0)
			(layer "F.Fab")
			(hide yes)
			(effects
				(font
					(size 1 1)
					(thickness 0.15)
				)
			)
		)
		(property "MPN" ""
			(at 0 0 0)
			(layer "F.Fab")
			(hide yes)
			(effects
				(font
					(size 1 1)
					(thickness 0.15)
				)
			)
		)
		(property "Manufacturer" ""
			(at 0 0 0)
			(layer "F.Fab")
			(hide yes)
			(effects
				(font
					(size 1 1)
					(thickness 0.15)
				)
			)
		)
		(property "Public" "False"
			(at 0 0 0)
			(layer "F.Fab")
			(hide yes)
			(effects
				(font
					(size 1 1)
					(thickness 0.15)
				)
			)
		)
		(sheetname "KR to SFI #1")
		(sheetfile "kr_sfi.kicad_sch")
		(attr exclude_from_pos_files exclude_from_bom)
		(fp_circle
			(center 0 0)
			(end 0.475 0)
			(stroke
				(width 0.05)
				(type default)
			)
			(fill no)
			(layer "F.CrtYd")
		)
		(pad "1" smd circle
			(at 0 0)
			(size 0.75 0.75)
			(layers "F.Cu" "F.Mask")
			(net 721 "Net-(U43C-REFCLK1-)")
			(pinfunction "1")
			(pintype "passive")
			(teardrops
				(best_length_ratio 0.4)
				(max_length 1)
				(best_width_ratio 0.9)
				(max_width 2)
				(curved_edges yes)
				(filter_ratio 0.9)
				(enabled yes)
				(allow_two_segments yes)
				(prefer_zone_connections yes)
			)
		)
	)
	(footprint "antmicro-footprints:C_0402_1005Metric"
		(layer "F.Cu")
		(at 193.280022 137.754586 -45)
		(descr "Capacitor SMD 0402")
		(tags "capacitor SMD 0402")
		(property "Reference" "C121"
			(at 3.864615 -0.381761 135)
			(layer "F.SilkS")
			(effects
				(font
					(size 0.7 0.7)
					(thickness 0.15)
				)
				(justify right top)
			)
		)
		(property "Value" "C_100n_0402"
			(at -1.022927 2.155213 135)
			(layer "F.Fab")
			(effects
				(font
					(size 0.7 0.7)
					(thickness 0.15)
				)
				(justify right top)
			)
		)
		(property "Datasheet" "https://www.murata.com/products/productdetail?partno=GRM155R61H104KE14%23"
			(at 0 0 135)
			(layer "B.Fab")
			(hide yes)
			(effects
				(font
					(size 1.27 1.27)
					(thickness 0.15)
				)
				(justify mirror)
			)
		)
		(property "Author" "Antmicro"
			(at 54.168 -327.134 45)
			(layer "F.Fab")
			(hide yes)
			(effects
				(font
					(size 1 1)
					(thickness 0.15)
				)
			)
		)
		(property "Dielectric" "X5R"
			(at 54.168 -327.134 45)
			(layer "F.Fab")
			(hide yes)
			(effects
				(font
					(size 1 1)
					(thickness 0.15)
				)
			)
		)
		(property "License" "Apache-2.0"
			(at 54.168 -327.134 45)
			(layer "F.Fab")
			(hide yes)
			(effects
				(font
					(size 1 1)
					(thickness 0.15)
				)
			)
		)
		(property "MPN" "GRM155R61H104KE14D"
			(at 54.168 -327.134 45)
			(layer "F.Fab")
			(hide yes)
			(effects
				(font
					(size 1 1)
					(thickness 0.15)
				)
			)
		)
		(property "Manufacturer" "Murata"
			(at 54.168 -327.134 45)
			(layer "F.Fab")
			(hide yes)
			(effects
				(font
					(size 1 1)
					(thickness 0.15)
				)
			)
		)
		(property "Public" "False"
			(at 54.168 -327.134 45)
			(layer "F.Fab")
			(hide yes)
			(effects
				(font
					(size 1 1)
					(thickness 0.15)
				)
			)
		)
		(property "Val" "100n"
			(at 54.168 -327.134 45)
			(layer "F.Fab")
			(hide yes)
			(effects
				(font
					(size 1 1)
					(thickness 0.15)
				)
			)
		)
		(property "Voltage" "50V"
			(at 54.168 -327.134 45)
			(layer "F.Fab")
			(hide yes)
			(effects
				(font
					(size 1 1)
					(thickness 0.15)
				)
			)
		)
		(sheetname "PCIe redriver")
		(sheetfile "pcie_redriver.kicad_sch")
		(attr smd)
		(fp_poly
			(pts
				(xy -0.925 -0.47) (xy 0.925 -0.47) (xy 0.925 0.47) (xy -0.925 0.47)
			)
			(stroke
				(width 0.05)
				(type default)
			)
			(fill no)
			(layer "F.CrtYd")
		)
		(fp_line
			(start -0.494 0.248)
			(end -0.494 -0.25)
			(stroke
				(width 0.15)
				(type solid)
			)
			(layer "F.Fab")
		)
		(fp_line
			(start -0.494 -0.25)
			(end 0.504 -0.25)
			(stroke
				(width 0.15)
				(type solid)
			)
			(layer "F.Fab")
		)
		(fp_line
			(start 0.504 0.248)
			(end -0.494 0.248)
			(stroke
				(width 0.15)
				(type solid)
			)
			(layer "F.Fab")
		)
		(fp_line
			(start 0.504 -0.25)
			(end 0.504 0.248)
			(stroke
				(width 0.15)
				(type solid)
			)
			(layer "F.Fab")
		)
		(pad "1" smd roundrect
			(at -0.48 0 315)
			(size 0.59 0.64)
			(layers "F.Cu" "F.Mask" "F.Paste")
			(roundrect_rratio 0.25)
			(net 1 "GND")
			(pintype "passive")
			(teardrops
				(best_length_ratio 0.2)
				(max_length 1)
				(best_width_ratio 0.9)
				(max_width 2)
				(curved_edges yes)
				(filter_ratio 0.9)
				(enabled yes)
				(allow_two_segments yes)
				(prefer_zone_connections yes)
			)
		)
		(pad "2" smd roundrect
			(at 0.48 0 315)
			(size 0.59 0.64)
			(layers "F.Cu" "F.Mask" "F.Paste")
			(roundrect_rratio 0.25)
			(net 2 "+3V3")
			(pintype "passive")
			(teardrops
				(best_length_ratio 0.2)
				(max_length 1)
				(best_width_ratio 0.9)
				(max_width 2)
				(curved_edges yes)
				(filter_ratio 0.9)
				(enabled yes)
				(allow_two_segments yes)
				(prefer_zone_connections yes)
			)
		)
	)
	(footprint "antmicro-footprints:SOT-563"
		(layer "F.Cu")
		(at 312.4005 95.1365 -90)
		(property "Reference" "U21"
			(at -3.6265 -3.5995 180)
			(layer "F.SilkS")
			(effects
				(font
					(size 0.7 0.7)
					(thickness 0.15)
				)
				(justify right bottom)
			)
		)
		(property "Value" "TPS564247DRLR"
			(at 0 2.000001 90)
			(layer "F.Fab")
			(effects
				(font
					(size 0.7 0.7)
					(thickness 0.15)
				)
				(justify right bottom)
			)
		)
		(property "Datasheet" "https://www.ti.com/lit/ds/symlink/tps564247.pdf?ts=1713526387938&ref_url=https%253A%252F%252Fwww.mouser.pl%252F"
			(at 0 0 270)
			(layer "F.Fab")
			(hide yes)
			(effects
				(font
					(size 1.27 1.27)
					(thickness 0.15)
				)
			)
		)
		(property "Author" "Antmicro"
			(at 217.264 407.537 0)
			(layer "F.Fab")
			(hide yes)
			(effects
				(font
					(size 1 1)
					(thickness 0.15)
				)
			)
		)
		(property "License" "Apache-2.0"
			(at 217.264 407.537 0)
			(layer "F.Fab")
			(hide yes)
			(effects
				(font
					(size 1 1)
					(thickness 0.15)
				)
			)
		)
		(property "MPN" "TPS564247DRLR"
			(at 217.264 407.537 0)
			(layer "F.Fab")
			(hide yes)
			(effects
				(font
					(size 1 1)
					(thickness 0.15)
				)
			)
		)
		(property "Manufacturer" "Texas Instruments"
			(at 217.264 407.537 0)
			(layer "F.Fab")
			(hide yes)
			(effects
				(font
					(size 1 1)
					(thickness 0.15)
				)
			)
		)
		(sheetname "Power")
		(sheetfile "power.kicad_sch")
		(attr smd)
		(fp_line
			(start 0.776 0.972)
			(end 0.526 0.972)
			(stroke
				(width 0.15)
				(type solid)
			)
			(layer "F.SilkS")
		)
		(fp_line
			(start -0.778 0.949)
			(end -0.424 0.949)
			(stroke
				(width 0.15)
				(type solid)
			)
			(layer "F.SilkS")
		)
		(fp_line
			(start -0.778 0.776)
			(end -0.778 0.949)
			(stroke
				(width 0.15)
				(type solid)
			)
			(layer "F.SilkS")
		)
		(fp_line
			(start 0.776 0.776)
			(end 0.776 0.972)
			(stroke
				(width 0.15)
				(type solid)
			)
			(layer "F.SilkS")
		)
		(fp_line
			(start -0.499 -0.974)
			(end -0.724 -0.778)
			(stroke
				(width 0.15)
				(type solid)
			)
			(layer "F.SilkS")
		)
		(fp_line
			(start 0.776 -0.974)
			(end 0.776 -0.778)
			(stroke
				(width 0.15)
				(type solid)
			)
			(layer "F.SilkS")
		)
		(fp_line
			(start 0.776 -0.974)
			(end 0.526 -0.974)
			(stroke
				(width 0.15)
				(type solid)
			)
			(layer "F.SilkS")
		)
		(fp_circle
			(center -0.903 -0.999)
			(end -0.952 -0.95)
			(stroke
				(width 0.15)
				(type solid)
			)
			(fill yes)
			(layer "F.SilkS")
		)
		(fp_rect
			(start 1.19 -1.12)
			(end -1.2 1.1)
			(stroke
				(width 0.05)
				(type solid)
			)
			(fill no)
			(layer "F.CrtYd")
		)
		(fp_line
			(start 0.651 0.847)
			(end -0.653 0.847)
			(stroke
				(width 0.15)
				(type solid)
			)
			(layer "F.Fab")
		)
		(fp_line
			(start -0.653 -0.678)
			(end -0.653 0.847)
			(stroke
				(width 0.15)
				(type solid)
			)
			(layer "F.Fab")
		)
		(fp_line
			(start -0.453 -0.849)
			(end -0.653 -0.678)
			(stroke
				(width 0.15)
				(type solid)
			)
			(layer "F.Fab")
		)
		(fp_line
			(start -0.453 -0.849)
			(end 0.651 -0.849)
			(stroke
				(width 0.15)
				(type solid)
			)
			(layer "F.Fab")
		)
		(fp_line
			(start 0.651 -0.849)
			(end 0.651 0.847)
			(stroke
				(width 0.15)
				(type solid)
			)
			(layer "F.Fab")
		)
		(pad "1" smd roundrect
			(at -0.749 -0.499 180)
			(size 0.3 0.6)
			(layers "F.Cu" "F.Mask" "F.Paste")
			(roundrect_rratio 0.25)
			(net 62 "+12V_AON")
			(pinfunction "V_{IN}")
			(pintype "power_in")
			(teardrops
				(best_length_ratio 0.2)
				(max_length 1)
				(best_width_ratio 0.9)
				(max_width 2)
				(curved_edges yes)
				(filter_ratio 0.9)
				(enabled yes)
				(allow_two_segments yes)
				(prefer_zone_connections yes)
			)
		)
		(pad "2" smd roundrect
			(at -0.749 0.001 180)
			(size 0.3 0.6)
			(layers "F.Cu" "F.Mask" "F.Paste")
			(roundrect_rratio 0.25)
			(net 870 "Net-(U21-SW)")
			(pinfunction "SW")
			(pintype "passive")
			(teardrops
				(best_length_ratio 0.2)
				(max_length 1)
				(best_width_ratio 0.9)
				(max_width 2)
				(curved_edges yes)
				(filter_ratio 0.9)
				(enabled yes)
				(allow_two_segments yes)
				(prefer_zone_connections yes)
			)
		)
		(pad "3" smd roundrect
			(at -0.749 0.497 180)
			(size 0.3 0.6)
			(layers "F.Cu" "F.Mask" "F.Paste")
			(roundrect_rratio 0.25)
			(net 1 "GND")
			(pinfunction "GND")
			(pintype "power_in")
			(teardrops
				(best_length_ratio 0.2)
				(max_length 1)
				(best_width_ratio 0.9)
				(max_width 2)
				(curved_edges yes)
				(filter_ratio 0.9)
				(enabled yes)
				(allow_two_segments yes)
				(prefer_zone_connections yes)
			)
		)
		(pad "4" smd roundrect
			(at 0.747 0.497 180)
			(size 0.3 0.6)
			(layers "F.Cu" "F.Mask" "F.Paste")
			(roundrect_rratio 0.25)
			(net 1 "GND")
			(pinfunction "AGND")
			(pintype "power_in")
			(teardrops
				(best_length_ratio 0.2)
				(max_length 1)
				(best_width_ratio 0.9)
				(max_width 2)
				(curved_edges yes)
				(filter_ratio 0.9)
				(enabled yes)
				(allow_two_segments yes)
				(prefer_zone_connections yes)
			)
		)
		(pad "5" smd roundrect
			(at 0.747 0.001 180)
			(size 0.3 0.6)
			(layers "F.Cu" "F.Mask" "F.Paste")
			(roundrect_rratio 0.25)
			(net 584 "Net-(U21-EN)")
			(pinfunction "EN")
			(pintype "passive")
			(teardrops
				(best_length_ratio 0.2)
				(max_length 1)
				(best_width_ratio 0.9)
				(max_width 2)
				(curved_edges yes)
				(filter_ratio 0.9)
				(enabled yes)
				(allow_two_segments yes)
				(prefer_zone_connections yes)
			)
		)
		(pad "6" smd roundrect
			(at 0.747 -0.499 180)
			(size 0.3 0.6)
			(layers "F.Cu" "F.Mask" "F.Paste")
			(roundrect_rratio 0.25)
			(net 585 "Net-(U21-FB)")
			(pinfunction "FB")
			(pintype "passive")
			(teardrops
				(best_length_ratio 0.2)
				(max_length 1)
				(best_width_ratio 0.9)
				(max_width 2)
				(curved_edges yes)
				(filter_ratio 0.9)
				(enabled yes)
				(allow_two_segments yes)
				(prefer_zone_connections yes)
			)
		)
	)
	(footprint "antmicro-footprints:C_0402_1005Metric"
		(layer "F.Cu")
		(at 129.5 99.49 -90)
		(descr "Capacitor SMD 0402")
		(tags "capacitor SMD 0402")
		(property "Reference" "C15"
			(at -1.13 0.5 90)
			(layer "F.SilkS")
			(effects
				(font
					(size 0.7 0.7)
					(thickness 0.15)
				)
				(justify right bottom)
			)
		)
		(property "Value" "C_100n_0402"
			(at -1.022927 2.155213 90)
			(layer "F.Fab")
			(effects
				(font
					(size 0.7 0.7)
					(thickness 0.15)
				)
				(justify right bottom)
			)
		)
		(property "Datasheet" "https://www.murata.com/products/productdetail?partno=GRM155R61H104KE14%23"
			(at 0 0 270)
			(layer "F.Fab")
			(hide yes)
			(effects
				(font
					(size 1.27 1.27)
					(thickness 0.15)
				)
			)
		)
		(property "Author" "Antmicro"
			(at 30.01 228.99 0)
			(layer "F.Fab")
			(hide yes)
			(effects
				(font
					(size 1 1)
					(thickness 0.15)
				)
			)
		)
		(property "Dielectric" "X5R"
			(at 30.01 228.99 0)
			(layer "F.Fab")
			(hide yes)
			(effects
				(font
					(size 1 1)
					(thickness 0.15)
				)
			)
		)
		(property "License" "Apache-2.0"
			(at 30.01 228.99 0)
			(layer "F.Fab")
			(hide yes)
			(effects
				(font
					(size 1 1)
					(thickness 0.15)
				)
			)
		)
		(property "MPN" "GRM155R61H104KE14D"
			(at 30.01 228.99 0)
			(layer "F.Fab")
			(hide yes)
			(effects
				(font
					(size 1 1)
					(thickness 0.15)
				)
			)
		)
		(property "Manufacturer" "Murata"
			(at 30.01 228.99 0)
			(layer "F.Fab")
			(hide yes)
			(effects
				(font
					(size 1 1)
					(thickness 0.15)
				)
			)
		)
		(property "Public" "False"
			(at 30.01 228.99 0)
			(layer "F.Fab")
			(hide yes)
			(effects
				(font
					(size 1 1)
					(thickness 0.15)
				)
			)
		)
		(property "Val" "100n"
			(at 30.01 228.99 0)
			(layer "F.Fab")
			(hide yes)
			(effects
				(font
					(size 1 1)
					(thickness 0.15)
				)
			)
		)
		(property "Voltage" "50V"
			(at 30.01 228.99 0)
			(layer "F.Fab")
			(hide yes)
			(effects
				(font
					(size 1 1)
					(thickness 0.15)
				)
			)
		)
		(sheetname "2xUSB3.0+RJ45")
		(sheetfile "usb3+rj45.kicad_sch")
		(attr smd)
		(fp_rect
			(start -0.925 -0.47)
			(end 0.925 0.47)
			(stroke
				(width 0.05)
				(type default)
			)
			(fill no)
			(layer "F.CrtYd")
		)
		(fp_line
			(start -0.494 0.248)
			(end -0.494 -0.25)
			(stroke
				(width 0.15)
				(type solid)
			)
			(layer "F.Fab")
		)
		(fp_line
			(start 0.504 0.248)
			(end -0.494 0.248)
			(stroke
				(width 0.15)
				(type solid)
			)
			(layer "F.Fab")
		)
		(fp_line
			(start -0.494 -0.25)
			(end 0.504 -0.25)
			(stroke
				(width 0.15)
				(type solid)
			)
			(layer "F.Fab")
		)
		(fp_line
			(start 0.504 -0.25)
			(end 0.504 0.248)
			(stroke
				(width 0.15)
				(type solid)
			)
			(layer "F.Fab")
		)
		(pad "1" smd roundrect
			(at -0.48 0 270)
			(size 0.59 0.64)
			(layers "F.Cu" "F.Mask" "F.Paste")
			(roundrect_rratio 0.25)
			(net 51 "Net-(C13-Pad1)")
			(pintype "passive")
			(teardrops
				(best_length_ratio 0.2)
				(max_length 1)
				(best_width_ratio 0.9)
				(max_width 2)
				(curved_edges yes)
				(filter_ratio 0.9)
				(enabled yes)
				(allow_two_segments yes)
				(prefer_zone_connections yes)
			)
		)
		(pad "2" smd roundrect
			(at 0.48 0 270)
			(size 0.59 0.64)
			(layers "F.Cu" "F.Mask" "F.Paste")
			(roundrect_rratio 0.25)
			(net 1 "GND")
			(pintype "passive")
			(teardrops
				(best_length_ratio 0.2)
				(max_length 1)
				(best_width_ratio 0.9)
				(max_width 2)
				(curved_edges yes)
				(filter_ratio 0.9)
				(enabled yes)
				(allow_two_segments yes)
				(prefer_zone_connections yes)
			)
		)
	)
	(footprint "antmicro-footprints:R_0402_1005Metric"
		(layer "F.Cu")
		(at 112.9 145.86 180)
		(descr "Resistor SMD 0402")
		(tags "resistor SMD 0402")
		(property "Reference" "R203"
			(at 0.85 -0.45 0)
			(layer "F.SilkS")
			(effects
				(font
					(size 0.7 0.7)
					(thickness 0.15)
				)
				(justify right bottom)
			)
		)
		(property "Value" "R_1k_0402"
			(at -1.011843 1.772047 0)
			(layer "F.Fab")
			(effects
				(font
					(size 0.7 0.7)
					(thickness 0.15)
				)
				(justify right bottom)
			)
		)
		(property "Datasheet" "https://www.bourns.com/docs/product-datasheets/cr.pdf"
			(at 0 0 180)
			(layer "F.Fab")
			(hide yes)
			(effects
				(font
					(size 1.27 1.27)
					(thickness 0.15)
				)
			)
		)
		(property "Author" "Antmicro"
			(at 225.8 291.72 0)
			(layer "F.Fab")
			(hide yes)
			(effects
				(font
					(size 1 1)
					(thickness 0.15)
				)
			)
		)
		(property "License" "Apache-2.0"
			(at 225.8 291.72 0)
			(layer "F.Fab")
			(hide yes)
			(effects
				(font
					(size 1 1)
					(thickness 0.15)
				)
			)
		)
		(property "MPN" "CR0402-FX-1001GLF"
			(at 225.8 291.72 0)
			(layer "F.Fab")
			(hide yes)
			(effects
				(font
					(size 1 1)
					(thickness 0.15)
				)
			)
		)
		(property "Manufacturer" "Bourns"
			(at 225.8 291.72 0)
			(layer "F.Fab")
			(hide yes)
			(effects
				(font
					(size 1 1)
					(thickness 0.15)
				)
			)
		)
		(property "Public" "False"
			(at 225.8 291.72 0)
			(layer "F.Fab")
			(hide yes)
			(effects
				(font
					(size 1 1)
					(thickness 0.15)
				)
			)
		)
		(property "Tolerance" "1%"
			(at 225.8 291.72 0)
			(layer "F.Fab")
			(hide yes)
			(effects
				(font
					(size 1 1)
					(thickness 0.15)
				)
			)
		)
		(property "Val" "1k"
			(at 225.8 291.72 0)
			(layer "F.Fab")
			(hide yes)
			(effects
				(font
					(size 1 1)
					(thickness 0.15)
				)
			)
		)
		(sheetname "PCIe redriver")
		(sheetfile "pcie_redriver.kicad_sch")
		(attr smd dnp)
		(fp_rect
			(start -0.925 -0.47)
			(end 0.925 0.47)
			(stroke
				(width 0.05)
				(type default)
			)
			(fill no)
			(layer "F.CrtYd")
		)
		(fp_rect
			(start -0.5 -0.25)
			(end 0.5 0.25)
			(stroke
				(width 0.15)
				(type solid)
			)
			(fill no)
			(layer "F.Fab")
		)
		(pad "1" smd roundrect
			(at -0.48 0 180)
			(size 0.59 0.64)
			(layers "F.Cu" "F.Mask" "F.Paste")
			(roundrect_rratio 0.25)
			(net 1 "GND")
			(pintype "passive")
			(teardrops
				(best_length_ratio 0.2)
				(max_length 1)
				(best_width_ratio 0.9)
				(max_width 2)
				(curved_edges yes)
				(filter_ratio 0.9)
				(enabled yes)
				(allow_two_segments yes)
				(prefer_zone_connections yes)
			)
		)
		(pad "2" smd roundrect
			(at 0.48 0 180)
			(size 0.59 0.64)
			(layers "F.Cu" "F.Mask" "F.Paste")
			(roundrect_rratio 0.25)
			(net 623 "/PCIe redriver/TX_EQ0")
			(pintype "passive")
			(teardrops
				(best_length_ratio 0.2)
				(max_length 1)
				(best_width_ratio 0.9)
				(max_width 2)
				(curved_edges yes)
				(filter_ratio 0.9)
				(enabled yes)
				(allow_two_segments yes)
				(prefer_zone_connections yes)
			)
		)
	)
	(footprint "antmicro-footprints:C_0603_1608Metric"
		(layer "F.Cu")
		(at 314.275499 134.21 90)
		(descr "Capacitor SMD 0603")
		(tags "capacitor 0603")
		(property "Reference" "C61"
			(at 1.15 0.674501 90)
			(layer "F.SilkS")
			(effects
				(font
					(size 0.7 0.7)
					(thickness 0.15)
				)
				(justify left bottom)
			)
		)
		(property "Value" "C_22u_16V_0603"
			(at -1.42757 1.770288 90)
			(layer "F.Fab")
			(effects
				(font
					(size 0.7 0.7)
					(thickness 0.15)
				)
				(justify left bottom)
			)
		)
		(property "Datasheet" "https://product.samsungsem.com/mlcc/CL10A226MO7JZN.do"
			(at 0 0 90)
			(layer "F.Fab")
			(hide yes)
			(effects
				(font
					(size 1.27 1.27)
					(thickness 0.15)
				)
			)
		)
		(property "Author" "Antmicro"
			(at 448.485499 -180.065499 0)
			(layer "F.Fab")
			(hide yes)
			(effects
				(font
					(size 1 1)
					(thickness 0.15)
				)
			)
		)
		(property "Dielectric" ""
			(at 448.485499 -180.065499 0)
			(layer "F.Fab")
			(hide yes)
			(effects
				(font
					(size 1 1)
					(thickness 0.15)
				)
			)
		)
		(property "License" "Apache-2.0"
			(at 448.485499 -180.065499 0)
			(layer "F.Fab")
			(hide yes)
			(effects
				(font
					(size 1 1)
					(thickness 0.15)
				)
			)
		)
		(property "MPN" "CL10A226MO7JZNC"
			(at 448.485499 -180.065499 0)
			(layer "F.Fab")
			(hide yes)
			(effects
				(font
					(size 1 1)
					(thickness 0.15)
				)
			)
		)
		(property "Manufacturer" "Samsung Electro-Mechanics"
			(at 448.485499 -180.065499 0)
			(layer "F.Fab")
			(hide yes)
			(effects
				(font
					(size 1 1)
					(thickness 0.15)
				)
			)
		)
		(property "Public" "False"
			(at 448.485499 -180.065499 0)
			(layer "F.Fab")
			(hide yes)
			(effects
				(font
					(size 1 1)
					(thickness 0.15)
				)
			)
		)
		(property "Val" "22u"
			(at 448.485499 -180.065499 0)
			(layer "F.Fab")
			(hide yes)
			(effects
				(font
					(size 1 1)
					(thickness 0.15)
				)
			)
		)
		(property "Voltage" "16V"
			(at 448.485499 -180.065499 0)
			(layer "F.Fab")
			(hide yes)
			(effects
				(font
					(size 1 1)
					(thickness 0.15)
				)
			)
		)
		(sheetname "Power")
		(sheetfile "power.kicad_sch")
		(attr smd)
		(fp_line
			(start -0.15 -0.4)
			(end 0.15 -0.4)
			(stroke
				(width 0.15)
				(type solid)
			)
			(layer "F.SilkS")
		)
		(fp_line
			(start -0.15 0.4)
			(end 0.15 0.4)
			(stroke
				(width 0.15)
				(type solid)
			)
			(layer "F.SilkS")
		)
		(fp_rect
			(start -1.25 -0.65)
			(end 1.25 0.65)
			(stroke
				(width 0.05)
				(type solid)
			)
			(fill no)
			(layer "F.CrtYd")
		)
		(fp_rect
			(start -0.8 -0.4)
			(end 0.8 0.4)
			(stroke
				(width 0.15)
				(type solid)
			)
			(fill no)
			(layer "F.Fab")
		)
		(pad "1" smd roundrect
			(at -0.7 0 90)
			(size 0.8 1)
			(layers "F.Cu" "F.Mask" "F.Paste")
			(roundrect_rratio 0.2)
			(net 1 "GND")
			(pintype "passive")
			(teardrops
				(best_length_ratio 0.2)
				(max_length 1)
				(best_width_ratio 0.9)
				(max_width 2)
				(curved_edges yes)
				(filter_ratio 0.9)
				(enabled yes)
				(allow_two_segments yes)
				(prefer_zone_connections yes)
			)
		)
		(pad "2" smd roundrect
			(at 0.7 0 90)
			(size 0.8 1)
			(layers "F.Cu" "F.Mask" "F.Paste")
			(roundrect_rratio 0.2)
			(net 62 "+12V_AON")
			(pintype "passive")
			(teardrops
				(best_length_ratio 0.2)
				(max_length 1)
				(best_width_ratio 0.9)
				(max_width 2)
				(curved_edges yes)
				(filter_ratio 0.9)
				(enabled yes)
				(allow_two_segments yes)
				(prefer_zone_connections yes)
			)
		)
	)
	(footprint "antmicro-footprints:R_0402_1005Metric"
		(layer "F.Cu")
		(at 130.15 89.51 -90)
		(descr "Resistor SMD 0402")
		(tags "resistor SMD 0402")
		(property "Reference" "R245"
			(at 0.799999 -0.4 90)
			(layer "F.SilkS")
			(effects
				(font
					(size 0.7 0.7)
					(thickness 0.15)
				)
				(justify right bottom)
			)
		)
		(property "Value" "R_0R_0402"
			(at -1.011843 1.772047 90)
			(layer "F.Fab")
			(effects
				(font
					(size 0.7 0.7)
					(thickness 0.15)
				)
				(justify right bottom)
			)
		)
		(property "Datasheet" "https://industrial.panasonic.com/cdbs/www-data/pdf/RDA0000/AOA0000C301.pdf"
			(at 0 0 270)
			(layer "F.Fab")
			(hide yes)
			(effects
				(font
					(size 1.27 1.27)
					(thickness 0.15)
				)
			)
		)
		(property "Author" "Antmicro"
			(at 40.64 219.66 0)
			(layer "F.Fab")
			(hide yes)
			(effects
				(font
					(size 1 1)
					(thickness 0.15)
				)
			)
		)
		(property "Current" "1A"
			(at 40.64 219.66 0)
			(layer "F.Fab")
			(hide yes)
			(effects
				(font
					(size 1 1)
					(thickness 0.15)
				)
			)
		)
		(property "License" "Apache-2.0"
			(at 40.64 219.66 0)
			(layer "F.Fab")
			(hide yes)
			(effects
				(font
					(size 1 1)
					(thickness 0.15)
				)
			)
		)
		(property "MPN" "ERJ2GE0R00X"
			(at 40.64 219.66 0)
			(layer "F.Fab")
			(hide yes)
			(effects
				(font
					(size 1 1)
					(thickness 0.15)
				)
			)
		)
		(property "Manufacturer" "Panasonic"
			(at 40.64 219.66 0)
			(layer "F.Fab")
			(hide yes)
			(effects
				(font
					(size 1 1)
					(thickness 0.15)
				)
			)
		)
		(property "Public" "False"
			(at 40.64 219.66 0)
			(layer "F.Fab")
			(hide yes)
			(effects
				(font
					(size 1 1)
					(thickness 0.15)
				)
			)
		)
		(property "Tolerance" ""
			(at 40.64 219.66 0)
			(layer "F.Fab")
			(hide yes)
			(effects
				(font
					(size 1 1)
					(thickness 0.15)
				)
			)
		)
		(property "Val" "0R"
			(at 40.64 219.66 0)
			(layer "F.Fab")
			(hide yes)
			(effects
				(font
					(size 1 1)
					(thickness 0.15)
				)
			)
		)
		(sheetname "GPIO expander")
		(sheetfile "gpio_exp.kicad_sch")
		(attr smd)
		(fp_rect
			(start -0.925 -0.47)
			(end 0.925 0.47)
			(stroke
				(width 0.05)
				(type default)
			)
			(fill no)
			(layer "F.CrtYd")
		)
		(fp_rect
			(start -0.5 -0.25)
			(end 0.5 0.25)
			(stroke
				(width 0.15)
				(type solid)
			)
			(fill no)
			(layer "F.Fab")
		)
		(pad "1" smd roundrect
			(at -0.48 0 270)
			(size 0.59 0.64)
			(layers "F.Cu" "F.Mask" "F.Paste")
			(roundrect_rratio 0.25)
			(net 646 "Net-(U41-IO0_7)")
			(pintype "passive")
			(teardrops
				(best_length_ratio 0.2)
				(max_length 1)
				(best_width_ratio 0.9)
				(max_width 2)
				(curved_edges yes)
				(filter_ratio 0.9)
				(enabled yes)
				(allow_two_segments yes)
				(prefer_zone_connections yes)
			)
		)
		(pad "2" smd roundrect
			(at 0.48 0 270)
			(size 0.59 0.64)
			(layers "F.Cu" "F.Mask" "F.Paste")
			(roundrect_rratio 0.25)
			(net 526 "/Backplane/~{PRSNT}")
			(pintype "passive")
			(teardrops
				(best_length_ratio 0.2)
				(max_length 1)
				(best_width_ratio 0.9)
				(max_width 2)
				(curved_edges yes)
				(filter_ratio 0.9)
				(enabled yes)
				(allow_two_segments yes)
				(prefer_zone_connections yes)
			)
		)
	)
	(footprint "antmicro-footprints:R_0402_1005Metric"
		(layer "F.Cu")
		(at 143.45 85.06 180)
		(descr "Resistor SMD 0402")
		(tags "resistor SMD 0402")
		(property "Reference" "R135"
			(at 0.85 -0.45 0)
			(layer "F.SilkS")
			(effects
				(font
					(size 0.7 0.7)
					(thickness 0.15)
				)
				(justify right bottom)
			)
		)
		(property "Value" "R_10k_0402"
			(at -1.011843 1.772047 0)
			(layer "F.Fab")
			(effects
				(font
					(size 0.7 0.7)
					(thickness 0.15)
				)
				(justify right bottom)
			)
		)
		(property "Datasheet" "https://www.bourns.com/docs/product-datasheets/cr.pdf"
			(at 0 0 180)
			(layer "F.Fab")
			(hide yes)
			(effects
				(font
					(size 1.27 1.27)
					(thickness 0.15)
				)
			)
		)
		(property "Author" "Antmicro"
			(at 286.9 170.12 0)
			(layer "F.Fab")
			(hide yes)
			(effects
				(font
					(size 1 1)
					(thickness 0.15)
				)
			)
		)
		(property "License" "Apache-2.0"
			(at 286.9 170.12 0)
			(layer "F.Fab")
			(hide yes)
			(effects
				(font
					(size 1 1)
					(thickness 0.15)
				)
			)
		)
		(property "MPN" "CR0402-FX-1002GLF"
			(at 286.9 170.12 0)
			(layer "F.Fab")
			(hide yes)
			(effects
				(font
					(size 1 1)
					(thickness 0.15)
				)
			)
		)
		(property "Manufacturer" "Bourns"
			(at 286.9 170.12 0)
			(layer "F.Fab")
			(hide yes)
			(effects
				(font
					(size 1 1)
					(thickness 0.15)
				)
			)
		)
		(property "Public" "False"
			(at 286.9 170.12 0)
			(layer "F.Fab")
			(hide yes)
			(effects
				(font
					(size 1 1)
					(thickness 0.15)
				)
			)
		)
		(property "Tolerance" "1%"
			(at 286.9 170.12 0)
			(layer "F.Fab")
			(hide yes)
			(effects
				(font
					(size 1 1)
					(thickness 0.15)
				)
			)
		)
		(property "Val" "10k"
			(at 286.9 170.12 0)
			(layer "F.Fab")
			(hide yes)
			(effects
				(font
					(size 1 1)
					(thickness 0.15)
				)
			)
		)
		(sheetname "M.2 key E")
		(sheetfile "m2keye.kicad_sch")
		(attr smd dnp)
		(fp_rect
			(start -0.925 -0.47)
			(end 0.925 0.47)
			(stroke
				(width 0.05)
				(type default)
			)
			(fill no)
			(layer "F.CrtYd")
		)
		(fp_rect
			(start -0.5 -0.25)
			(end 0.5 0.25)
			(stroke
				(width 0.15)
				(type solid)
			)
			(fill no)
			(layer "F.Fab")
		)
		(pad "1" smd roundrect
			(at -0.48 0 180)
			(size 0.59 0.64)
			(layers "F.Cu" "F.Mask" "F.Paste")
			(roundrect_rratio 0.25)
			(net 23 "/M.2 key E/~{PERST_D}")
			(pintype "passive")
			(teardrops
				(best_length_ratio 0.2)
				(max_length 1)
				(best_width_ratio 0.9)
				(max_width 2)
				(curved_edges yes)
				(filter_ratio 0.9)
				(enabled yes)
				(allow_two_segments yes)
				(prefer_zone_connections yes)
			)
		)
		(pad "2" smd roundrect
			(at 0.48 0 180)
			(size 0.59 0.64)
			(layers "F.Cu" "F.Mask" "F.Paste")
			(roundrect_rratio 0.25)
			(net 2 "+3V3")
			(pintype "passive")
			(teardrops
				(best_length_ratio 0.2)
				(max_length 1)
				(best_width_ratio 0.9)
				(max_width 2)
				(curved_edges yes)
				(filter_ratio 0.9)
				(enabled yes)
				(allow_two_segments yes)
				(prefer_zone_connections yes)
			)
		)
	)
	(footprint "antmicro-footprints:Mech_M2_2280_H2.5mm"
		(layer "F.Cu")
		(at 295.4495 157.485 180)
		(property "Reference" "A1"
			(at 0 8.89 0)
			(layer "F.SilkS")
			(hide yes)
			(effects
				(font
					(size 0.7 0.7)
					(thickness 0.15)
				)
				(justify left bottom)
			)
		)
		(property "Value" "Mech_M2_2280_H2.5mm"
			(at 0 6.857 0)
			(layer "F.Fab")
			(effects
				(font
					(size 0.7 0.7)
					(thickness 0.15)
				)
				(justify left bottom)
			)
		)
		(property "Author" "Antmicro"
			(at 590.899 314.97 0)
			(layer "F.Fab")
			(hide yes)
			(effects
				(font
					(size 1 1)
					(thickness 0.15)
				)
			)
		)
		(property "License" "Apache-2.0"
			(at 590.899 314.97 0)
			(layer "F.Fab")
			(hide yes)
			(effects
				(font
					(size 1 1)
					(thickness 0.15)
				)
			)
		)
		(property "MPN" ""
			(at 590.899 314.97 0)
			(layer "F.Fab")
			(hide yes)
			(effects
				(font
					(size 1 1)
					(thickness 0.15)
				)
			)
		)
		(property "Manufacturer" ""
			(at 590.899 314.97 0)
			(layer "F.Fab")
			(hide yes)
			(effects
				(font
					(size 1 1)
					(thickness 0.15)
				)
			)
		)
		(property "Public" "False"
			(at 590.899 314.97 0)
			(layer "F.Fab")
			(hide yes)
			(effects
				(font
					(size 1 1)
					(thickness 0.15)
				)
			)
		)
		(sheetname "M.2 key M #2")
		(sheetfile "m2keym.kicad_sch")
		(attr exclude_from_pos_files exclude_from_bom allow_missing_courtyard)
		(fp_rect
			(start -10.922 0.0508)
			(end 11.0236 80.0608)
			(stroke
				(width 0.15)
				(type solid)
			)
			(fill no)
			(layer "F.Fab")
		)
	)
	(footprint "antmicro-footprints:R_0201"
		(layer "F.Cu")
		(at 156.332 147.935 -90)
		(descr "Resistor SMD 0201")
		(tags "resistor SMD 0201")
		(property "Reference" "R254"
			(at 6.495 -0.618 270)
			(layer "F.SilkS")
			(effects
				(font
					(size 0.7 0.7)
					(thickness 0.15)
				)
				(justify left bottom)
			)
		)
		(property "Value" "R_0R_0201"
			(at 0 1.25 270)
			(layer "F.Fab")
			(effects
				(font
					(size 0.7 0.7)
					(thickness 0.15)
				)
				(justify left bottom)
			)
		)
		(property "Datasheet" "https://www.bourns.com/docs/product-datasheets/cr.pdf"
			(at 0 0 270)
			(layer "F.Fab")
			(hide yes)
			(effects
				(font
					(size 1.27 1.27)
					(thickness 0.15)
				)
			)
		)
		(property "Author" "Antmicro"
			(at 8.397 304.267 0)
			(layer "F.Fab")
			(hide yes)
			(effects
				(font
					(size 1 1)
					(thickness 0.15)
				)
			)
		)
		(property "License" "Apache-2.0"
			(at 8.397 304.267 0)
			(layer "F.Fab")
			(hide yes)
			(effects
				(font
					(size 1 1)
					(thickness 0.15)
				)
			)
		)
		(property "MPN" "CR0201-FX-0R00GLF"
			(at 8.397 304.267 0)
			(layer "F.Fab")
			(hide yes)
			(effects
				(font
					(size 1 1)
					(thickness 0.15)
				)
			)
		)
		(property "Manufacturer" "Bourns"
			(at 8.397 304.267 0)
			(layer "F.Fab")
			(hide yes)
			(effects
				(font
					(size 1 1)
					(thickness 0.15)
				)
			)
		)
		(property "Tolerance" "1%"
			(at 8.397 304.267 0)
			(layer "F.Fab")
			(hide yes)
			(effects
				(font
					(size 1 1)
					(thickness 0.15)
				)
			)
		)
		(property "Val" "0R"
			(at 8.397 304.267 0)
			(layer "F.Fab")
			(hide yes)
			(effects
				(font
					(size 1 1)
					(thickness 0.15)
				)
			)
		)
		(sheetname "KR to SFI #1")
		(sheetfile "kr_sfi.kicad_sch")
		(attr smd dnp)
		(fp_rect
			(start -0.7 -0.35)
			(end 0.7 0.35)
			(stroke
				(width 0.05)
				(type default)
			)
			(fill no)
			(layer "F.CrtYd")
		)
		(fp_rect
			(start -0.3 -0.15)
			(end 0.298 0.148)
			(stroke
				(width 0.15)
				(type solid)
			)
			(fill no)
			(layer "F.Fab")
		)
		(pad "" smd roundrect
			(at -0.346 0 270)
			(size 0.318 0.36)
			(layers "F.Paste")
			(roundrect_rratio 0.25)
			(teardrops
				(best_length_ratio 0.2)
				(max_length 1)
				(best_width_ratio 0.9)
				(max_width 2)
				(curved_edges yes)
				(filter_ratio 0.9)
				(enabled yes)
				(allow_two_segments yes)
				(prefer_zone_connections yes)
			)
		)
		(pad "" smd roundrect
			(at 0.344 0 270)
			(size 0.318 0.36)
			(layers "F.Paste")
			(roundrect_rratio 0.25)
			(teardrops
				(best_length_ratio 0.2)
				(max_length 1)
				(best_width_ratio 0.9)
				(max_width 2)
				(curved_edges yes)
				(filter_ratio 0.9)
				(enabled yes)
				(allow_two_segments yes)
				(prefer_zone_connections yes)
			)
		)
		(pad "1" smd roundrect
			(at -0.32 0 270)
			(size 0.46 0.4)
			(layers "F.Cu" "F.Mask")
			(roundrect_rratio 0.25)
			(net 113 "/2xSFP+/10GKR_SFP0.TX-")
			(pintype "passive")
			(teardrops
				(best_length_ratio 0.2)
				(max_length 1)
				(best_width_ratio 0.9)
				(max_width 2)
				(curved_edges yes)
				(filter_ratio 0.9)
				(enabled yes)
				(allow_two_segments yes)
				(prefer_zone_connections yes)
			)
		)
		(pad "2" smd roundrect
			(at 0.32 0 270)
			(size 0.46 0.4)
			(layers "F.Cu" "F.Mask")
			(roundrect_rratio 0.25)
			(net 948 "/2xSFP+/KR to SFI #1/BYP_TX-")
			(pintype "passive")
			(teardrops
				(best_length_ratio 0.2)
				(max_length 1)
				(best_width_ratio 0.9)
				(max_width 2)
				(curved_edges yes)
				(filter_ratio 0.9)
				(enabled yes)
				(allow_two_segments yes)
				(prefer_zone_connections yes)
			)
		)
	)
	(footprint "antmicro-footprints:C_0402_1005Metric"
		(layer "F.Cu")
		(at 261.54 87.949999 90)
		(descr "Capacitor SMD 0402")
		(tags "capacitor SMD 0402")
		(property "Reference" "C83"
			(at -1.060001 1.36 90)
			(layer "F.SilkS")
			(effects
				(font
					(size 0.7 0.7)
					(thickness 0.15)
				)
				(justify left bottom)
			)
		)
		(property "Value" "C_100n_0402"
			(at -1.022927 2.155213 90)
			(layer "F.Fab")
			(effects
				(font
					(size 0.7 0.7)
					(thickness 0.15)
				)
				(justify left bottom)
			)
		)
		(property "Datasheet" "https://www.murata.com/products/productdetail?partno=GRM155R61H104KE14%23"
			(at 0 0 90)
			(layer "F.Fab")
			(hide yes)
			(effects
				(font
					(size 1.27 1.27)
					(thickness 0.15)
				)
			)
		)
		(property "Author" "Antmicro"
			(at 349.489999 -173.590001 0)
			(layer "F.Fab")
			(hide yes)
			(effects
				(font
					(size 1 1)
					(thickness 0.15)
				)
			)
		)
		(property "Dielectric" "X5R"
			(at 349.489999 -173.590001 0)
			(layer "F.Fab")
			(hide yes)
			(effects
				(font
					(size 1 1)
					(thickness 0.15)
				)
			)
		)
		(property "License" "Apache-2.0"
			(at 349.489999 -173.590001 0)
			(layer "F.Fab")
			(hide yes)
			(effects
				(font
					(size 1 1)
					(thickness 0.15)
				)
			)
		)
		(property "MPN" "GRM155R61H104KE14D"
			(at 349.489999 -173.590001 0)
			(layer "F.Fab")
			(hide yes)
			(effects
				(font
					(size 1 1)
					(thickness 0.15)
				)
			)
		)
		(property "Manufacturer" "Murata"
			(at 349.489999 -173.590001 0)
			(layer "F.Fab")
			(hide yes)
			(effects
				(font
					(size 1 1)
					(thickness 0.15)
				)
			)
		)
		(property "Public" "False"
			(at 349.489999 -173.590001 0)
			(layer "F.Fab")
			(hide yes)
			(effects
				(font
					(size 1 1)
					(thickness 0.15)
				)
			)
		)
		(property "Val" "100n"
			(at 349.489999 -173.590001 0)
			(layer "F.Fab")
			(hide yes)
			(effects
				(font
					(size 1 1)
					(thickness 0.15)
				)
			)
		)
		(property "Voltage" "50V"
			(at 349.489999 -173.590001 0)
			(layer "F.Fab")
			(hide yes)
			(effects
				(font
					(size 1 1)
					(thickness 0.15)
				)
			)
		)
		(sheetname "Misc")
		(sheetfile "misc.kicad_sch")
		(attr smd)
		(fp_rect
			(start -0.925 -0.47)
			(end 0.925 0.47)
			(stroke
				(width 0.05)
				(type default)
			)
			(fill no)
			(layer "F.CrtYd")
		)
		(fp_line
			(start 0.504 -0.25)
			(end 0.504 0.248)
			(stroke
				(width 0.15)
				(type solid)
			)
			(layer "F.Fab")
		)
		(fp_line
			(start -0.494 -0.25)
			(end 0.504 -0.25)
			(stroke
				(width 0.15)
				(type solid)
			)
			(layer "F.Fab")
		)
		(fp_line
			(start 0.504 0.248)
			(end -0.494 0.248)
			(stroke
				(width 0.15)
				(type solid)
			)
			(layer "F.Fab")
		)
		(fp_line
			(start -0.494 0.248)
			(end -0.494 -0.25)
			(stroke
				(width 0.15)
				(type solid)
			)
			(layer "F.Fab")
		)
		(pad "1" smd roundrect
			(at -0.48 0 90)
			(size 0.59 0.64)
			(layers "F.Cu" "F.Mask" "F.Paste")
			(roundrect_rratio 0.25)
			(net 1 "GND")
			(pintype "passive")
			(teardrops
				(best_length_ratio 0.2)
				(max_length 1)
				(best_width_ratio 0.9)
				(max_width 2)
				(curved_edges yes)
				(filter_ratio 0.9)
				(enabled yes)
				(allow_two_segments yes)
				(prefer_zone_connections yes)
			)
		)
		(pad "2" smd roundrect
			(at 0.48 0 90)
			(size 0.59 0.64)
			(layers "F.Cu" "F.Mask" "F.Paste")
			(roundrect_rratio 0.25)
			(net 80 "Net-(Q6-D)")
			(pintype "passive")
			(teardrops
				(best_length_ratio 0.2)
				(max_length 1)
				(best_width_ratio 0.9)
				(max_width 2)
				(curved_edges yes)
				(filter_ratio 0.9)
				(enabled yes)
				(allow_two_segments yes)
				(prefer_zone_connections yes)
			)
		)
	)
	(footprint "antmicro-footprints:R_0402_1005Metric"
		(layer "F.Cu")
		(at 297.2 84.03 90)
		(descr "Resistor SMD 0402")
		(tags "resistor SMD 0402")
		(property "Reference" "R126"
			(at -3.68 0.45 90)
			(layer "F.SilkS")
			(effects
				(font
					(size 0.7 0.7)
					(thickness 0.15)
				)
				(justify left bottom)
			)
		)
		(property "Value" "R_0R_0402"
			(at -1.011843 1.772047 90)
			(layer "F.Fab")
			(effects
				(font
					(size 0.7 0.7)
					(thickness 0.15)
				)
				(justify left bottom)
			)
		)
		(property "Datasheet" "https://industrial.panasonic.com/cdbs/www-data/pdf/RDA0000/AOA0000C301.pdf"
			(at 0 0 90)
			(layer "F.Fab")
			(hide yes)
			(effects
				(font
					(size 1.27 1.27)
					(thickness 0.15)
				)
			)
		)
		(property "Author" "Antmicro"
			(at 381.23 -213.17 0)
			(layer "F.Fab")
			(hide yes)
			(effects
				(font
					(size 1 1)
					(thickness 0.15)
				)
			)
		)
		(property "Current" "1A"
			(at 381.23 -213.17 0)
			(layer "F.Fab")
			(hide yes)
			(effects
				(font
					(size 1 1)
					(thickness 0.15)
				)
			)
		)
		(property "License" "Apache-2.0"
			(at 381.23 -213.17 0)
			(layer "F.Fab")
			(hide yes)
			(effects
				(font
					(size 1 1)
					(thickness 0.15)
				)
			)
		)
		(property "MPN" "ERJ2GE0R00X"
			(at 381.23 -213.17 0)
			(layer "F.Fab")
			(hide yes)
			(effects
				(font
					(size 1 1)
					(thickness 0.15)
				)
			)
		)
		(property "Manufacturer" "Panasonic"
			(at 381.23 -213.17 0)
			(layer "F.Fab")
			(hide yes)
			(effects
				(font
					(size 1 1)
					(thickness 0.15)
				)
			)
		)
		(property "Public" "False"
			(at 381.23 -213.17 0)
			(layer "F.Fab")
			(hide yes)
			(effects
				(font
					(size 1 1)
					(thickness 0.15)
				)
			)
		)
		(property "Tolerance" ""
			(at 381.23 -213.17 0)
			(layer "F.Fab")
			(hide yes)
			(effects
				(font
					(size 1 1)
					(thickness 0.15)
				)
			)
		)
		(property "Val" "0R"
			(at 381.23 -213.17 0)
			(layer "F.Fab")
			(hide yes)
			(effects
				(font
					(size 1 1)
					(thickness 0.15)
				)
			)
		)
		(sheetname "M.2 key M #2")
		(sheetfile "m2keym.kicad_sch")
		(attr smd)
		(fp_rect
			(start -0.925 -0.47)
			(end 0.925 0.47)
			(stroke
				(width 0.05)
				(type default)
			)
			(fill no)
			(layer "F.CrtYd")
		)
		(fp_rect
			(start -0.5 -0.25)
			(end 0.5 0.25)
			(stroke
				(width 0.15)
				(type solid)
			)
			(fill no)
			(layer "F.Fab")
		)
		(pad "1" smd roundrect
			(at -0.48 0 90)
			(size 0.59 0.64)
			(layers "F.Cu" "F.Mask" "F.Paste")
			(roundrect_rratio 0.25)
			(net 528 "/Backplane/~{PERST}")
			(pintype "passive")
			(teardrops
				(best_length_ratio 0.2)
				(max_length 1)
				(best_width_ratio 0.9)
				(max_width 2)
				(curved_edges yes)
				(filter_ratio 0.9)
				(enabled yes)
				(allow_two_segments yes)
				(prefer_zone_connections yes)
			)
		)
		(pad "2" smd roundrect
			(at 0.48 0 90)
			(size 0.59 0.64)
			(layers "F.Cu" "F.Mask" "F.Paste")
			(roundrect_rratio 0.25)
			(net 270 "/M.2 key M #2/~{PERST_D}")
			(pintype "passive")
			(teardrops
				(best_length_ratio 0.2)
				(max_length 1)
				(best_width_ratio 0.9)
				(max_width 2)
				(curved_edges yes)
				(filter_ratio 0.9)
				(enabled yes)
				(allow_two_segments yes)
				(prefer_zone_connections yes)
			)
		)
	)
	(footprint "antmicro-footprints:TP_SMD_0.75mm"
		(layer "F.Cu")
		(at 149.85 129.56)
		(property "Reference" "TP71"
			(at 0.45 -1.25 90)
			(layer "F.SilkS")
			(effects
				(font
					(size 0.7 0.7)
					(thickness 0.15)
				)
				(justify left bottom)
			)
		)
		(property "Value" "TP_0.75mm_SMD"
			(at 0 1.2 0)
			(layer "F.Fab")
			(effects
				(font
					(size 0.7 0.7)
					(thickness 0.15)
				)
				(justify left bottom)
			)
		)
		(property "Author" "Antmicro"
			(at 0 0 0)
			(layer "F.Fab")
			(hide yes)
			(effects
				(font
					(size 1 1)
					(thickness 0.15)
				)
			)
		)
		(property "License" "Apache-2.0"
			(at 0 0 0)
			(layer "F.Fab")
			(hide yes)
			(effects
				(font
					(size 1 1)
					(thickness 0.15)
				)
			)
		)
		(property "MPN" ""
			(at 0 0 0)
			(layer "F.Fab")
			(hide yes)
			(effects
				(font
					(size 1 1)
					(thickness 0.15)
				)
			)
		)
		(property "Manufacturer" ""
			(at 0 0 0)
			(layer "F.Fab")
			(hide yes)
			(effects
				(font
					(size 1 1)
					(thickness 0.15)
				)
			)
		)
		(property "Public" "False"
			(at 0 0 0)
			(layer "F.Fab")
			(hide yes)
			(effects
				(font
					(size 1 1)
					(thickness 0.15)
				)
			)
		)
		(sheetname "KR to SFI #1")
		(sheetfile "kr_sfi.kicad_sch")
		(attr exclude_from_pos_files exclude_from_bom)
		(fp_circle
			(center 0 0)
			(end 0.475 0)
			(stroke
				(width 0.05)
				(type default)
			)
			(fill no)
			(layer "F.CrtYd")
		)
		(pad "1" smd circle
			(at 0 0)
			(size 0.75 0.75)
			(layers "F.Cu" "F.Mask")
			(net 734 "Net-(U43A-LOSA)")
			(pinfunction "1")
			(pintype "passive")
			(teardrops
				(best_length_ratio 0.4)
				(max_length 1)
				(best_width_ratio 0.9)
				(max_width 2)
				(curved_edges yes)
				(filter_ratio 0.9)
				(enabled yes)
				(allow_two_segments yes)
				(prefer_zone_connections yes)
			)
		)
	)
	(footprint "antmicro-footprints:LED_0603_1608Metric_G"
		(layer "F.Cu")
		(at 197.70861 74.802163 90)
		(descr "LED SMD 0603 Green")
		(tags "LED SMD 0603 Green")
		(property "Reference" "D28"
			(at -1.1 -0.55 90)
			(layer "F.SilkS")
			(effects
				(font
					(size 0.7 0.7)
					(thickness 0.15)
				)
				(justify left bottom)
			)
		)
		(property "Value" "LED_G_0603_LTST-C190GKT"
			(at -0.001 1.599 90)
			(layer "F.Fab")
			(effects
				(font
					(size 0.7 0.7)
					(thickness 0.15)
				)
				(justify left bottom)
			)
		)
		(property "Datasheet" "https://media.digikey.com/pdf/Data%20Sheets/Lite-On%20PDFs/LTST-C190GKT.pdf"
			(at 0 0 90)
			(layer "F.Fab")
			(hide yes)
			(effects
				(font
					(size 1.27 1.27)
					(thickness 0.15)
				)
			)
		)
		(property "Author" "Antmicro"
			(at 272.510773 -122.906447 0)
			(layer "F.Fab")
			(hide yes)
			(effects
				(font
					(size 1 1)
					(thickness 0.15)
				)
			)
		)
		(property "Color" "Green"
			(at 272.510773 -122.906447 0)
			(layer "F.Fab")
			(hide yes)
			(effects
				(font
					(size 1 1)
					(thickness 0.15)
				)
			)
		)
		(property "License" "Apache-2.0"
			(at 272.510773 -122.906447 0)
			(layer "F.Fab")
			(hide yes)
			(effects
				(font
					(size 1 1)
					(thickness 0.15)
				)
			)
		)
		(property "MPN" "LTST-C190GKT"
			(at 272.510773 -122.906447 0)
			(layer "F.Fab")
			(hide yes)
			(effects
				(font
					(size 1 1)
					(thickness 0.15)
				)
			)
		)
		(property "Manufacturer" "Lite-On"
			(at 272.510773 -122.906447 0)
			(layer "F.Fab")
			(hide yes)
			(effects
				(font
					(size 1 1)
					(thickness 0.15)
				)
			)
		)
		(property "Public" "False"
			(at 272.510773 -122.906447 0)
			(layer "F.Fab")
			(hide yes)
			(effects
				(font
					(size 1 1)
					(thickness 0.15)
				)
			)
		)
		(sheetname "Power")
		(sheetfile "power.kicad_sch")
		(attr smd)
		(fp_line
			(start 0.22 -0.35)
			(end -0.22 -0.35)
			(stroke
				(width 0.15)
				(type solid)
			)
			(layer "F.SilkS")
		)
		(fp_line
			(start -1.18 -0.319)
			(end -1.18 0.321)
			(stroke
				(width 0.15)
				(type solid)
			)
			(layer "F.SilkS")
		)
		(fp_line
			(start 0.105328 0.001008)
			(end 0.24 0.001)
			(stroke
				(width 0.1)
				(type solid)
			)
			(layer "F.SilkS")
		)
		(fp_line
			(start -0.094672 0.001008)
			(end 0.105328 -0.198992)
			(stroke
				(width 0.1)
				(type solid)
			)
			(layer "F.SilkS")
		)
		(fp_line
			(start -0.094672 0.001008)
			(end -0.24 0.001008)
			(stroke
				(width 0.1)
				(type solid)
			)
			(layer "F.SilkS")
		)
		(fp_line
			(start 0.105328 0.201008)
			(end 0.105328 -0.198992)
			(stroke
				(width 0.1)
				(type solid)
			)
			(layer "F.SilkS")
		)
		(fp_line
			(start 0.105328 0.201008)
			(end -0.094672 0.001008)
			(stroke
				(width 0.1)
				(type solid)
			)
			(layer "F.SilkS")
		)
		(fp_line
			(start -0.094672 0.201008)
			(end -0.094672 -0.198992)
			(stroke
				(width 0.1)
				(type solid)
			)
			(layer "F.SilkS")
		)
		(fp_line
			(start 0.22 0.35)
			(end -0.22 0.35)
			(stroke
				(width 0.15)
				(type solid)
			)
			(layer "F.SilkS")
		)
		(fp_rect
			(start 1.25 0.65)
			(end -1.25 -0.65)
			(stroke
				(width 0.05)
				(type solid)
			)
			(fill no)
			(layer "F.CrtYd")
		)
		(fp_line
			(start 0.201 -0.202)
			(end -0.101 0)
			(stroke
				(width 0.15)
				(type solid)
			)
			(layer "F.Fab")
		)
		(fp_line
			(start -0.199 -0.202)
			(end -0.199 0.1)
			(stroke
				(width 0.15)
				(type solid)
			)
			(layer "F.Fab")
		)
		(fp_line
			(start 0.599 0)
			(end 0.201 0)
			(stroke
				(width 0.15)
				(type solid)
			)
			(layer "F.Fab")
		)
		(fp_line
			(start 0.201 0)
			(end 0.201 -0.202)
			(stroke
				(width 0.15)
				(type solid)
			)
			(layer "F.Fab")
		)
		(fp_line
			(start -0.101 0)
			(end 0.201 0.2)
			(stroke
				(width 0.15)
				(type solid)
			)
			(layer "F.Fab")
		)
		(fp_line
			(start -0.199 0)
			(end -0.597 0)
			(stroke
				(width 0.15)
				(type solid)
			)
			(layer "F.Fab")
		)
		(fp_line
			(start 0.201 0.2)
			(end 0.201 0)
			(stroke
				(width 0.15)
				(type solid)
			)
			(layer "F.Fab")
		)
		(fp_line
			(start -0.199 0.2)
			(end -0.199 0.1)
			(stroke
				(width 0.15)
				(type solid)
			)
			(layer "F.Fab")
		)
		(fp_rect
			(start 0.848 0.4)
			(end -0.85 -0.402)
			(stroke
				(width 0.15)
				(type solid)
			)
			(fill no)
			(layer "F.Fab")
		)
		(pad "1" smd roundrect
			(at -0.7 0 270)
			(size 0.8 1)
			(layers "F.Cu" "F.Mask" "F.Paste")
			(roundrect_rratio 0.2)
			(net 981 "Net-(D28-C)")
			(pinfunction "C")
			(pintype "passive")
			(teardrops
				(best_length_ratio 0.2)
				(max_length 1)
				(best_width_ratio 0.9)
				(max_width 2)
				(curved_edges yes)
				(filter_ratio 0.9)
				(enabled yes)
				(allow_two_segments yes)
				(prefer_zone_connections yes)
			)
		)
		(pad "2" smd roundrect
			(at 0.7 0 270)
			(size 0.8 1)
			(layers "F.Cu" "F.Mask" "F.Paste")
			(roundrect_rratio 0.2)
			(net 2 "+3V3")
			(pinfunction "A")
			(pintype "passive")
			(teardrops
				(best_length_ratio 0.2)
				(max_length 1)
				(best_width_ratio 0.9)
				(max_width 2)
				(curved_edges yes)
				(filter_ratio 0.9)
				(enabled yes)
				(allow_two_segments yes)
				(prefer_zone_connections yes)
			)
		)
	)
	(footprint "antmicro-footprints:R_0402_1005Metric"
		(layer "F.Cu")
		(at 308.7 105.81 180)
		(descr "Resistor SMD 0402")
		(tags "resistor SMD 0402")
		(property "Reference" "R99"
			(at -1.15 -1.3 0)
			(layer "F.SilkS")
			(effects
				(font
					(size 0.7 0.7)
					(thickness 0.15)
				)
				(justify right bottom)
			)
		)
		(property "Value" "R_68k_0402"
			(at -1.011843 1.772047 0)
			(layer "F.Fab")
			(effects
				(font
					(size 0.7 0.7)
					(thickness 0.15)
				)
				(justify right bottom)
			)
		)
		(property "Datasheet" "https://www.bourns.com/docs/product-datasheets/cr.pdf"
			(at 0 0 180)
			(layer "F.Fab")
			(hide yes)
			(effects
				(font
					(size 1.27 1.27)
					(thickness 0.15)
				)
			)
		)
		(property "Author" "Antmicro"
			(at 617.4 211.62 0)
			(layer "F.Fab")
			(hide yes)
			(effects
				(font
					(size 1 1)
					(thickness 0.15)
				)
			)
		)
		(property "License" "Apache-2.0"
			(at 617.4 211.62 0)
			(layer "F.Fab")
			(hide yes)
			(effects
				(font
					(size 1 1)
					(thickness 0.15)
				)
			)
		)
		(property "MPN" "CR0402-FX-6802GLF"
			(at 617.4 211.62 0)
			(layer "F.Fab")
			(hide yes)
			(effects
				(font
					(size 1 1)
					(thickness 0.15)
				)
			)
		)
		(property "Manufacturer" "Bourns"
			(at 617.4 211.62 0)
			(layer "F.Fab")
			(hide yes)
			(effects
				(font
					(size 1 1)
					(thickness 0.15)
				)
			)
		)
		(property "Public" "False"
			(at 617.4 211.62 0)
			(layer "F.Fab")
			(hide yes)
			(effects
				(font
					(size 1 1)
					(thickness 0.15)
				)
			)
		)
		(property "Tolerance" "1%"
			(at 617.4 211.62 0)
			(layer "F.Fab")
			(hide yes)
			(effects
				(font
					(size 1 1)
					(thickness 0.15)
				)
			)
		)
		(property "Val" "68k"
			(at 617.4 211.62 0)
			(layer "F.Fab")
			(hide yes)
			(effects
				(font
					(size 1 1)
					(thickness 0.15)
				)
			)
		)
		(sheetname "Power")
		(sheetfile "power.kicad_sch")
		(attr smd)
		(fp_rect
			(start -0.925 -0.47)
			(end 0.925 0.47)
			(stroke
				(width 0.05)
				(type default)
			)
			(fill no)
			(layer "F.CrtYd")
		)
		(fp_rect
			(start -0.5 -0.25)
			(end 0.5 0.25)
			(stroke
				(width 0.15)
				(type solid)
			)
			(fill no)
			(layer "F.Fab")
		)
		(pad "1" smd roundrect
			(at -0.48 0 180)
			(size 0.59 0.64)
			(layers "F.Cu" "F.Mask" "F.Paste")
			(roundrect_rratio 0.25)
			(net 581 "Net-(U19-FB)")
			(pintype "passive")
			(teardrops
				(best_length_ratio 0.2)
				(max_length 1)
				(best_width_ratio 0.9)
				(max_width 2)
				(curved_edges yes)
				(filter_ratio 0.9)
				(enabled yes)
				(allow_two_segments yes)
				(prefer_zone_connections yes)
			)
		)
		(pad "2" smd roundrect
			(at 0.48 0 180)
			(size 0.59 0.64)
			(layers "F.Cu" "F.Mask" "F.Paste")
			(roundrect_rratio 0.25)
			(net 71 "Net-(U49-IN+)")
			(pintype "passive")
			(teardrops
				(best_length_ratio 0.2)
				(max_length 1)
				(best_width_ratio 0.9)
				(max_width 2)
				(curved_edges yes)
				(filter_ratio 0.9)
				(enabled yes)
				(allow_two_segments yes)
				(prefer_zone_connections yes)
			)
		)
	)
	(footprint "antmicro-footprints:C_0603_1608Metric"
		(layer "F.Cu")
		(at 177.52 93.22)
		(descr "Capacitor SMD 0603")
		(tags "capacitor 0603")
		(property "Reference" "C71"
			(at -3.27 0.49 0)
			(layer "F.SilkS")
			(effects
				(font
					(size 0.7 0.7)
					(thickness 0.15)
				)
				(justify left bottom)
			)
		)
		(property "Value" "C_22u_16V_0603"
			(at -1.42757 1.770288 0)
			(layer "F.Fab")
			(effects
				(font
					(size 0.7 0.7)
					(thickness 0.15)
				)
				(justify left bottom)
			)
		)
		(property "Datasheet" "https://product.samsungsem.com/mlcc/CL10A226MO7JZN.do"
			(at 0 0 0)
			(layer "F.Fab")
			(hide yes)
			(effects
				(font
					(size 1.27 1.27)
					(thickness 0.15)
				)
			)
		)
		(property "Author" "Antmicro"
			(at 0 0 0)
			(layer "F.Fab")
			(hide yes)
			(effects
				(font
					(size 1 1)
					(thickness 0.15)
				)
			)
		)
		(property "Dielectric" ""
			(at 0 0 0)
			(layer "F.Fab")
			(hide yes)
			(effects
				(font
					(size 1 1)
					(thickness 0.15)
				)
			)
		)
		(property "License" "Apache-2.0"
			(at 0 0 0)
			(layer "F.Fab")
			(hide yes)
			(effects
				(font
					(size 1 1)
					(thickness 0.15)
				)
			)
		)
		(property "MPN" "CL10A226MO7JZNC"
			(at 0 0 0)
			(layer "F.Fab")
			(hide yes)
			(effects
				(font
					(size 1 1)
					(thickness 0.15)
				)
			)
		)
		(property "Manufacturer" "Samsung Electro-Mechanics"
			(at 0 0 0)
			(layer "F.Fab")
			(hide yes)
			(effects
				(font
					(size 1 1)
					(thickness 0.15)
				)
			)
		)
		(property "Public" "False"
			(at 0 0 0)
			(layer "F.Fab")
			(hide yes)
			(effects
				(font
					(size 1 1)
					(thickness 0.15)
				)
			)
		)
		(property "Val" "22u"
			(at 0 0 0)
			(layer "F.Fab")
			(hide yes)
			(effects
				(font
					(size 1 1)
					(thickness 0.15)
				)
			)
		)
		(property "Voltage" "16V"
			(at 0 0 0)
			(layer "F.Fab")
			(hide yes)
			(effects
				(font
					(size 1 1)
					(thickness 0.15)
				)
			)
		)
		(sheetname "M.2 key M #1")
		(sheetfile "m2keym_low.kicad_sch")
		(attr smd)
		(fp_line
			(start -0.15 -0.4)
			(end 0.15 -0.4)
			(stroke
				(width 0.15)
				(type solid)
			)
			(layer "F.SilkS")
		)
		(fp_line
			(start -0.15 0.4)
			(end 0.15 0.4)
			(stroke
				(width 0.15)
				(type solid)
			)
			(layer "F.SilkS")
		)
		(fp_rect
			(start -1.25 -0.65)
			(end 1.25 0.65)
			(stroke
				(width 0.05)
				(type solid)
			)
			(fill no)
			(layer "F.CrtYd")
		)
		(fp_rect
			(start -0.8 -0.4)
			(end 0.8 0.4)
			(stroke
				(width 0.15)
				(type solid)
			)
			(fill no)
			(layer "F.Fab")
		)
		(pad "1" smd roundrect
			(at -0.7 0)
			(size 0.8 1)
			(layers "F.Cu" "F.Mask" "F.Paste")
			(roundrect_rratio 0.2)
			(net 1 "GND")
			(pintype "passive")
			(teardrops
				(best_length_ratio 0.2)
				(max_length 1)
				(best_width_ratio 0.9)
				(max_width 2)
				(curved_edges yes)
				(filter_ratio 0.9)
				(enabled yes)
				(allow_two_segments yes)
				(prefer_zone_connections yes)
			)
		)
		(pad "2" smd roundrect
			(at 0.7 0)
			(size 0.8 1)
			(layers "F.Cu" "F.Mask" "F.Paste")
			(roundrect_rratio 0.2)
			(net 969 "/M.2 key M #1/M2_3V3")
			(pintype "passive")
			(teardrops
				(best_length_ratio 0.2)
				(max_length 1)
				(best_width_ratio 0.9)
				(max_width 2)
				(curved_edges yes)
				(filter_ratio 0.9)
				(enabled yes)
				(allow_two_segments yes)
				(prefer_zone_connections yes)
			)
		)
	)
	(footprint "antmicro-footprints:TP_SMD_0.75mm"
		(layer "F.Cu")
		(at 195.315076 131.515076 45)
		(property "Reference" "TP56"
			(at 0.4 0.4 45)
			(layer "F.SilkS")
			(effects
				(font
					(size 0.7 0.7)
					(thickness 0.15)
				)
				(justify left bottom)
			)
		)
		(property "Value" "TP_0.75mm_SMD"
			(at 0 1.2 45)
			(layer "F.Fab")
			(effects
				(font
					(size 0.7 0.7)
					(thickness 0.15)
				)
				(justify left bottom)
			)
		)
		(property "Author" "Antmicro"
			(at 369.6 -267.02 45)
			(layer "F.Fab")
			(hide yes)
			(effects
				(font
					(size 1 1)
					(thickness 0.15)
				)
			)
		)
		(property "License" "Apache-2.0"
			(at 369.6 -267.02 45)
			(layer "F.Fab")
			(hide yes)
			(effects
				(font
					(size 1 1)
					(thickness 0.15)
				)
			)
		)
		(property "MPN" ""
			(at 369.6 -267.02 45)
			(layer "F.Fab")
			(hide yes)
			(effects
				(font
					(size 1 1)
					(thickness 0.15)
				)
			)
		)
		(property "Manufacturer" ""
			(at 369.6 -267.02 45)
			(layer "F.Fab")
			(hide yes)
			(effects
				(font
					(size 1 1)
					(thickness 0.15)
				)
			)
		)
		(property "Public" "False"
			(at 369.6 -267.02 45)
			(layer "F.Fab")
			(hide yes)
			(effects
				(font
					(size 1 1)
					(thickness 0.15)
				)
			)
		)
		(sheetname "PCIe redriver")
		(sheetfile "pcie_redriver.kicad_sch")
		(attr exclude_from_pos_files exclude_from_bom)
		(fp_circle
			(center 0 0)
			(end 0.475 0)
			(stroke
				(width 0.05)
				(type default)
			)
			(fill no)
			(layer "F.CrtYd")
		)
		(pad "1" smd circle
			(at 0 0 45)
			(size 0.75 0.75)
			(layers "F.Cu" "F.Mask")
			(net 719 "Net-(U40-~{I2C_{RESET}})")
			(pinfunction "1")
			(pintype "passive")
			(teardrops
				(best_length_ratio 0.4)
				(max_length 1)
				(best_width_ratio 0.9)
				(max_width 2)
				(curved_edges yes)
				(filter_ratio 0.9)
				(enabled yes)
				(allow_two_segments yes)
				(prefer_zone_connections yes)
			)
		)
	)
	(footprint "antmicro-footprints:TSOT23-6"
		(layer "F.Cu")
		(at 116.9 86.86)
		(property "Reference" "U3"
			(at -0.75 -1.75 0)
			(layer "F.SilkS")
			(effects
				(font
					(size 0.7 0.7)
					(thickness 0.15)
				)
				(justify left bottom)
			)
		)
		(property "Value" "AP22615A_TSOT26"
			(at 0 2.6 0)
			(layer "F.Fab")
			(effects
				(font
					(size 0.7 0.7)
					(thickness 0.15)
				)
				(justify left bottom)
			)
		)
		(property "Datasheet" "https://www.mouser.com/datasheet/2/115/DIOD_S_A0008958405_1-2543193.pdf"
			(at 0 0 0)
			(layer "F.Fab")
			(hide yes)
			(effects
				(font
					(size 1.27 1.27)
					(thickness 0.15)
				)
			)
		)
		(property "Author" "Antmicro"
			(at 0 0 0)
			(layer "F.Fab")
			(hide yes)
			(effects
				(font
					(size 1 1)
					(thickness 0.15)
				)
			)
		)
		(property "License" "Apache-2.0"
			(at 0 0 0)
			(layer "F.Fab")
			(hide yes)
			(effects
				(font
					(size 1 1)
					(thickness 0.15)
				)
			)
		)
		(property "MPN" "AP22615AWU-7"
			(at 0 0 0)
			(layer "F.Fab")
			(hide yes)
			(effects
				(font
					(size 1 1)
					(thickness 0.15)
				)
			)
		)
		(property "Manufacturer" "Diodes Incorporated"
			(at 0 0 0)
			(layer "F.Fab")
			(hide yes)
			(effects
				(font
					(size 1 1)
					(thickness 0.15)
				)
			)
		)
		(sheetname "2xUSB3.0+RJ45")
		(sheetfile "usb3+rj45.kicad_sch")
		(attr smd)
		(fp_line
			(start -1 -1.5)
			(end -1 -1.375)
			(stroke
				(width 0.15)
				(type solid)
			)
			(layer "F.SilkS")
		)
		(fp_line
			(start -1 1.55)
			(end -1 1.4)
			(stroke
				(width 0.15)
				(type solid)
			)
			(layer "F.SilkS")
		)
		(fp_line
			(start 1 -1.497)
			(end -1 -1.5)
			(stroke
				(width 0.15)
				(type solid)
			)
			(layer "F.SilkS")
		)
		(fp_line
			(start 1 -1.497)
			(end 1 -1.375)
			(stroke
				(width 0.15)
				(type solid)
			)
			(layer "F.SilkS")
		)
		(fp_line
			(start 1 1.55)
			(end -1 1.55)
			(stroke
				(width 0.15)
				(type solid)
			)
			(layer "F.SilkS")
		)
		(fp_line
			(start 1 1.55)
			(end 1 1.4)
			(stroke
				(width 0.15)
				(type solid)
			)
			(layer "F.SilkS")
		)
		(fp_circle
			(center -1.44 -1.5)
			(end -1.39 -1.5)
			(stroke
				(width 0.15)
				(type solid)
			)
			(fill yes)
			(layer "F.SilkS")
		)
		(fp_rect
			(start 1.93 -1.7)
			(end -1.93 1.7)
			(stroke
				(width 0.05)
				(type solid)
			)
			(fill no)
			(layer "F.CrtYd")
		)
		(fp_line
			(start -0.45 -1.521)
			(end -0.876 -1.096)
			(stroke
				(width 0.15)
				(type solid)
			)
			(layer "F.Fab")
		)
		(fp_rect
			(start 0.875 1.528)
			(end -0.875 -1.525)
			(stroke
				(width 0.15)
				(type solid)
			)
			(fill no)
			(layer "F.Fab")
		)
		(pad "1" smd rect
			(at -1.301 -0.947 270)
			(size 0.7 1.2)
			(layers "F.Cu" "F.Mask" "F.Paste")
			(net 42 "/2xUSB3.0+RJ45/P1_VBUS")
			(pinfunction "OUT")
			(pintype "power_out")
			(teardrops
				(best_length_ratio 0.2)
				(max_length 1)
				(best_width_ratio 0.9)
				(max_width 2)
				(curved_edges yes)
				(filter_ratio 0.9)
				(enabled yes)
				(allow_two_segments yes)
				(prefer_zone_connections yes)
			)
		)
		(pad "2" smd rect
			(at -1.301 0.004 270)
			(size 0.7 1.2)
			(layers "F.Cu" "F.Mask" "F.Paste")
			(net 1 "GND")
			(pinfunction "GND")
			(pintype "power_in")
			(teardrops
				(best_length_ratio 0.2)
				(max_length 1)
				(best_width_ratio 0.9)
				(max_width 2)
				(curved_edges yes)
				(filter_ratio 0.9)
				(enabled yes)
				(allow_two_segments yes)
				(prefer_zone_connections yes)
			)
		)
		(pad "3" smd rect
			(at -1.301 0.954 270)
			(size 0.7 1.2)
			(layers "F.Cu" "F.Mask" "F.Paste")
			(net 553 "/2xUSB3.0+RJ45/FLG_1B")
			(pinfunction "FLG")
			(pintype "output")
			(teardrops
				(best_length_ratio 0.2)
				(max_length 1)
				(best_width_ratio 0.9)
				(max_width 2)
				(curved_edges yes)
				(filter_ratio 0.9)
				(enabled yes)
				(allow_two_segments yes)
				(prefer_zone_connections yes)
			)
		)
		(pad "4" smd rect
			(at 1.299 0.954 270)
			(size 0.7 1.2)
			(layers "F.Cu" "F.Mask" "F.Paste")
			(net 555 "/2xUSB3.0+RJ45/EN_1B")
			(pinfunction "EN")
			(pintype "input")
			(teardrops
				(best_length_ratio 0.2)
				(max_length 1)
				(best_width_ratio 0.9)
				(max_width 2)
				(curved_edges yes)
				(filter_ratio 0.9)
				(enabled yes)
				(allow_two_segments yes)
				(prefer_zone_connections yes)
			)
		)
		(pad "5" smd rect
			(at 1.299 0.004 270)
			(size 0.7 1.2)
			(layers "F.Cu" "F.Mask" "F.Paste")
			(net 547 "/2xUSB3.0+RJ45/P1_ISET")
			(pinfunction "ISET")
			(pintype "passive")
			(teardrops
				(best_length_ratio 0.2)
				(max_length 1)
				(best_width_ratio 0.9)
				(max_width 2)
				(curved_edges yes)
				(filter_ratio 0.9)
				(enabled yes)
				(allow_two_segments yes)
				(prefer_zone_connections yes)
			)
		)
		(pad "6" smd rect
			(at 1.299 -0.947 270)
			(size 0.7 1.2)
			(layers "F.Cu" "F.Mask" "F.Paste")
			(net 52 "+5V")
			(pinfunction "IN")
			(pintype "power_in")
			(teardrops
				(best_length_ratio 0.2)
				(max_length 1)
				(best_width_ratio 0.9)
				(max_width 2)
				(curved_edges yes)
				(filter_ratio 0.9)
				(enabled yes)
				(allow_two_segments yes)
				(prefer_zone_connections yes)
			)
		)
	)
	(footprint "antmicro-footprints:R_0402_1005Metric"
		(layer "F.Cu")
		(at 193.70861 77.152163 90)
		(descr "Resistor SMD 0402")
		(tags "resistor SMD 0402")
		(property "Reference" "R325"
			(at -1.9 -0.5 90)
			(layer "F.SilkS")
			(effects
				(font
					(size 0.7 0.7)
					(thickness 0.15)
				)
				(justify left bottom)
			)
		)
		(property "Value" "R_2k2_0402"
			(at -1.011843 1.772047 90)
			(layer "F.Fab")
			(effects
				(font
					(size 0.7 0.7)
					(thickness 0.15)
				)
				(justify left bottom)
			)
		)
		(property "Datasheet" "https://www.bourns.com/docs/product-datasheets/cr.pdf"
			(at 0 0 90)
			(layer "F.Fab")
			(hide yes)
			(effects
				(font
					(size 1.27 1.27)
					(thickness 0.15)
				)
			)
		)
		(property "Author" "Antmicro"
			(at 270.860773 -116.556447 0)
			(layer "F.Fab")
			(hide yes)
			(effects
				(font
					(size 1 1)
					(thickness 0.15)
				)
			)
		)
		(property "License" "Apache-2.0"
			(at 270.860773 -116.556447 0)
			(layer "F.Fab")
			(hide yes)
			(effects
				(font
					(size 1 1)
					(thickness 0.15)
				)
			)
		)
		(property "MPN" "CR0402-FX-2201GLF"
			(at 270.860773 -116.556447 0)
			(layer "F.Fab")
			(hide yes)
			(effects
				(font
					(size 1 1)
					(thickness 0.15)
				)
			)
		)
		(property "Manufacturer" "Bourns"
			(at 270.860773 -116.556447 0)
			(layer "F.Fab")
			(hide yes)
			(effects
				(font
					(size 1 1)
					(thickness 0.15)
				)
			)
		)
		(property "Tolerance" "1%"
			(at 270.860773 -116.556447 0)
			(layer "F.Fab")
			(hide yes)
			(effects
				(font
					(size 1 1)
					(thickness 0.15)
				)
			)
		)
		(property "Val" "2k2"
			(at 270.860773 -116.556447 0)
			(layer "F.Fab")
			(hide yes)
			(effects
				(font
					(size 1 1)
					(thickness 0.15)
				)
			)
		)
		(sheetname "Power")
		(sheetfile "power.kicad_sch")
		(attr smd)
		(fp_rect
			(start -0.925 -0.47)
			(end 0.925 0.47)
			(stroke
				(width 0.05)
				(type default)
			)
			(fill no)
			(layer "F.CrtYd")
		)
		(fp_rect
			(start -0.5 -0.25)
			(end 0.5 0.25)
			(stroke
				(width 0.15)
				(type solid)
			)
			(fill no)
			(layer "F.Fab")
		)
		(pad "1" smd roundrect
			(at -0.48 0 90)
			(size 0.59 0.64)
			(layers "F.Cu" "F.Mask" "F.Paste")
			(roundrect_rratio 0.25)
			(net 1 "GND")
			(pintype "passive")
			(teardrops
				(best_length_ratio 0.2)
				(max_length 1)
				(best_width_ratio 0.9)
				(max_width 2)
				(curved_edges yes)
				(filter_ratio 0.9)
				(enabled yes)
				(allow_two_segments yes)
				(prefer_zone_connections yes)
			)
		)
		(pad "2" smd roundrect
			(at 0.48 0 90)
			(size 0.59 0.64)
			(layers "F.Cu" "F.Mask" "F.Paste")
			(roundrect_rratio 0.25)
			(net 984 "Net-(D32-C)")
			(pintype "passive")
			(teardrops
				(best_length_ratio 0.2)
				(max_length 1)
				(best_width_ratio 0.9)
				(max_width 2)
				(curved_edges yes)
				(filter_ratio 0.9)
				(enabled yes)
				(allow_two_segments yes)
				(prefer_zone_connections yes)
			)
		)
	)
	(footprint "antmicro-footprints:R_0402_1005Metric"
		(layer "F.Cu")
		(at 155.299 158.11 180)
		(descr "Resistor SMD 0402")
		(tags "resistor SMD 0402")
		(property "Reference" "R43"
			(at -6.701 17.5 0)
			(layer "F.SilkS")
			(effects
				(font
					(size 0.7 0.7)
					(thickness 0.15)
				)
				(justify right bottom)
			)
		)
		(property "Value" "R_0R_0402"
			(at -1.011843 1.772047 0)
			(layer "F.Fab")
			(effects
				(font
					(size 0.7 0.7)
					(thickness 0.15)
				)
				(justify right bottom)
			)
		)
		(property "Datasheet" "https://industrial.panasonic.com/cdbs/www-data/pdf/RDA0000/AOA0000C301.pdf"
			(at 0 0 180)
			(layer "F.Fab")
			(hide yes)
			(effects
				(font
					(size 1.27 1.27)
					(thickness 0.15)
				)
			)
		)
		(property "Author" "Antmicro"
			(at 310.598 316.22 0)
			(layer "F.Fab")
			(hide yes)
			(effects
				(font
					(size 1 1)
					(thickness 0.15)
				)
			)
		)
		(property "Current" "1A"
			(at 310.598 316.22 0)
			(layer "F.Fab")
			(hide yes)
			(effects
				(font
					(size 1 1)
					(thickness 0.15)
				)
			)
		)
		(property "License" "Apache-2.0"
			(at 310.598 316.22 0)
			(layer "F.Fab")
			(hide yes)
			(effects
				(font
					(size 1 1)
					(thickness 0.15)
				)
			)
		)
		(property "MPN" "ERJ2GE0R00X"
			(at 310.598 316.22 0)
			(layer "F.Fab")
			(hide yes)
			(effects
				(font
					(size 1 1)
					(thickness 0.15)
				)
			)
		)
		(property "Manufacturer" "Panasonic"
			(at 310.598 316.22 0)
			(layer "F.Fab")
			(hide yes)
			(effects
				(font
					(size 1 1)
					(thickness 0.15)
				)
			)
		)
		(property "Public" "False"
			(at 310.598 316.22 0)
			(layer "F.Fab")
			(hide yes)
			(effects
				(font
					(size 1 1)
					(thickness 0.15)
				)
			)
		)
		(property "Tolerance" ""
			(at 310.598 316.22 0)
			(layer "F.Fab")
			(hide yes)
			(effects
				(font
					(size 1 1)
					(thickness 0.15)
				)
			)
		)
		(property "Val" "0R"
			(at 310.598 316.22 0)
			(layer "F.Fab")
			(hide yes)
			(effects
				(font
					(size 1 1)
					(thickness 0.15)
				)
			)
		)
		(sheetname "2xSFP+")
		(sheetfile "2xSFP+.kicad_sch")
		(attr smd)
		(fp_rect
			(start -0.925 -0.47)
			(end 0.925 0.47)
			(stroke
				(width 0.05)
				(type default)
			)
			(fill no)
			(layer "F.CrtYd")
		)
		(fp_rect
			(start -0.5 -0.25)
			(end 0.5 0.25)
			(stroke
				(width 0.15)
				(type solid)
			)
			(fill no)
			(layer "F.Fab")
		)
		(pad "1" smd roundrect
			(at -0.48 0 180)
			(size 0.59 0.64)
			(layers "F.Cu" "F.Mask" "F.Paste")
			(roundrect_rratio 0.25)
			(net 562 "/2xSFP+/~{LED0_0}")
			(pintype "passive")
			(teardrops
				(best_length_ratio 0.2)
				(max_length 1)
				(best_width_ratio 0.9)
				(max_width 2)
				(curved_edges yes)
				(filter_ratio 0.9)
				(enabled yes)
				(allow_two_segments yes)
				(prefer_zone_connections yes)
			)
		)
		(pad "2" smd roundrect
			(at 0.48 0 180)
			(size 0.59 0.64)
			(layers "F.Cu" "F.Mask" "F.Paste")
			(roundrect_rratio 0.25)
			(net 939 "/2xSFP+/SFP0_LEDY")
			(pintype "passive")
			(teardrops
				(best_length_ratio 0.2)
				(max_length 1)
				(best_width_ratio 0.9)
				(max_width 2)
				(curved_edges yes)
				(filter_ratio 0.9)
				(enabled yes)
				(allow_two_segments yes)
				(prefer_zone_connections yes)
			)
		)
	)
	(footprint "antmicro-footprints:R_0402_1005Metric"
		(layer "F.Cu")
		(at 289.85 102.86 180)
		(descr "Resistor SMD 0402")
		(tags "resistor SMD 0402")
		(property "Reference" "R115"
			(at -1.4 -2.35 0)
			(layer "F.SilkS")
			(effects
				(font
					(size 0.7 0.7)
					(thickness 0.15)
				)
				(justify right bottom)
			)
		)
		(property "Value" "R_0R_0402"
			(at -1.011843 1.772047 0)
			(layer "F.Fab")
			(effects
				(font
					(size 0.7 0.7)
					(thickness 0.15)
				)
				(justify right bottom)
			)
		)
		(property "Datasheet" "https://industrial.panasonic.com/cdbs/www-data/pdf/RDA0000/AOA0000C301.pdf"
			(at 0 0 180)
			(layer "F.Fab")
			(hide yes)
			(effects
				(font
					(size 1.27 1.27)
					(thickness 0.15)
				)
			)
		)
		(property "Author" "Antmicro"
			(at 579.7 205.72 0)
			(layer "F.Fab")
			(hide yes)
			(effects
				(font
					(size 1 1)
					(thickness 0.15)
				)
			)
		)
		(property "Current" "1A"
			(at 579.7 205.72 0)
			(layer "F.Fab")
			(hide yes)
			(effects
				(font
					(size 1 1)
					(thickness 0.15)
				)
			)
		)
		(property "License" "Apache-2.0"
			(at 579.7 205.72 0)
			(layer "F.Fab")
			(hide yes)
			(effects
				(font
					(size 1 1)
					(thickness 0.15)
				)
			)
		)
		(property "MPN" "ERJ2GE0R00X"
			(at 579.7 205.72 0)
			(layer "F.Fab")
			(hide yes)
			(effects
				(font
					(size 1 1)
					(thickness 0.15)
				)
			)
		)
		(property "Manufacturer" "Panasonic"
			(at 579.7 205.72 0)
			(layer "F.Fab")
			(hide yes)
			(effects
				(font
					(size 1 1)
					(thickness 0.15)
				)
			)
		)
		(property "Public" "False"
			(at 579.7 205.72 0)
			(layer "F.Fab")
			(hide yes)
			(effects
				(font
					(size 1 1)
					(thickness 0.15)
				)
			)
		)
		(property "Tolerance" ""
			(at 579.7 205.72 0)
			(layer "F.Fab")
			(hide yes)
			(effects
				(font
					(size 1 1)
					(thickness 0.15)
				)
			)
		)
		(property "Val" "0R"
			(at 579.7 205.72 0)
			(layer "F.Fab")
			(hide yes)
			(effects
				(font
					(size 1 1)
					(thickness 0.15)
				)
			)
		)
		(sheetname "Power")
		(sheetfile "power.kicad_sch")
		(attr smd dnp)
		(fp_rect
			(start -0.925 -0.47)
			(end 0.925 0.47)
			(stroke
				(width 0.05)
				(type default)
			)
			(fill no)
			(layer "F.CrtYd")
		)
		(fp_rect
			(start -0.5 -0.25)
			(end 0.5 0.25)
			(stroke
				(width 0.15)
				(type solid)
			)
			(fill no)
			(layer "F.Fab")
		)
		(pad "1" smd roundrect
			(at -0.48 0 180)
			(size 0.59 0.64)
			(layers "F.Cu" "F.Mask" "F.Paste")
			(roundrect_rratio 0.25)
			(net 528 "/Backplane/~{PERST}")
			(pintype "passive")
			(teardrops
				(best_length_ratio 0.2)
				(max_length 1)
				(best_width_ratio 0.9)
				(max_width 2)
				(curved_edges yes)
				(filter_ratio 0.9)
				(enabled yes)
				(allow_two_segments yes)
				(prefer_zone_connections yes)
			)
		)
		(pad "2" smd roundrect
			(at 0.48 0 180)
			(size 0.59 0.64)
			(layers "F.Cu" "F.Mask" "F.Paste")
			(roundrect_rratio 0.25)
			(net 535 "Net-(Q3-G)")
			(pintype "passive")
			(teardrops
				(best_length_ratio 0.2)
				(max_length 1)
				(best_width_ratio 0.9)
				(max_width 2)
				(curved_edges yes)
				(filter_ratio 0.9)
				(enabled yes)
				(allow_two_segments yes)
				(prefer_zone_connections yes)
			)
		)
	)
	(footprint "antmicro-footprints:Mech_M2_2230_H2.5mm"
		(layer "F.Cu")
		(at 120.0745 80.3095 90)
		(property "Reference" "A4"
			(at -0.001 -12.11 90)
			(layer "F.SilkS")
			(hide yes)
			(effects
				(font
					(size 0.7 0.7)
					(thickness 0.15)
				)
				(justify right bottom)
			)
		)
		(property "Value" "Mech_M2_2230_H2.5mm"
			(at -0.001 6.857 90)
			(layer "F.Fab")
			(effects
				(font
					(size 0.7 0.7)
					(thickness 0.15)
				)
				(justify right bottom)
			)
		)
		(property "Author" "Antmicro"
			(at 200.384 -39.765 0)
			(layer "F.Fab")
			(hide yes)
			(effects
				(font
					(size 1 1)
					(thickness 0.15)
				)
			)
		)
		(property "License" "Apache-2.0"
			(at 200.384 -39.765 0)
			(layer "F.Fab")
			(hide yes)
			(effects
				(font
					(size 1 1)
					(thickness 0.15)
				)
			)
		)
		(property "MPN" ""
			(at 200.384 -39.765 0)
			(layer "F.Fab")
			(hide yes)
			(effects
				(font
					(size 1 1)
					(thickness 0.15)
				)
			)
		)
		(property "Manufacturer" "None"
			(at 200.384 -39.765 0)
			(layer "F.Fab")
			(hide yes)
			(effects
				(font
					(size 1 1)
					(thickness 0.15)
				)
			)
		)
		(property "Public" "False"
			(at 200.384 -39.765 0)
			(layer "F.Fab")
			(hide yes)
			(effects
				(font
					(size 1 1)
					(thickness 0.15)
				)
			)
		)
		(sheetname "M.2 key E")
		(sheetfile "m2keye.kicad_sch")
		(attr exclude_from_pos_files exclude_from_bom allow_missing_courtyard dnp)
	)
	(footprint "antmicro-footprints:R_0402_1005Metric"
		(layer "F.Cu")
		(at 155.299 160.11 180)
		(descr "Resistor SMD 0402")
		(tags "resistor SMD 0402")
		(property "Reference" "R45"
			(at -6.701 17.5 0)
			(layer "F.SilkS")
			(effects
				(font
					(size 0.7 0.7)
					(thickness 0.15)
				)
				(justify right bottom)
			)
		)
		(property "Value" "R_0R_0402"
			(at -1.011843 1.772047 0)
			(layer "F.Fab")
			(effects
				(font
					(size 0.7 0.7)
					(thickness 0.15)
				)
				(justify right bottom)
			)
		)
		(property "Datasheet" "https://industrial.panasonic.com/cdbs/www-data/pdf/RDA0000/AOA0000C301.pdf"
			(at 0 0 180)
			(layer "F.Fab")
			(hide yes)
			(effects
				(font
					(size 1.27 1.27)
					(thickness 0.15)
				)
			)
		)
		(property "Author" "Antmicro"
			(at 310.598 320.22 0)
			(layer "F.Fab")
			(hide yes)
			(effects
				(font
					(size 1 1)
					(thickness 0.15)
				)
			)
		)
		(property "Current" "1A"
			(at 310.598 320.22 0)
			(layer "F.Fab")
			(hide yes)
			(effects
				(font
					(size 1 1)
					(thickness 0.15)
				)
			)
		)
		(property "License" "Apache-2.0"
			(at 310.598 320.22 0)
			(layer "F.Fab")
			(hide yes)
			(effects
				(font
					(size 1 1)
					(thickness 0.15)
				)
			)
		)
		(property "MPN" "ERJ2GE0R00X"
			(at 310.598 320.22 0)
			(layer "F.Fab")
			(hide yes)
			(effects
				(font
					(size 1 1)
					(thickness 0.15)
				)
			)
		)
		(property "Manufacturer" "Panasonic"
			(at 310.598 320.22 0)
			(layer "F.Fab")
			(hide yes)
			(effects
				(font
					(size 1 1)
					(thickness 0.15)
				)
			)
		)
		(property "Public" "False"
			(at 310.598 320.22 0)
			(layer "F.Fab")
			(hide yes)
			(effects
				(font
					(size 1 1)
					(thickness 0.15)
				)
			)
		)
		(property "Tolerance" ""
			(at 310.598 320.22 0)
			(layer "F.Fab")
			(hide yes)
			(effects
				(font
					(size 1 1)
					(thickness 0.15)
				)
			)
		)
		(property "Val" "0R"
			(at 310.598 320.22 0)
			(layer "F.Fab")
			(hide yes)
			(effects
				(font
					(size 1 1)
					(thickness 0.15)
				)
			)
		)
		(sheetname "2xSFP+")
		(sheetfile "2xSFP+.kicad_sch")
		(attr smd dnp)
		(fp_rect
			(start -0.925 -0.47)
			(end 0.925 0.47)
			(stroke
				(width 0.05)
				(type default)
			)
			(fill no)
			(layer "F.CrtYd")
		)
		(fp_rect
			(start -0.5 -0.25)
			(end 0.5 0.25)
			(stroke
				(width 0.15)
				(type solid)
			)
			(fill no)
			(layer "F.Fab")
		)
		(pad "1" smd roundrect
			(at -0.48 0 180)
			(size 0.59 0.64)
			(layers "F.Cu" "F.Mask" "F.Paste")
			(roundrect_rratio 0.25)
			(net 564 "/2xSFP+/~{LED0_2}")
			(pintype "passive")
			(teardrops
				(best_length_ratio 0.2)
				(max_length 1)
				(best_width_ratio 0.9)
				(max_width 2)
				(curved_edges yes)
				(filter_ratio 0.9)
				(enabled yes)
				(allow_two_segments yes)
				(prefer_zone_connections yes)
			)
		)
		(pad "2" smd roundrect
			(at 0.48 0 180)
			(size 0.59 0.64)
			(layers "F.Cu" "F.Mask" "F.Paste")
			(roundrect_rratio 0.25)
			(net 931 "/2xSFP+/SFP0_LEDG")
			(pintype "passive")
			(teardrops
				(best_length_ratio 0.2)
				(max_length 1)
				(best_width_ratio 0.9)
				(max_width 2)
				(curved_edges yes)
				(filter_ratio 0.9)
				(enabled yes)
				(allow_two_segments yes)
				(prefer_zone_connections yes)
			)
		)
	)
	(footprint "antmicro-footprints:C_0402_1005Metric"
		(layer "F.Cu")
		(at 299.05 101.571 -90)
		(descr "Capacitor SMD 0402")
		(tags "capacitor SMD 0402")
		(property "Reference" "C69"
			(at -2.961 -0.4 90)
			(layer "F.SilkS")
			(effects
				(font
					(size 0.7 0.7)
					(thickness 0.15)
				)
				(justify right bottom)
			)
		)
		(property "Value" "C_1u_0402"
			(at -1.022927 2.155213 90)
			(layer "F.Fab")
			(effects
				(font
					(size 0.7 0.7)
					(thickness 0.15)
				)
				(justify right bottom)
			)
		)
		(property "Datasheet" "https://product.tdk.com/en/search/capacitor/ceramic/mlcc/info?part_no=C1005X6S1A105K050BC"
			(at 0 0 270)
			(layer "F.Fab")
			(hide yes)
			(effects
				(font
					(size 1.27 1.27)
					(thickness 0.15)
				)
			)
		)
		(property "Author" "Antmicro"
			(at 197.479 400.621 0)
			(layer "F.Fab")
			(hide yes)
			(effects
				(font
					(size 1 1)
					(thickness 0.15)
				)
			)
		)
		(property "Dielectric" ""
			(at 197.479 400.621 0)
			(layer "F.Fab")
			(hide yes)
			(effects
				(font
					(size 1 1)
					(thickness 0.15)
				)
			)
		)
		(property "License" "Apache-2.0"
			(at 197.479 400.621 0)
			(layer "F.Fab")
			(hide yes)
			(effects
				(font
					(size 1 1)
					(thickness 0.15)
				)
			)
		)
		(property "MPN" "C1005X6S1A105K050BC"
			(at 197.479 400.621 0)
			(layer "F.Fab")
			(hide yes)
			(effects
				(font
					(size 1 1)
					(thickness 0.15)
				)
			)
		)
		(property "Manufacturer" "TDK"
			(at 197.479 400.621 0)
			(layer "F.Fab")
			(hide yes)
			(effects
				(font
					(size 1 1)
					(thickness 0.15)
				)
			)
		)
		(property "Public" "False"
			(at 197.479 400.621 0)
			(layer "F.Fab")
			(hide yes)
			(effects
				(font
					(size 1 1)
					(thickness 0.15)
				)
			)
		)
		(property "Val" "1u"
			(at 197.479 400.621 0)
			(layer "F.Fab")
			(hide yes)
			(effects
				(font
					(size 1 1)
					(thickness 0.15)
				)
			)
		)
		(property "Voltage" ""
			(at 197.479 400.621 0)
			(layer "F.Fab")
			(hide yes)
			(effects
				(font
					(size 1 1)
					(thickness 0.15)
				)
			)
		)
		(sheetname "Power")
		(sheetfile "power.kicad_sch")
		(attr smd)
		(fp_rect
			(start -0.925 -0.47)
			(end 0.925 0.47)
			(stroke
				(width 0.05)
				(type default)
			)
			(fill no)
			(layer "F.CrtYd")
		)
		(fp_line
			(start -0.494 0.248)
			(end -0.494 -0.25)
			(stroke
				(width 0.15)
				(type solid)
			)
			(layer "F.Fab")
		)
		(fp_line
			(start 0.504 0.248)
			(end -0.494 0.248)
			(stroke
				(width 0.15)
				(type solid)
			)
			(layer "F.Fab")
		)
		(fp_line
			(start -0.494 -0.25)
			(end 0.504 -0.25)
			(stroke
				(width 0.15)
				(type solid)
			)
			(layer "F.Fab")
		)
		(fp_line
			(start 0.504 -0.25)
			(end 0.504 0.248)
			(stroke
				(width 0.15)
				(type solid)
			)
			(layer "F.Fab")
		)
		(pad "1" smd roundrect
			(at -0.48 0 270)
			(size 0.59 0.64)
			(layers "F.Cu" "F.Mask" "F.Paste")
			(roundrect_rratio 0.25)
			(net 1 "GND")
			(pintype "passive")
			(teardrops
				(best_length_ratio 0.2)
				(max_length 1)
				(best_width_ratio 0.9)
				(max_width 2)
				(curved_edges yes)
				(filter_ratio 0.9)
				(enabled yes)
				(allow_two_segments yes)
				(prefer_zone_connections yes)
			)
		)
		(pad "2" smd roundrect
			(at 0.48 0 270)
			(size 0.59 0.64)
			(layers "F.Cu" "F.Mask" "F.Paste")
			(roundrect_rratio 0.25)
			(net 79 "Net-(U23-VOUT)")
			(pintype "passive")
			(teardrops
				(best_length_ratio 0.2)
				(max_length 1)
				(best_width_ratio 0.9)
				(max_width 2)
				(curved_edges yes)
				(filter_ratio 0.9)
				(enabled yes)
				(allow_two_segments yes)
				(prefer_zone_connections yes)
			)
		)
	)
	(footprint "antmicro-footprints:Spacer_Drill3.7mm_H2.5mm_9774025151R"
		(layer "F.Cu")
		(at 261.75 102.11)
		(descr "Spacer M=3 h=2.5mm fi=5.1mm")
		(property "Reference" "H2"
			(at 0 -3.2 0)
			(layer "F.SilkS")
			(hide yes)
			(effects
				(font
					(size 0.7 0.7)
					(thickness 0.15)
				)
				(justify left bottom)
			)
		)
		(property "Value" "Spacer_Drill3.7mm_H2.5mm_9774025151R"
			(at 0 4 0)
			(layer "F.Fab")
			(effects
				(font
					(size 0.7 0.7)
					(thickness 0.15)
				)
				(justify left bottom)
			)
		)
		(property "Datasheet" "https://www.we-online.com/components/products/datasheet/9774025151R.pdf"
			(at 0 0 0)
			(layer "F.Fab")
			(hide yes)
			(effects
				(font
					(size 1.27 1.27)
					(thickness 0.15)
				)
			)
		)
		(property "Author" "Antmicro"
			(at 0 0 0)
			(layer "F.Fab")
			(hide yes)
			(effects
				(font
					(size 1 1)
					(thickness 0.15)
				)
			)
		)
		(property "License" "Apache-2.0"
			(at 0 0 0)
			(layer "F.Fab")
			(hide yes)
			(effects
				(font
					(size 1 1)
					(thickness 0.15)
				)
			)
		)
		(property "MPN" "9774025151R"
			(at 0 0 0)
			(layer "F.Fab")
			(hide yes)
			(effects
				(font
					(size 1 1)
					(thickness 0.15)
				)
			)
		)
		(property "Manufacturer" "Würth Elektronik"
			(at 0 0 0)
			(layer "F.Fab")
			(hide yes)
			(effects
				(font
					(size 1 1)
					(thickness 0.15)
				)
			)
		)
		(property "Public" "False"
			(at 0 0 0)
			(layer "F.Fab")
			(hide yes)
			(effects
				(font
					(size 1 1)
					(thickness 0.15)
				)
			)
		)
		(sheetname "M.2 key M #1")
		(sheetfile "m2keym_low.kicad_sch")
		(solder_paste_margin_ratio -1)
		(attr smd)
		(fp_circle
			(center 0 0)
			(end 3.05 0)
			(stroke
				(width 0.05)
				(type solid)
			)
			(fill no)
			(layer "F.CrtYd")
		)
		(fp_circle
			(center 0 0)
			(end 2.6 0)
			(stroke
				(width 0.15)
				(type solid)
			)
			(fill no)
			(layer "F.Fab")
		)
		(pad "" smd custom
			(at -1.7 -1.7)
			(size 0.62 0.62)
			(layers "F.Paste")
			(thermal_bridge_angle 90)
			(options
				(clearance outline)
				(anchor circle)
			)
			(primitives
				(gr_arc
					(start -0.250195 1.279127)
					(mid 0.285453 0.294389)
					(end 1.266786 -0.24747)
					(width 0.2)
				)
				(gr_arc
					(start -0.34334 1.279127)
					(mid 0.218448 0.232561)
					(end 1.259603 -0.339191)
					(width 0.2)
				)
				(gr_arc
					(start -0.436309 1.279127)
					(mid 0.152481 0.169693)
					(end 1.255279 -0.431435)
					(width 0.2)
				)
				(gr_arc
					(start -0.529126 1.279127)
					(mid 0.087542 0.105784)
					(end 1.253811 -0.524161)
					(width 0.2)
				)
				(gr_arc
					(start -0.621807 1.279127)
					(mid 0.0309 0.033527)
					(end 1.275473 -0.621136)
					(width 0.2)
				)
				(gr_arc
					(start -0.71437 1.279127)
					(mid -0.037758 -0.026651)
					(end 1.263664 -0.711602)
					(width 0.2)
				)
				(gr_arc
					(start -0.806826 1.279127)
					(mid -0.105837 -0.087395)
					(end 1.253435 -0.802342)
					(width 0.2)
				)
				(gr_arc
					(start -0.899187 1.279127)
					(mid -0.165236 -0.156885)
					(end 1.267475 -0.897258)
					(width 0.2)
				)
				(gr_arc
					(start -0.991463 1.279127)
					(mid -0.228522 -0.222449)
					(end 1.270645 -0.990112)
					(width 0.2)
				)
				(gr_arc
					(start -1.083663 1.279127)
					(mid -0.294507 -0.285313)
					(end 1.266278 -1.081674)
					(width 0.2)
				)
				(gr_line
					(start 1.279127 -0.250195)
					(end 1.279127 -1.083663)
					(width 0.2)
				)
				(gr_line
					(start -0.250195 1.279127)
					(end -1.083663 1.279127)
					(width 0.2)
				)
			)
			(teardrops
				(best_length_ratio 0.2)
				(max_length 1)
				(best_width_ratio 0.9)
				(max_width 2)
				(curved_edges yes)
				(filter_ratio 0.9)
				(enabled yes)
				(allow_two_segments yes)
				(prefer_zone_connections yes)
			)
		)
		(pad "" smd custom
			(at -1.7 1.7 90)
			(size 0.62 0.62)
			(layers "F.Paste")
			(thermal_bridge_angle 90)
			(options
				(clearance outline)
				(anchor circle)
			)
			(primitives
				(gr_arc
					(start -0.250195 1.279127)
					(mid 0.285453 0.294389)
					(end 1.266786 -0.24747)
					(width 0.2)
				)
				(gr_arc
					(start -0.34334 1.279127)
					(mid 0.218448 0.232561)
					(end 1.259603 -0.339191)
					(width 0.2)
				)
				(gr_arc
					(start -0.436309 1.279127)
					(mid 0.152481 0.169693)
					(end 1.255279 -0.431435)
					(width 0.2)
				)
				(gr_arc
					(start -0.529126 1.279127)
					(mid 0.087542 0.105784)
					(end 1.253811 -0.524161)
					(width 0.2)
				)
				(gr_arc
					(start -0.621807 1.279127)
					(mid 0.0309 0.033527)
					(end 1.275473 -0.621136)
					(width 0.2)
				)
				(gr_arc
					(start -0.71437 1.279127)
					(mid -0.037758 -0.026651)
					(end 1.263664 -0.711602)
					(width 0.2)
				)
				(gr_arc
					(start -0.806826 1.279127)
					(mid -0.105837 -0.087395)
					(end 1.253435 -0.802342)
					(width 0.2)
				)
				(gr_arc
					(start -0.899187 1.279127)
					(mid -0.165236 -0.156885)
					(end 1.267475 -0.897258)
					(width 0.2)
				)
				(gr_arc
					(start -0.991463 1.279127)
					(mid -0.228522 -0.222449)
					(end 1.270645 -0.990112)
					(width 0.2)
				)
				(gr_arc
					(start -1.083663 1.279127)
					(mid -0.294507 -0.285313)
					(end 1.266278 -1.081674)
					(width 0.2)
				)
				(gr_line
					(start 1.279127 -0.250195)
					(end 1.279127 -1.083663)
					(width 0.2)
				)
				(gr_line
					(start -0.250195 1.279127)
					(end -1.083663 1.279127)
					(width 0.2)
				)
			)
			(teardrops
				(best_length_ratio 0.2)
				(max_length 1)
				(best_width_ratio 0.9)
				(max_width 2)
				(curved_edges yes)
				(filter_ratio 0.9)
				(enabled yes)
				(allow_two_segments yes)
				(prefer_zone_connections yes)
			)
		)
		(pad "" smd custom
			(at 1.7 -1.7 270)
			(size 0.62 0.62)
			(layers "F.Paste")
			(thermal_bridge_angle 90)
			(options
				(clearance outline)
				(anchor circle)
			)
			(primitives
				(gr_arc
					(start -0.250195 1.279127)
					(mid 0.285453 0.294389)
					(end 1.266786 -0.24747)
					(width 0.2)
				)
				(gr_arc
					(start -0.34334 1.279127)
					(mid 0.218448 0.232561)
					(end 1.259603 -0.339191)
					(width 0.2)
				)
				(gr_arc
					(start -0.436309 1.279127)
					(mid 0.152481 0.169693)
					(end 1.255279 -0.431435)
					(width 0.2)
				)
				(gr_arc
					(start -0.529126 1.279127)
					(mid 0.087542 0.105784)
					(end 1.253811 -0.524161)
					(width 0.2)
				)
				(gr_arc
					(start -0.621807 1.279127)
					(mid 0.0309 0.033527)
					(end 1.275473 -0.621136)
					(width 0.2)
				)
				(gr_arc
					(start -0.71437 1.279127)
					(mid -0.037758 -0.026651)
					(end 1.263664 -0.711602)
					(width 0.2)
				)
				(gr_arc
					(start -0.806826 1.279127)
					(mid -0.105837 -0.087395)
					(end 1.253435 -0.802342)
					(width 0.2)
				)
				(gr_arc
					(start -0.899187 1.279127)
					(mid -0.165236 -0.156885)
					(end 1.267475 -0.897258)
					(width 0.2)
				)
				(gr_arc
					(start -0.991463 1.279127)
					(mid -0.228522 -0.222449)
					(end 1.270645 -0.990112)
					(width 0.2)
				)
				(gr_arc
					(start -1.083663 1.279127)
					(mid -0.294507 -0.285313)
					(end 1.266278 -1.081674)
					(width 0.2)
				)
				(gr_line
					(start 1.279127 -0.250195)
					(end 1.279127 -1.083663)
					(width 0.2)
				)
				(gr_line
					(start -0.250195 1.279127)
					(end -1.083663 1.279127)
					(width 0.2)
				)
			)
			(teardrops
				(best_length_ratio 0.2)
				(max_length 1)
				(best_width_ratio 0.9)
				(max_width 2)
				(curved_edges yes)
				(filter_ratio 0.9)
				(enabled yes)
				(allow_two_segments yes)
				(prefer_zone_connections yes)
			)
		)
		(pad "" smd custom
			(at 1.7 1.7 180)
			(size 0.62 0.62)
			(layers "F.Paste")
			(thermal_bridge_angle 90)
			(options
				(clearance outline)
				(anchor circle)
			)
			(primitives
				(gr_arc
					(start -0.250195 1.279127)
					(mid 0.285453 0.294389)
					(end 1.266786 -0.24747)
					(width 0.2)
				)
				(gr_arc
					(start -0.34334 1.279127)
					(mid 0.218448 0.232561)
					(end 1.259603 -0.339191)
					(width 0.2)
				)
				(gr_arc
					(start -0.436309 1.279127)
					(mid 0.152481 0.169693)
					(end 1.255279 -0.431435)
					(width 0.2)
				)
				(gr_arc
					(start -0.529126 1.279127)
					(mid 0.087542 0.105784)
					(end 1.253811 -0.524161)
					(width 0.2)
				)
				(gr_arc
					(start -0.621807 1.279127)
					(mid 0.0309 0.033527)
					(end 1.275473 -0.621136)
					(width 0.2)
				)
				(gr_arc
					(start -0.71437 1.279127)
					(mid -0.037758 -0.026651)
					(end 1.263664 -0.711602)
					(width 0.2)
				)
				(gr_arc
					(start -0.806826 1.279127)
					(mid -0.105837 -0.087395)
					(end 1.253435 -0.802342)
					(width 0.2)
				)
				(gr_arc
					(start -0.899187 1.279127)
					(mid -0.165236 -0.156885)
					(end 1.267475 -0.897258)
					(width 0.2)
				)
				(gr_arc
					(start -0.991463 1.279127)
					(mid -0.228522 -0.222449)
					(end 1.270645 -0.990112)
					(width 0.2)
				)
				(gr_arc
					(start -1.083663 1.279127)
					(mid -0.294507 -0.285313)
					(end 1.266278 -1.081674)
					(width 0.2)
				)
				(gr_line
					(start 1.279127 -0.250195)
					(end 1.279127 -1.083663)
					(width 0.2)
				)
				(gr_line
					(start -0.250195 1.279127)
					(end -1.083663 1.279127)
					(width 0.2)
				)
			)
			(teardrops
				(best_length_ratio 0.2)
				(max_length 1)
				(best_width_ratio 0.9)
				(max_width 2)
				(curved_edges yes)
				(filter_ratio 0.9)
				(enabled yes)
				(allow_two_segments yes)
				(prefer_zone_connections yes)
			)
		)
		(pad "1" thru_hole circle
			(at 0 0)
			(size 6 6)
			(drill 3.7)
			(layers "*.Cu" "*.Mask")
			(remove_unused_layers no)
			(net 1 "GND")
			(pintype "passive")
			(teardrops
				(best_length_ratio 0.4)
				(max_length 1)
				(best_width_ratio 0.9)
				(max_width 2)
				(curved_edges yes)
				(filter_ratio 0.9)
				(enabled yes)
				(allow_two_segments yes)
				(prefer_zone_connections yes)
			)
		)
	)
	(footprint "antmicro-footprints:C_0402_1005Metric"
		(layer "F.Cu")
		(at 143 140.86)
		(descr "Capacitor SMD 0402")
		(tags "capacitor SMD 0402")
		(property "Reference" "C151"
			(at -3.55 0.4 0)
			(layer "F.SilkS")
			(effects
				(font
					(size 0.7 0.7)
					(thickness 0.15)
				)
				(justify left bottom)
			)
		)
		(property "Value" "C_100n_0402"
			(at -1.022927 2.155213 0)
			(layer "F.Fab")
			(effects
				(font
					(size 0.7 0.7)
					(thickness 0.15)
				)
				(justify left bottom)
			)
		)
		(property "Datasheet" "https://www.murata.com/products/productdetail?partno=GRM155R61H104KE14%23"
			(at 0 0 0)
			(layer "F.Fab")
			(hide yes)
			(effects
				(font
					(size 1.27 1.27)
					(thickness 0.15)
				)
			)
		)
		(property "Author" "Antmicro"
			(at 0 0 0)
			(layer "F.Fab")
			(hide yes)
			(effects
				(font
					(size 1 1)
					(thickness 0.15)
				)
			)
		)
		(property "Dielectric" "X5R"
			(at 0 0 0)
			(layer "F.Fab")
			(hide yes)
			(effects
				(font
					(size 1 1)
					(thickness 0.15)
				)
			)
		)
		(property "License" "Apache-2.0"
			(at 0 0 0)
			(layer "F.Fab")
			(hide yes)
			(effects
				(font
					(size 1 1)
					(thickness 0.15)
				)
			)
		)
		(property "MPN" "GRM155R61H104KE14D"
			(at 0 0 0)
			(layer "F.Fab")
			(hide yes)
			(effects
				(font
					(size 1 1)
					(thickness 0.15)
				)
			)
		)
		(property "Manufacturer" "Murata"
			(at 0 0 0)
			(layer "F.Fab")
			(hide yes)
			(effects
				(font
					(size 1 1)
					(thickness 0.15)
				)
			)
		)
		(property "Public" "False"
			(at 0 0 0)
			(layer "F.Fab")
			(hide yes)
			(effects
				(font
					(size 1 1)
					(thickness 0.15)
				)
			)
		)
		(property "Val" "100n"
			(at 0 0 0)
			(layer "F.Fab")
			(hide yes)
			(effects
				(font
					(size 1 1)
					(thickness 0.15)
				)
			)
		)
		(property "Voltage" "50V"
			(at 0 0 0)
			(layer "F.Fab")
			(hide yes)
			(effects
				(font
					(size 1 1)
					(thickness 0.15)
				)
			)
		)
		(sheetname "KR to SFI #1")
		(sheetfile "kr_sfi.kicad_sch")
		(attr smd)
		(fp_rect
			(start -0.925 -0.47)
			(end 0.925 0.47)
			(stroke
				(width 0.05)
				(type default)
			)
			(fill no)
			(layer "F.CrtYd")
		)
		(fp_line
			(start -0.494 -0.25)
			(end 0.504 -0.25)
			(stroke
				(width 0.15)
				(type solid)
			)
			(layer "F.Fab")
		)
		(fp_line
			(start -0.494 0.248)
			(end -0.494 -0.25)
			(stroke
				(width 0.15)
				(type solid)
			)
			(layer "F.Fab")
		)
		(fp_line
			(start 0.504 -0.25)
			(end 0.504 0.248)
			(stroke
				(width 0.15)
				(type solid)
			)
			(layer "F.Fab")
		)
		(fp_line
			(start 0.504 0.248)
			(end -0.494 0.248)
			(stroke
				(width 0.15)
				(type solid)
			)
			(layer "F.Fab")
		)
		(pad "1" smd roundrect
			(at -0.48 0)
			(size 0.59 0.64)
			(layers "F.Cu" "F.Mask" "F.Paste")
			(roundrect_rratio 0.25)
			(net 109 "/2xSFP+/KR to SFI #1/CLK-")
			(pintype "passive")
			(teardrops
				(best_length_ratio 0.2)
				(max_length 1)
				(best_width_ratio 0.9)
				(max_width 2)
				(curved_edges yes)
				(filter_ratio 0.9)
				(enabled yes)
				(allow_two_segments yes)
				(prefer_zone_connections yes)
			)
		)
		(pad "2" smd roundrect
			(at 0.48 0)
			(size 0.59 0.64)
			(layers "F.Cu" "F.Mask" "F.Paste")
			(roundrect_rratio 0.25)
			(net 108 "/2xSFP+/KR to SFI #1/REFCLK+")
			(pintype "passive")
			(teardrops
				(best_length_ratio 0.2)
				(max_length 1)
				(best_width_ratio 0.9)
				(max_width 2)
				(curved_edges yes)
				(filter_ratio 0.9)
				(enabled yes)
				(allow_two_segments yes)
				(prefer_zone_connections yes)
			)
		)
	)
	(footprint "antmicro-footprints:R_0201"
		(layer "F.Cu")
		(at 134.41 147.935 -90)
		(descr "Resistor SMD 0201")
		(tags "resistor SMD 0201")
		(property "Reference" "R284"
			(at 6.475 -0.29 270)
			(layer "F.SilkS")
			(effects
				(font
					(size 0.7 0.7)
					(thickness 0.15)
				)
				(justify left bottom)
			)
		)
		(property "Value" "R_0R_0201"
			(at 0 1.25 270)
			(layer "F.Fab")
			(effects
				(font
					(size 0.7 0.7)
					(thickness 0.15)
				)
				(justify left bottom)
			)
		)
		(property "Datasheet" "https://www.bourns.com/docs/product-datasheets/cr.pdf"
			(at 0 0 270)
			(layer "F.Fab")
			(hide yes)
			(effects
				(font
					(size 1.27 1.27)
					(thickness 0.15)
				)
			)
		)
		(property "Author" "Antmicro"
			(at -13.525 282.345 0)
			(layer "F.Fab")
			(hide yes)
			(effects
				(font
					(size 1 1)
					(thickness 0.15)
				)
			)
		)
		(property "License" "Apache-2.0"
			(at -13.525 282.345 0)
			(layer "F.Fab")
			(hide yes)
			(effects
				(font
					(size 1 1)
					(thickness 0.15)
				)
			)
		)
		(property "MPN" "CR0201-FX-0R00GLF"
			(at -13.525 282.345 0)
			(layer "F.Fab")
			(hide yes)
			(effects
				(font
					(size 1 1)
					(thickness 0.15)
				)
			)
		)
		(property "Manufacturer" "Bourns"
			(at -13.525 282.345 0)
			(layer "F.Fab")
			(hide yes)
			(effects
				(font
					(size 1 1)
					(thickness 0.15)
				)
			)
		)
		(property "Tolerance" "1%"
			(at -13.525 282.345 0)
			(layer "F.Fab")
			(hide yes)
			(effects
				(font
					(size 1 1)
					(thickness 0.15)
				)
			)
		)
		(property "Val" "0R"
			(at -13.525 282.345 0)
			(layer "F.Fab")
			(hide yes)
			(effects
				(font
					(size 1 1)
					(thickness 0.15)
				)
			)
		)
		(sheetname "KR to SFI #2")
		(sheetfile "kr_sfi.kicad_sch")
		(attr smd dnp)
		(fp_rect
			(start -0.7 -0.35)
			(end 0.7 0.35)
			(stroke
				(width 0.05)
				(type default)
			)
			(fill no)
			(layer "F.CrtYd")
		)
		(fp_rect
			(start -0.3 -0.15)
			(end 0.298 0.148)
			(stroke
				(width 0.15)
				(type solid)
			)
			(fill no)
			(layer "F.Fab")
		)
		(pad "" smd roundrect
			(at -0.346 0 270)
			(size 0.318 0.36)
			(layers "F.Paste")
			(roundrect_rratio 0.25)
			(teardrops
				(best_length_ratio 0.2)
				(max_length 1)
				(best_width_ratio 0.9)
				(max_width 2)
				(curved_edges yes)
				(filter_ratio 0.9)
				(enabled yes)
				(allow_two_segments yes)
				(prefer_zone_connections yes)
			)
		)
		(pad "" smd roundrect
			(at 0.344 0 270)
			(size 0.318 0.36)
			(layers "F.Paste")
			(roundrect_rratio 0.25)
			(teardrops
				(best_length_ratio 0.2)
				(max_length 1)
				(best_width_ratio 0.9)
				(max_width 2)
				(curved_edges yes)
				(filter_ratio 0.9)
				(enabled yes)
				(allow_two_segments yes)
				(prefer_zone_connections yes)
			)
		)
		(pad "1" smd roundrect
			(at -0.32 0 270)
			(size 0.46 0.4)
			(layers "F.Cu" "F.Mask")
			(roundrect_rratio 0.25)
			(net 428 "/2xSFP+/10GKR_SFP1.RX-")
			(pintype "passive")
			(teardrops
				(best_length_ratio 0.2)
				(max_length 1)
				(best_width_ratio 0.9)
				(max_width 2)
				(curved_edges yes)
				(filter_ratio 0.9)
				(enabled yes)
				(allow_two_segments yes)
				(prefer_zone_connections yes)
			)
		)
		(pad "2" smd roundrect
			(at 0.32 0 270)
			(size 0.46 0.4)
			(layers "F.Cu" "F.Mask")
			(roundrect_rratio 0.25)
			(net 968 "/2xSFP+/KR to SFI #2/BYP_RX-")
			(pintype "passive")
			(teardrops
				(best_length_ratio 0.2)
				(max_length 1)
				(best_width_ratio 0.9)
				(max_width 2)
				(curved_edges yes)
				(filter_ratio 0.9)
				(enabled yes)
				(allow_two_segments yes)
				(prefer_zone_connections yes)
			)
		)
	)
	(footprint "antmicro-footprints:R_0402_1005Metric"
		(layer "F.Cu")
		(at 242.8 132.36 -90)
		(descr "Resistor SMD 0402")
		(tags "resistor SMD 0402")
		(property "Reference" "R176"
			(at 0.85 -0.45 90)
			(layer "F.SilkS")
			(effects
				(font
					(size 0.7 0.7)
					(thickness 0.15)
				)
				(justify right bottom)
			)
		)
		(property "Value" "R_10k_0402"
			(at -1.011843 1.772047 90)
			(layer "F.Fab")
			(effects
				(font
					(size 0.7 0.7)
					(thickness 0.15)
				)
				(justify right bottom)
			)
		)
		(property "Datasheet" "https://www.bourns.com/docs/product-datasheets/cr.pdf"
			(at 0 0 270)
			(layer "F.Fab")
			(hide yes)
			(effects
				(font
					(size 1.27 1.27)
					(thickness 0.15)
				)
			)
		)
		(property "Author" "Antmicro"
			(at 110.44 375.16 0)
			(layer "F.Fab")
			(hide yes)
			(effects
				(font
					(size 1 1)
					(thickness 0.15)
				)
			)
		)
		(property "License" "Apache-2.0"
			(at 110.44 375.16 0)
			(layer "F.Fab")
			(hide yes)
			(effects
				(font
					(size 1 1)
					(thickness 0.15)
				)
			)
		)
		(property "MPN" "CR0402-FX-1002GLF"
			(at 110.44 375.16 0)
			(layer "F.Fab")
			(hide yes)
			(effects
				(font
					(size 1 1)
					(thickness 0.15)
				)
			)
		)
		(property "Manufacturer" "Bourns"
			(at 110.44 375.16 0)
			(layer "F.Fab")
			(hide yes)
			(effects
				(font
					(size 1 1)
					(thickness 0.15)
				)
			)
		)
		(property "Public" "False"
			(at 110.44 375.16 0)
			(layer "F.Fab")
			(hide yes)
			(effects
				(font
					(size 1 1)
					(thickness 0.15)
				)
			)
		)
		(property "Tolerance" "1%"
			(at 110.44 375.16 0)
			(layer "F.Fab")
			(hide yes)
			(effects
				(font
					(size 1 1)
					(thickness 0.15)
				)
			)
		)
		(property "Val" "10k"
			(at 110.44 375.16 0)
			(layer "F.Fab")
			(hide yes)
			(effects
				(font
					(size 1 1)
					(thickness 0.15)
				)
			)
		)
		(sheetname "Com Express 7 MGMT")
		(sheetfile "com_express_7_mgmt.kicad_sch")
		(attr smd)
		(fp_rect
			(start -0.925 -0.47)
			(end 0.925 0.47)
			(stroke
				(width 0.05)
				(type default)
			)
			(fill no)
			(layer "F.CrtYd")
		)
		(fp_rect
			(start -0.5 -0.25)
			(end 0.5 0.25)
			(stroke
				(width 0.15)
				(type solid)
			)
			(fill no)
			(layer "F.Fab")
		)
		(pad "1" smd roundrect
			(at -0.48 0 270)
			(size 0.59 0.64)
			(layers "F.Cu" "F.Mask" "F.Paste")
			(roundrect_rratio 0.25)
			(net 873 "Net-(U34-EN)")
			(pintype "passive")
			(teardrops
				(best_length_ratio 0.2)
				(max_length 1)
				(best_width_ratio 0.9)
				(max_width 2)
				(curved_edges yes)
				(filter_ratio 0.9)
				(enabled yes)
				(allow_two_segments yes)
				(prefer_zone_connections yes)
			)
		)
		(pad "2" smd roundrect
			(at 0.48 0 270)
			(size 0.59 0.64)
			(layers "F.Cu" "F.Mask" "F.Paste")
			(roundrect_rratio 0.25)
			(net 73 "+3V3_AON")
			(pintype "passive")
			(teardrops
				(best_length_ratio 0.2)
				(max_length 1)
				(best_width_ratio 0.9)
				(max_width 2)
				(curved_edges yes)
				(filter_ratio 0.9)
				(enabled yes)
				(allow_two_segments yes)
				(prefer_zone_connections yes)
			)
		)
	)
	(footprint "antmicro-footprints:C_0201"
		(layer "F.Cu")
		(at 137.412 147.31 90)
		(descr "Capacitor SMD 0201")
		(tags "capacitor SMD 0201")
		(property "Reference" "C180"
			(at -4.099 0.288 90)
			(layer "F.SilkS")
			(effects
				(font
					(size 0.7 0.7)
					(thickness 0.15)
				)
				(justify left bottom)
			)
		)
		(property "Value" "C_100n_0201_25V"
			(at 0 1.4 90)
			(layer "F.Fab")
			(effects
				(font
					(size 0.7 0.7)
					(thickness 0.15)
				)
				(justify left bottom)
			)
		)
		(property "Datasheet" "https://product.tdk.com/en/search/capacitor/ceramic/mlcc/info?part_no=C0603X5R1E104K030BB"
			(at 0 0 90)
			(layer "F.Fab")
			(hide yes)
			(effects
				(font
					(size 1.27 1.27)
					(thickness 0.15)
				)
			)
		)
		(property "Author" "Antmicro"
			(at 284.722 9.898 0)
			(layer "F.Fab")
			(hide yes)
			(effects
				(font
					(size 1 1)
					(thickness 0.15)
				)
			)
		)
		(property "Dielectric" ""
			(at 284.722 9.898 0)
			(layer "F.Fab")
			(hide yes)
			(effects
				(font
					(size 1 1)
					(thickness 0.15)
				)
			)
		)
		(property "License" "Apache-2.0"
			(at 284.722 9.898 0)
			(layer "F.Fab")
			(hide yes)
			(effects
				(font
					(size 1 1)
					(thickness 0.15)
				)
			)
		)
		(property "MPN" "C0603X5R1E104K030BB"
			(at 284.722 9.898 0)
			(layer "F.Fab")
			(hide yes)
			(effects
				(font
					(size 1 1)
					(thickness 0.15)
				)
			)
		)
		(property "Manufacturer" "TDK"
			(at 284.722 9.898 0)
			(layer "F.Fab")
			(hide yes)
			(effects
				(font
					(size 1 1)
					(thickness 0.15)
				)
			)
		)
		(property "Public" "False"
			(at 284.722 9.898 0)
			(layer "F.Fab")
			(hide yes)
			(effects
				(font
					(size 1 1)
					(thickness 0.15)
				)
			)
		)
		(property "Val" "100n"
			(at 284.722 9.898 0)
			(layer "F.Fab")
			(hide yes)
			(effects
				(font
					(size 1 1)
					(thickness 0.15)
				)
			)
		)
		(property "Voltage" "25V"
			(at 284.722 9.898 0)
			(layer "F.Fab")
			(hide yes)
			(effects
				(font
					(size 1 1)
					(thickness 0.15)
				)
			)
		)
		(sheetname "KR to SFI #2")
		(sheetfile "kr_sfi.kicad_sch")
		(attr smd)
		(fp_rect
			(start -0.7 -0.35)
			(end 0.7 0.35)
			(stroke
				(width 0.05)
				(type default)
			)
			(fill no)
			(layer "F.CrtYd")
		)
		(fp_rect
			(start 0.3 0.15)
			(end -0.301 -0.149)
			(stroke
				(width 0.15)
				(type solid)
			)
			(fill no)
			(layer "F.Fab")
		)
		(pad "" smd roundrect
			(at -0.349 -0.002 90)
			(size 0.318 0.36)
			(layers "F.Paste")
			(roundrect_rratio 0.25)
			(teardrops
				(best_length_ratio 0.2)
				(max_length 1)
				(best_width_ratio 0.9)
				(max_width 2)
				(curved_edges yes)
				(filter_ratio 0.9)
				(enabled yes)
				(allow_two_segments yes)
				(prefer_zone_connections yes)
			)
		)
		(pad "" smd roundrect
			(at 0.341 -0.002 90)
			(size 0.318 0.36)
			(layers "F.Paste")
			(roundrect_rratio 0.25)
			(teardrops
				(best_length_ratio 0.2)
				(max_length 1)
				(best_width_ratio 0.9)
				(max_width 2)
				(curved_edges yes)
				(filter_ratio 0.9)
				(enabled yes)
				(allow_two_segments yes)
				(prefer_zone_connections yes)
			)
		)
		(pad "1" smd roundrect
			(at -0.321 -0.002 90)
			(size 0.46 0.4)
			(layers "F.Cu" "F.Mask")
			(roundrect_rratio 0.25)
			(net 119 "/2xSFP+/10GKR_SFP1.TX+")
			(pintype "passive")
			(teardrops
				(best_length_ratio 0.2)
				(max_length 1)
				(best_width_ratio 0.9)
				(max_width 2)
				(curved_edges yes)
				(filter_ratio 0.9)
				(enabled yes)
				(allow_two_segments yes)
				(prefer_zone_connections yes)
			)
		)
		(pad "2" smd roundrect
			(at 0.32 -0.002 90)
			(size 0.46 0.4)
			(layers "F.Cu" "F.Mask")
			(roundrect_rratio 0.25)
			(net 120 "/2xSFP+/KR to SFI #2/KR_C.TX+")
			(pintype "passive")
			(teardrops
				(best_length_ratio 0.2)
				(max_length 1)
				(best_width_ratio 0.9)
				(max_width 2)
				(curved_edges yes)
				(filter_ratio 0.9)
				(enabled yes)
				(allow_two_segments yes)
				(prefer_zone_connections yes)
			)
		)
	)
	(footprint "antmicro-footprints:R_0402_1005Metric"
		(layer "F.Cu")
		(at 131.25 97.91)
		(descr "Resistor SMD 0402")
		(tags "resistor SMD 0402")
		(property "Reference" "R30"
			(at -1.05 -0.55 0)
			(layer "F.SilkS")
			(effects
				(font
					(size 0.7 0.7)
					(thickness 0.15)
				)
				(justify left bottom)
			)
		)
		(property "Value" "R_0R_0402"
			(at -1.011843 1.772047 0)
			(layer "F.Fab")
			(effects
				(font
					(size 0.7 0.7)
					(thickness 0.15)
				)
				(justify left bottom)
			)
		)
		(property "Datasheet" "https://industrial.panasonic.com/cdbs/www-data/pdf/RDA0000/AOA0000C301.pdf"
			(at 0 0 0)
			(layer "F.Fab")
			(hide yes)
			(effects
				(font
					(size 1.27 1.27)
					(thickness 0.15)
				)
			)
		)
		(property "Author" "Antmicro"
			(at 0 0 0)
			(layer "F.Fab")
			(hide yes)
			(effects
				(font
					(size 1 1)
					(thickness 0.15)
				)
			)
		)
		(property "Current" "1A"
			(at 0 0 0)
			(layer "F.Fab")
			(hide yes)
			(effects
				(font
					(size 1 1)
					(thickness 0.15)
				)
			)
		)
		(property "License" "Apache-2.0"
			(at 0 0 0)
			(layer "F.Fab")
			(hide yes)
			(effects
				(font
					(size 1 1)
					(thickness 0.15)
				)
			)
		)
		(property "MPN" "ERJ2GE0R00X"
			(at 0 0 0)
			(layer "F.Fab")
			(hide yes)
			(effects
				(font
					(size 1 1)
					(thickness 0.15)
				)
			)
		)
		(property "Manufacturer" "Panasonic"
			(at 0 0 0)
			(layer "F.Fab")
			(hide yes)
			(effects
				(font
					(size 1 1)
					(thickness 0.15)
				)
			)
		)
		(property "Public" "False"
			(at 0 0 0)
			(layer "F.Fab")
			(hide yes)
			(effects
				(font
					(size 1 1)
					(thickness 0.15)
				)
			)
		)
		(property "Tolerance" ""
			(at 0 0 0)
			(layer "F.Fab")
			(hide yes)
			(effects
				(font
					(size 1 1)
					(thickness 0.15)
				)
			)
		)
		(property "Val" "0R"
			(at 0 0 0)
			(layer "F.Fab")
			(hide yes)
			(effects
				(font
					(size 1 1)
					(thickness 0.15)
				)
			)
		)
		(sheetname "2xUSB3.0+RJ45")
		(sheetfile "usb3+rj45.kicad_sch")
		(attr smd)
		(fp_rect
			(start -0.925 -0.47)
			(end 0.925 0.47)
			(stroke
				(width 0.05)
				(type default)
			)
			(fill no)
			(layer "F.CrtYd")
		)
		(fp_rect
			(start -0.5 -0.25)
			(end 0.5 0.25)
			(stroke
				(width 0.15)
				(type solid)
			)
			(fill no)
			(layer "F.Fab")
		)
		(pad "1" smd roundrect
			(at -0.48 0)
			(size 0.59 0.64)
			(layers "F.Cu" "F.Mask" "F.Paste")
			(roundrect_rratio 0.25)
			(net 51 "Net-(C13-Pad1)")
			(pintype "passive")
			(teardrops
				(best_length_ratio 0.2)
				(max_length 1)
				(best_width_ratio 0.9)
				(max_width 2)
				(curved_edges yes)
				(filter_ratio 0.9)
				(enabled yes)
				(allow_two_segments yes)
				(prefer_zone_connections yes)
			)
		)
		(pad "2" smd roundrect
			(at 0.48 0)
			(size 0.59 0.64)
			(layers "F.Cu" "F.Mask" "F.Paste")
			(roundrect_rratio 0.25)
			(net 296 "/2xUSB3.0+RJ45/GbE.CTREF")
			(pintype "passive")
			(teardrops
				(best_length_ratio 0.2)
				(max_length 1)
				(best_width_ratio 0.9)
				(max_width 2)
				(curved_edges yes)
				(filter_ratio 0.9)
				(enabled yes)
				(allow_two_segments yes)
				(prefer_zone_connections yes)
			)
		)
	)
	(footprint "antmicro-footprints:C_0402_1005Metric"
		(layer "F.Cu")
		(at 253.32825 127.651748 90)
		(descr "Capacitor SMD 0402")
		(tags "capacitor SMD 0402")
		(property "Reference" "C97"
			(at 0.841748 0.47175 90)
			(layer "F.SilkS")
			(effects
				(font
					(size 0.7 0.7)
					(thickness 0.15)
				)
				(justify left bottom)
			)
		)
		(property "Value" "C_100n_0402"
			(at -1.022927 2.155213 90)
			(layer "F.Fab")
			(effects
				(font
					(size 0.7 0.7)
					(thickness 0.15)
				)
				(justify left bottom)
			)
		)
		(property "Datasheet" "https://www.murata.com/products/productdetail?partno=GRM155R61H104KE14%23"
			(at 0 0 90)
			(layer "F.Fab")
			(hide yes)
			(effects
				(font
					(size 1.27 1.27)
					(thickness 0.15)
				)
			)
		)
		(property "Author" "Antmicro"
			(at 380.979998 -125.676502 0)
			(layer "F.Fab")
			(hide yes)
			(effects
				(font
					(size 1 1)
					(thickness 0.15)
				)
			)
		)
		(property "Dielectric" "X5R"
			(at 380.979998 -125.676502 0)
			(layer "F.Fab")
			(hide yes)
			(effects
				(font
					(size 1 1)
					(thickness 0.15)
				)
			)
		)
		(property "License" "Apache-2.0"
			(at 380.979998 -125.676502 0)
			(layer "F.Fab")
			(hide yes)
			(effects
				(font
					(size 1 1)
					(thickness 0.15)
				)
			)
		)
		(property "MPN" "GRM155R61H104KE14D"
			(at 380.979998 -125.676502 0)
			(layer "F.Fab")
			(hide yes)
			(effects
				(font
					(size 1 1)
					(thickness 0.15)
				)
			)
		)
		(property "Manufacturer" "Murata"
			(at 380.979998 -125.676502 0)
			(layer "F.Fab")
			(hide yes)
			(effects
				(font
					(size 1 1)
					(thickness 0.15)
				)
			)
		)
		(property "Public" "False"
			(at 380.979998 -125.676502 0)
			(layer "F.Fab")
			(hide yes)
			(effects
				(font
					(size 1 1)
					(thickness 0.15)
				)
			)
		)
		(property "Val" "100n"
			(at 380.979998 -125.676502 0)
			(layer "F.Fab")
			(hide yes)
			(effects
				(font
					(size 1 1)
					(thickness 0.15)
				)
			)
		)
		(property "Voltage" "50V"
			(at 380.979998 -125.676502 0)
			(layer "F.Fab")
			(hide yes)
			(effects
				(font
					(size 1 1)
					(thickness 0.15)
				)
			)
		)
		(sheetname "Com Express 7 MGMT")
		(sheetfile "com_express_7_mgmt.kicad_sch")
		(attr smd)
		(fp_rect
			(start -0.925 -0.47)
			(end 0.925 0.47)
			(stroke
				(width 0.05)
				(type default)
			)
			(fill no)
			(layer "F.CrtYd")
		)
		(fp_line
			(start 0.504 -0.25)
			(end 0.504 0.248)
			(stroke
				(width 0.15)
				(type solid)
			)
			(layer "F.Fab")
		)
		(fp_line
			(start -0.494 -0.25)
			(end 0.504 -0.25)
			(stroke
				(width 0.15)
				(type solid)
			)
			(layer "F.Fab")
		)
		(fp_line
			(start 0.504 0.248)
			(end -0.494 0.248)
			(stroke
				(width 0.15)
				(type solid)
			)
			(layer "F.Fab")
		)
		(fp_line
			(start -0.494 0.248)
			(end -0.494 -0.25)
			(stroke
				(width 0.15)
				(type solid)
			)
			(layer "F.Fab")
		)
		(pad "1" smd roundrect
			(at -0.48 0 90)
			(size 0.59 0.64)
			(layers "F.Cu" "F.Mask" "F.Paste")
			(roundrect_rratio 0.25)
			(net 1 "GND")
			(pintype "passive")
			(teardrops
				(best_length_ratio 0.2)
				(max_length 1)
				(best_width_ratio 0.9)
				(max_width 2)
				(curved_edges yes)
				(filter_ratio 0.9)
				(enabled yes)
				(allow_two_segments yes)
				(prefer_zone_connections yes)
			)
		)
		(pad "2" smd roundrect
			(at 0.48 0 90)
			(size 0.59 0.64)
			(layers "F.Cu" "F.Mask" "F.Paste")
			(roundrect_rratio 0.25)
			(net 73 "+3V3_AON")
			(pintype "passive")
			(teardrops
				(best_length_ratio 0.2)
				(max_length 1)
				(best_width_ratio 0.9)
				(max_width 2)
				(curved_edges yes)
				(filter_ratio 0.9)
				(enabled yes)
				(allow_two_segments yes)
				(prefer_zone_connections yes)
			)
		)
	)
	(footprint "antmicro-footprints:R_0402_1005Metric"
		(layer "F.Cu")
		(at 155.299 162.11 180)
		(descr "Resistor SMD 0402")
		(tags "resistor SMD 0402")
		(property "Reference" "R47"
			(at -6.701 17.5 0)
			(layer "F.SilkS")
			(effects
				(font
					(size 0.7 0.7)
					(thickness 0.15)
				)
				(justify right bottom)
			)
		)
		(property "Value" "R_0R_0402"
			(at -1.011843 1.772047 0)
			(layer "F.Fab")
			(effects
				(font
					(size 0.7 0.7)
					(thickness 0.15)
				)
				(justify right bottom)
			)
		)
		(property "Datasheet" "https://industrial.panasonic.com/cdbs/www-data/pdf/RDA0000/AOA0000C301.pdf"
			(at 0 0 180)
			(layer "F.Fab")
			(hide yes)
			(effects
				(font
					(size 1.27 1.27)
					(thickness 0.15)
				)
			)
		)
		(property "Author" "Antmicro"
			(at 310.598 324.22 0)
			(layer "F.Fab")
			(hide yes)
			(effects
				(font
					(size 1 1)
					(thickness 0.15)
				)
			)
		)
		(property "Current" "1A"
			(at 310.598 324.22 0)
			(layer "F.Fab")
			(hide yes)
			(effects
				(font
					(size 1 1)
					(thickness 0.15)
				)
			)
		)
		(property "License" "Apache-2.0"
			(at 310.598 324.22 0)
			(layer "F.Fab")
			(hide yes)
			(effects
				(font
					(size 1 1)
					(thickness 0.15)
				)
			)
		)
		(property "MPN" "ERJ2GE0R00X"
			(at 310.598 324.22 0)
			(layer "F.Fab")
			(hide yes)
			(effects
				(font
					(size 1 1)
					(thickness 0.15)
				)
			)
		)
		(property "Manufacturer" "Panasonic"
			(at 310.598 324.22 0)
			(layer "F.Fab")
			(hide yes)
			(effects
				(font
					(size 1 1)
					(thickness 0.15)
				)
			)
		)
		(property "Public" "False"
			(at 310.598 324.22 0)
			(layer "F.Fab")
			(hide yes)
			(effects
				(font
					(size 1 1)
					(thickness 0.15)
				)
			)
		)
		(property "Tolerance" ""
			(at 310.598 324.22 0)
			(layer "F.Fab")
			(hide yes)
			(effects
				(font
					(size 1 1)
					(thickness 0.15)
				)
			)
		)
		(property "Val" "0R"
			(at 310.598 324.22 0)
			(layer "F.Fab")
			(hide yes)
			(effects
				(font
					(size 1 1)
					(thickness 0.15)
				)
			)
		)
		(sheetname "2xSFP+")
		(sheetfile "2xSFP+.kicad_sch")
		(attr smd)
		(fp_rect
			(start -0.925 -0.47)
			(end 0.925 0.47)
			(stroke
				(width 0.05)
				(type default)
			)
			(fill no)
			(layer "F.CrtYd")
		)
		(fp_rect
			(start -0.5 -0.25)
			(end 0.5 0.25)
			(stroke
				(width 0.15)
				(type solid)
			)
			(fill no)
			(layer "F.Fab")
		)
		(pad "1" smd roundrect
			(at -0.48 0 180)
			(size 0.59 0.64)
			(layers "F.Cu" "F.Mask" "F.Paste")
			(roundrect_rratio 0.25)
			(net 566 "/2xSFP+/~{LED1_1}")
			(pintype "passive")
			(teardrops
				(best_length_ratio 0.2)
				(max_length 1)
				(best_width_ratio 0.9)
				(max_width 2)
				(curved_edges yes)
				(filter_ratio 0.9)
				(enabled yes)
				(allow_two_segments yes)
				(prefer_zone_connections yes)
			)
		)
		(pad "2" smd roundrect
			(at 0.48 0 180)
			(size 0.59 0.64)
			(layers "F.Cu" "F.Mask" "F.Paste")
			(roundrect_rratio 0.25)
			(net 929 "/2xSFP+/SFP1_LEDG")
			(pintype "passive")
			(teardrops
				(best_length_ratio 0.2)
				(max_length 1)
				(best_width_ratio 0.9)
				(max_width 2)
				(curved_edges yes)
				(filter_ratio 0.9)
				(enabled yes)
				(allow_two_segments yes)
				(prefer_zone_connections yes)
			)
		)
	)
	(footprint "antmicro-footprints:USON-10_2.5x1mm_P0.5mm"
		(layer "F.Cu")
		(at 314.75 167.01)
		(descr "USON-10 2.5x1mm_ Pitch 0.5mm")
		(tags "USON-10 2.5x1mm Pitch 0.5mm")
		(property "Reference" "U13"
			(at -0.9 1.15 90)
			(layer "F.SilkS")
			(effects
				(font
					(size 0.7 0.7)
					(thickness 0.15)
				)
				(justify left bottom)
			)
		)
		(property "Value" "ESD204DQAR"
			(at 0.018 2.499 0)
			(layer "F.Fab")
			(effects
				(font
					(size 0.7 0.7)
					(thickness 0.15)
				)
				(justify left bottom)
			)
		)
		(property "Datasheet" "https://www.ti.com/lit/ds/symlink/esd204.pdf?ts=1706004844383&ref_url=https%253A%252F%252Fwww.ti.com%252Finterface%252Fdiodes%252Fesd-protection-diodes%252Fproducts.html"
			(at 0 0 0)
			(layer "F.Fab")
			(hide yes)
			(effects
				(font
					(size 1.27 1.27)
					(thickness 0.15)
				)
			)
		)
		(property "Author" "Antmicro"
			(at 0 0 0)
			(layer "F.Fab")
			(hide yes)
			(effects
				(font
					(size 1 1)
					(thickness 0.15)
				)
			)
		)
		(property "License" "Apache-2.0"
			(at 0 0 0)
			(layer "F.Fab")
			(hide yes)
			(effects
				(font
					(size 1 1)
					(thickness 0.15)
				)
			)
		)
		(property "MPN" "ESD204DQAR"
			(at 0 0 0)
			(layer "F.Fab")
			(hide yes)
			(effects
				(font
					(size 1 1)
					(thickness 0.15)
				)
			)
		)
		(property "Manufacturer" "Texas Instruments"
			(at 0 0 0)
			(layer "F.Fab")
			(hide yes)
			(effects
				(font
					(size 1 1)
					(thickness 0.15)
				)
			)
		)
		(sheetname "Backplane")
		(sheetfile "backplane.kicad_sch")
		(attr smd)
		(fp_line
			(start 0.498 -1.401)
			(end -0.5 -1.401)
			(stroke
				(width 0.15)
				(type solid)
			)
			(layer "F.SilkS")
		)
		(fp_line
			(start 0.498 1.398)
			(end -0.5 1.398)
			(stroke
				(width 0.15)
				(type solid)
			)
			(layer "F.SilkS")
		)
		(fp_circle
			(center -0.68 -1.27)
			(end -0.63 -1.27)
			(stroke
				(width 0.15)
				(type solid)
			)
			(fill yes)
			(layer "F.SilkS")
		)
		(fp_rect
			(start -0.8 -1.5)
			(end 0.8 1.499)
			(stroke
				(width 0.05)
				(type solid)
			)
			(fill no)
			(layer "F.CrtYd")
		)
		(fp_line
			(start -0.5 -1)
			(end -0.5 1.249)
			(stroke
				(width 0.15)
				(type solid)
			)
			(layer "F.Fab")
		)
		(fp_line
			(start -0.5 1.249)
			(end 0.498 1.249)
			(stroke
				(width 0.15)
				(type solid)
			)
			(layer "F.Fab")
		)
		(fp_line
			(start -0.25 -1.25)
			(end -0.5 -1)
			(stroke
				(width 0.15)
				(type solid)
			)
			(layer "F.Fab")
		)
		(fp_line
			(start 0.498 -1.25)
			(end -0.25 -1.25)
			(stroke
				(width 0.15)
				(type solid)
			)
			(layer "F.Fab")
		)
		(fp_line
			(start 0.498 -1.25)
			(end 0.498 1.249)
			(stroke
				(width 0.15)
				(type solid)
			)
			(layer "F.Fab")
		)
		(pad "1" smd roundrect
			(at -0.387 -1 270)
			(size 0.25 0.55)
			(layers "F.Cu" "F.Mask" "F.Paste")
			(roundrect_rratio 0.25)
			(net 995 "unconnected-(U13-Pad1)_1")
			(pintype "passive+no_connect")
			(teardrops
				(best_length_ratio 0.2)
				(max_length 1)
				(best_width_ratio 0.9)
				(max_width 2)
				(curved_edges yes)
				(filter_ratio 0.9)
				(enabled yes)
				(allow_two_segments yes)
				(prefer_zone_connections yes)
			)
		)
		(pad "2" smd roundrect
			(at -0.387 -0.5 270)
			(size 0.25 0.55)
			(layers "F.Cu" "F.Mask" "F.Paste")
			(roundrect_rratio 0.25)
			(net 972 "unconnected-(U13-Pad2)")
			(pintype "passive+no_connect")
			(teardrops
				(best_length_ratio 0.2)
				(max_length 1)
				(best_width_ratio 0.9)
				(max_width 2)
				(curved_edges yes)
				(filter_ratio 0.9)
				(enabled yes)
				(allow_two_segments yes)
				(prefer_zone_connections yes)
			)
		)
		(pad "3" smd roundrect
			(at -0.387 0 270)
			(size 0.4 0.55)
			(layers "F.Cu" "F.Mask" "F.Paste")
			(roundrect_rratio 0.25)
			(net 1 "GND")
			(pintype "power_in")
			(teardrops
				(best_length_ratio 0.2)
				(max_length 1)
				(best_width_ratio 0.9)
				(max_width 2)
				(curved_edges yes)
				(filter_ratio 0.9)
				(enabled yes)
				(allow_two_segments yes)
				(prefer_zone_connections yes)
			)
		)
		(pad "4" smd roundrect
			(at -0.387 0.498 270)
			(size 0.25 0.55)
			(layers "F.Cu" "F.Mask" "F.Paste")
			(roundrect_rratio 0.25)
			(net 208 "/Backplane/UART.RX")
			(pintype "passive")
			(teardrops
				(best_length_ratio 0.2)
				(max_length 1)
				(best_width_ratio 0.9)
				(max_width 2)
				(curved_edges yes)
				(filter_ratio 0.9)
				(enabled yes)
				(allow_two_segments yes)
				(prefer_zone_connections yes)
			)
		)
		(pad "5" smd roundrect
			(at -0.387 0.998 270)
			(size 0.25 0.55)
			(layers "F.Cu" "F.Mask" "F.Paste")
			(roundrect_rratio 0.25)
			(net 207 "/Backplane/UART.TX")
			(pintype "passive")
			(teardrops
				(best_length_ratio 0.2)
				(max_length 1)
				(best_width_ratio 0.9)
				(max_width 2)
				(curved_edges yes)
				(filter_ratio 0.9)
				(enabled yes)
				(allow_two_segments yes)
				(prefer_zone_connections yes)
			)
		)
		(pad "6" smd roundrect
			(at 0.385 0.998 270)
			(size 0.25 0.55)
			(layers "F.Cu" "F.Mask" "F.Paste")
			(roundrect_rratio 0.25)
			(net 207 "/Backplane/UART.TX")
			(pintype "passive")
			(teardrops
				(best_length_ratio 0.2)
				(max_length 1)
				(best_width_ratio 0.9)
				(max_width 2)
				(curved_edges yes)
				(filter_ratio 0.9)
				(enabled yes)
				(allow_two_segments yes)
				(prefer_zone_connections yes)
			)
		)
		(pad "7" smd roundrect
			(at 0.385 0.498 270)
			(size 0.25 0.55)
			(layers "F.Cu" "F.Mask" "F.Paste")
			(roundrect_rratio 0.25)
			(net 208 "/Backplane/UART.RX")
			(pintype "passive")
			(teardrops
				(best_length_ratio 0.2)
				(max_length 1)
				(best_width_ratio 0.9)
				(max_width 2)
				(curved_edges yes)
				(filter_ratio 0.9)
				(enabled yes)
				(allow_two_segments yes)
				(prefer_zone_connections yes)
			)
		)
		(pad "8" smd roundrect
			(at 0.385 0 270)
			(size 0.4 0.55)
			(layers "F.Cu" "F.Mask" "F.Paste")
			(roundrect_rratio 0.25)
			(net 1 "GND")
			(pintype "passive")
			(teardrops
				(best_length_ratio 0.2)
				(max_length 1)
				(best_width_ratio 0.9)
				(max_width 2)
				(curved_edges yes)
				(filter_ratio 0.9)
				(enabled yes)
				(allow_two_segments yes)
				(prefer_zone_connections yes)
			)
		)
		(pad "9" smd roundrect
			(at 0.385 -0.5 270)
			(size 0.25 0.55)
			(layers "F.Cu" "F.Mask" "F.Paste")
			(roundrect_rratio 0.25)
			(net 994 "unconnected-(U13-Pad2)_1")
			(pintype "passive+no_connect")
			(teardrops
				(best_length_ratio 0.2)
				(max_length 1)
				(best_width_ratio 0.9)
				(max_width 2)
				(curved_edges yes)
				(filter_ratio 0.9)
				(enabled yes)
				(allow_two_segments yes)
				(prefer_zone_connections yes)
			)
		)
		(pad "10" smd roundrect
			(at 0.385 -1 270)
			(size 0.25 0.55)
			(layers "F.Cu" "F.Mask" "F.Paste")
			(roundrect_rratio 0.25)
			(net 971 "unconnected-(U13-Pad1)")
			(pintype "passive+no_connect")
			(teardrops
				(best_length_ratio 0.2)
				(max_length 1)
				(best_width_ratio 0.9)
				(max_width 2)
				(curved_edges yes)
				(filter_ratio 0.9)
				(enabled yes)
				(allow_two_segments yes)
				(prefer_zone_connections yes)
			)
		)
	)
	(footprint "antmicro-footprints:R_0402_1005Metric"
		(layer "F.Cu")
		(at 124.84 134.88 180)
		(descr "Resistor SMD 0402")
		(tags "resistor SMD 0402")
		(property "Reference" "R304"
			(at 0.79 -0.43 0)
			(layer "F.SilkS")
			(effects
				(font
					(size 0.7 0.7)
					(thickness 0.15)
				)
				(justify right bottom)
			)
		)
		(property "Value" "R_10k_0402"
			(at -1.011843 1.772047 0)
			(layer "F.Fab")
			(effects
				(font
					(size 0.7 0.7)
					(thickness 0.15)
				)
				(justify right bottom)
			)
		)
		(property "Datasheet" "https://www.bourns.com/docs/product-datasheets/cr.pdf"
			(at 0 0 180)
			(layer "F.Fab")
			(hide yes)
			(effects
				(font
					(size 1.27 1.27)
					(thickness 0.15)
				)
			)
		)
		(property "Author" "Antmicro"
			(at 249.68 269.76 0)
			(layer "F.Fab")
			(hide yes)
			(effects
				(font
					(size 1 1)
					(thickness 0.15)
				)
			)
		)
		(property "License" "Apache-2.0"
			(at 249.68 269.76 0)
			(layer "F.Fab")
			(hide yes)
			(effects
				(font
					(size 1 1)
					(thickness 0.15)
				)
			)
		)
		(property "MPN" "CR0402-FX-1002GLF"
			(at 249.68 269.76 0)
			(layer "F.Fab")
			(hide yes)
			(effects
				(font
					(size 1 1)
					(thickness 0.15)
				)
			)
		)
		(property "Manufacturer" "Bourns"
			(at 249.68 269.76 0)
			(layer "F.Fab")
			(hide yes)
			(effects
				(font
					(size 1 1)
					(thickness 0.15)
				)
			)
		)
		(property "Public" "False"
			(at 249.68 269.76 0)
			(layer "F.Fab")
			(hide yes)
			(effects
				(font
					(size 1 1)
					(thickness 0.15)
				)
			)
		)
		(property "Tolerance" "1%"
			(at 249.68 269.76 0)
			(layer "F.Fab")
			(hide yes)
			(effects
				(font
					(size 1 1)
					(thickness 0.15)
				)
			)
		)
		(property "Val" "10k"
			(at 249.68 269.76 0)
			(layer "F.Fab")
			(hide yes)
			(effects
				(font
					(size 1 1)
					(thickness 0.15)
				)
			)
		)
		(sheetname "KR to SFI #2")
		(sheetfile "kr_sfi.kicad_sch")
		(attr smd dnp)
		(fp_rect
			(start -0.925 -0.47)
			(end 0.925 0.47)
			(stroke
				(width 0.05)
				(type default)
			)
			(fill no)
			(layer "F.CrtYd")
		)
		(fp_rect
			(start -0.5 -0.25)
			(end 0.5 0.25)
			(stroke
				(width 0.15)
				(type solid)
			)
			(fill no)
			(layer "F.Fab")
		)
		(pad "1" smd roundrect
			(at -0.48 0 180)
			(size 0.59 0.64)
			(layers "F.Cu" "F.Mask" "F.Paste")
			(roundrect_rratio 0.25)
			(net 684 "Net-(U45C-ST)")
			(pintype "passive")
			(teardrops
				(best_length_ratio 0.2)
				(max_length 1)
				(best_width_ratio 0.9)
				(max_width 2)
				(curved_edges yes)
				(filter_ratio 0.9)
				(enabled yes)
				(allow_two_segments yes)
				(prefer_zone_connections yes)
			)
		)
		(pad "2" smd roundrect
			(at 0.48 0 180)
			(size 0.59 0.64)
			(layers "F.Cu" "F.Mask" "F.Paste")
			(roundrect_rratio 0.25)
			(net 78 "+1V8")
			(pintype "passive")
			(teardrops
				(best_length_ratio 0.2)
				(max_length 1)
				(best_width_ratio 0.9)
				(max_width 2)
				(curved_edges yes)
				(filter_ratio 0.9)
				(enabled yes)
				(allow_two_segments yes)
				(prefer_zone_connections yes)
			)
		)
	)
	(footprint "antmicro-footprints:R_0201"
		(layer "F.Cu")
		(at 152.57 147.31 90)
		(descr "Resistor SMD 0201")
		(tags "resistor SMD 0201")
		(property "Reference" "R257"
			(at -4.125 0.28 90)
			(layer "F.SilkS")
			(effects
				(font
					(size 0.7 0.7)
					(thickness 0.15)
				)
				(justify left bottom)
			)
		)
		(property "Value" "R_0R_0201"
			(at 0 1.25 90)
			(layer "F.Fab")
			(effects
				(font
					(size 0.7 0.7)
					(thickness 0.15)
				)
				(justify left bottom)
			)
		)
		(property "Datasheet" "https://www.bourns.com/docs/product-datasheets/cr.pdf"
			(at 0 0 90)
			(layer "F.Fab")
			(hide yes)
			(effects
				(font
					(size 1.27 1.27)
					(thickness 0.15)
				)
			)
		)
		(property "Author" "Antmicro"
			(at 299.88 -5.26 0)
			(layer "F.Fab")
			(hide yes)
			(effects
				(font
					(size 1 1)
					(thickness 0.15)
				)
			)
		)
		(property "License" "Apache-2.0"
			(at 299.88 -5.26 0)
			(layer "F.Fab")
			(hide yes)
			(effects
				(font
					(size 1 1)
					(thickness 0.15)
				)
			)
		)
		(property "MPN" "CR0201-FX-0R00GLF"
			(at 299.88 -5.26 0)
			(layer "F.Fab")
			(hide yes)
			(effects
				(font
					(size 1 1)
					(thickness 0.15)
				)
			)
		)
		(property "Manufacturer" "Bourns"
			(at 299.88 -5.26 0)
			(layer "F.Fab")
			(hide yes)
			(effects
				(font
					(size 1 1)
					(thickness 0.15)
				)
			)
		)
		(property "Tolerance" "1%"
			(at 299.88 -5.26 0)
			(layer "F.Fab")
			(hide yes)
			(effects
				(font
					(size 1 1)
					(thickness 0.15)
				)
			)
		)
		(property "Val" "0R"
			(at 299.88 -5.26 0)
			(layer "F.Fab")
			(hide yes)
			(effects
				(font
					(size 1 1)
					(thickness 0.15)
				)
			)
		)
		(sheetname "KR to SFI #1")
		(sheetfile "kr_sfi.kicad_sch")
		(attr smd)
		(fp_rect
			(start -0.7 -0.35)
			(end 0.7 0.35)
			(stroke
				(width 0.05)
				(type default)
			)
			(fill no)
			(layer "F.CrtYd")
		)
		(fp_rect
			(start -0.3 -0.15)
			(end 0.298 0.148)
			(stroke
				(width 0.15)
				(type solid)
			)
			(fill no)
			(layer "F.Fab")
		)
		(pad "" smd roundrect
			(at -0.346 0 90)
			(size 0.318 0.36)
			(layers "F.Paste")
			(roundrect_rratio 0.25)
			(teardrops
				(best_length_ratio 0.2)
				(max_length 1)
				(best_width_ratio 0.9)
				(max_width 2)
				(curved_edges yes)
				(filter_ratio 0.9)
				(enabled yes)
				(allow_two_segments yes)
				(prefer_zone_connections yes)
			)
		)
		(pad "" smd roundrect
			(at 0.344 0 90)
			(size 0.318 0.36)
			(layers "F.Paste")
			(roundrect_rratio 0.25)
			(teardrops
				(best_length_ratio 0.2)
				(max_length 1)
				(best_width_ratio 0.9)
				(max_width 2)
				(curved_edges yes)
				(filter_ratio 0.9)
				(enabled yes)
				(allow_two_segments yes)
				(prefer_zone_connections yes)
			)
		)
		(pad "1" smd roundrect
			(at -0.32 0 90)
			(size 0.46 0.4)
			(layers "F.Cu" "F.Mask")
			(roundrect_rratio 0.25)
			(net 433 "/2xSFP+/10GKR_SFP0.RX-")
			(pintype "passive")
			(teardrops
				(best_length_ratio 0.2)
				(max_length 1)
				(best_width_ratio 0.9)
				(max_width 2)
				(curved_edges yes)
				(filter_ratio 0.9)
				(enabled yes)
				(allow_two_segments yes)
				(prefer_zone_connections yes)
			)
		)
		(pad "2" smd roundrect
			(at 0.32 0 90)
			(size 0.46 0.4)
			(layers "F.Cu" "F.Mask")
			(roundrect_rratio 0.25)
			(net 665 "/2xSFP+/KR to SFI #1/KR_R.RX-")
			(pintype "passive")
			(teardrops
				(best_length_ratio 0.2)
				(max_length 1)
				(best_width_ratio 0.9)
				(max_width 2)
				(curved_edges yes)
				(filter_ratio 0.9)
				(enabled yes)
				(allow_two_segments yes)
				(prefer_zone_connections yes)
			)
		)
	)
	(footprint "antmicro-footprints:R_0402_1005Metric"
		(layer "F.Cu")
		(at 113.7 78.71)
		(descr "Resistor SMD 0402")
		(tags "resistor SMD 0402")
		(property "Reference" "R71"
			(at -1 1.35 0)
			(layer "F.SilkS")
			(effects
				(font
					(size 0.7 0.7)
					(thickness 0.15)
				)
				(justify left bottom)
			)
		)
		(property "Value" "R_0R_0402"
			(at -1.011843 1.772047 0)
			(layer "F.Fab")
			(effects
				(font
					(size 0.7 0.7)
					(thickness 0.15)
				)
				(justify left bottom)
			)
		)
		(property "Datasheet" "https://industrial.panasonic.com/cdbs/www-data/pdf/RDA0000/AOA0000C301.pdf"
			(at 0 0 0)
			(layer "F.Fab")
			(hide yes)
			(effects
				(font
					(size 1.27 1.27)
					(thickness 0.15)
				)
			)
		)
		(property "Author" "Antmicro"
			(at 0 0 0)
			(layer "F.Fab")
			(hide yes)
			(effects
				(font
					(size 1 1)
					(thickness 0.15)
				)
			)
		)
		(property "Current" "1A"
			(at 0 0 0)
			(layer "F.Fab")
			(hide yes)
			(effects
				(font
					(size 1 1)
					(thickness 0.15)
				)
			)
		)
		(property "License" "Apache-2.0"
			(at 0 0 0)
			(layer "F.Fab")
			(hide yes)
			(effects
				(font
					(size 1 1)
					(thickness 0.15)
				)
			)
		)
		(property "MPN" "ERJ2GE0R00X"
			(at 0 0 0)
			(layer "F.Fab")
			(hide yes)
			(effects
				(font
					(size 1 1)
					(thickness 0.15)
				)
			)
		)
		(property "Manufacturer" "Panasonic"
			(at 0 0 0)
			(layer "F.Fab")
			(hide yes)
			(effects
				(font
					(size 1 1)
					(thickness 0.15)
				)
			)
		)
		(property "Public" "False"
			(at 0 0 0)
			(layer "F.Fab")
			(hide yes)
			(effects
				(font
					(size 1 1)
					(thickness 0.15)
				)
			)
		)
		(property "Tolerance" ""
			(at 0 0 0)
			(layer "F.Fab")
			(hide yes)
			(effects
				(font
					(size 1 1)
					(thickness 0.15)
				)
			)
		)
		(property "Val" "0R"
			(at 0 0 0)
			(layer "F.Fab")
			(hide yes)
			(effects
				(font
					(size 1 1)
					(thickness 0.15)
				)
			)
		)
		(sheetname "USB-C console")
		(sheetfile "usb-c_console.kicad_sch")
		(attr smd)
		(fp_rect
			(start -0.925 -0.47)
			(end 0.925 0.47)
			(stroke
				(width 0.05)
				(type default)
			)
			(fill no)
			(layer "F.CrtYd")
		)
		(fp_rect
			(start -0.5 -0.25)
			(end 0.5 0.25)
			(stroke
				(width 0.15)
				(type solid)
			)
			(fill no)
			(layer "F.Fab")
		)
		(pad "1" smd roundrect
			(at -0.48 0)
			(size 0.59 0.64)
			(layers "F.Cu" "F.Mask" "F.Paste")
			(roundrect_rratio 0.25)
			(net 57 "/USB-C console/FTDI_VCCIO")
			(pintype "passive")
			(teardrops
				(best_length_ratio 0.2)
				(max_length 1)
				(best_width_ratio 0.9)
				(max_width 2)
				(curved_edges yes)
				(filter_ratio 0.9)
				(enabled yes)
				(allow_two_segments yes)
				(prefer_zone_connections yes)
			)
		)
		(pad "2" smd roundrect
			(at 0.48 0)
			(size 0.59 0.64)
			(layers "F.Cu" "F.Mask" "F.Paste")
			(roundrect_rratio 0.25)
			(net 570 "Net-(U6-~{RESET})")
			(pintype "passive")
			(teardrops
				(best_length_ratio 0.2)
				(max_length 1)
				(best_width_ratio 0.9)
				(max_width 2)
				(curved_edges yes)
				(filter_ratio 0.9)
				(enabled yes)
				(allow_two_segments yes)
				(prefer_zone_connections yes)
			)
		)
	)
	(footprint "antmicro-footprints:R_0402_1005Metric"
		(layer "F.Cu")
		(at 126.425 87.060001 180)
		(descr "Resistor SMD 0402")
		(tags "resistor SMD 0402")
		(property "Reference" "R242"
			(at -1.575 -6.4 0)
			(layer "F.SilkS")
			(effects
				(font
					(size 0.7 0.7)
					(thickness 0.15)
				)
				(justify right bottom)
			)
		)
		(property "Value" "R_0R_0402"
			(at -1.011843 1.772047 0)
			(layer "F.Fab")
			(effects
				(font
					(size 0.7 0.7)
					(thickness 0.15)
				)
				(justify right bottom)
			)
		)
		(property "Datasheet" "https://industrial.panasonic.com/cdbs/www-data/pdf/RDA0000/AOA0000C301.pdf"
			(at 0 0 180)
			(layer "F.Fab")
			(hide yes)
			(effects
				(font
					(size 1.27 1.27)
					(thickness 0.15)
				)
			)
		)
		(property "Author" "Antmicro"
			(at 252.85 174.120002 0)
			(layer "F.Fab")
			(hide yes)
			(effects
				(font
					(size 1 1)
					(thickness 0.15)
				)
			)
		)
		(property "Current" "1A"
			(at 252.85 174.120002 0)
			(layer "F.Fab")
			(hide yes)
			(effects
				(font
					(size 1 1)
					(thickness 0.15)
				)
			)
		)
		(property "License" "Apache-2.0"
			(at 252.85 174.120002 0)
			(layer "F.Fab")
			(hide yes)
			(effects
				(font
					(size 1 1)
					(thickness 0.15)
				)
			)
		)
		(property "MPN" "ERJ2GE0R00X"
			(at 252.85 174.120002 0)
			(layer "F.Fab")
			(hide yes)
			(effects
				(font
					(size 1 1)
					(thickness 0.15)
				)
			)
		)
		(property "Manufacturer" "Panasonic"
			(at 252.85 174.120002 0)
			(layer "F.Fab")
			(hide yes)
			(effects
				(font
					(size 1 1)
					(thickness 0.15)
				)
			)
		)
		(property "Public" "False"
			(at 252.85 174.120002 0)
			(layer "F.Fab")
			(hide yes)
			(effects
				(font
					(size 1 1)
					(thickness 0.15)
				)
			)
		)
		(property "Tolerance" ""
			(at 252.85 174.120002 0)
			(layer "F.Fab")
			(hide yes)
			(effects
				(font
					(size 1 1)
					(thickness 0.15)
				)
			)
		)
		(property "Val" "0R"
			(at 252.85 174.120002 0)
			(layer "F.Fab")
			(hide yes)
			(effects
				(font
					(size 1 1)
					(thickness 0.15)
				)
			)
		)
		(sheetname "GPIO expander")
		(sheetfile "gpio_exp.kicad_sch")
		(attr smd)
		(fp_rect
			(start -0.925 -0.47)
			(end 0.925 0.47)
			(stroke
				(width 0.05)
				(type default)
			)
			(fill no)
			(layer "F.CrtYd")
		)
		(fp_rect
			(start -0.5 -0.25)
			(end 0.5 0.25)
			(stroke
				(width 0.15)
				(type solid)
			)
			(fill no)
			(layer "F.Fab")
		)
		(pad "1" smd roundrect
			(at -0.48 0 180)
			(size 0.59 0.64)
			(layers "F.Cu" "F.Mask" "F.Paste")
			(roundrect_rratio 0.25)
			(net 643 "Net-(U41-IO0_4)")
			(pintype "passive")
			(teardrops
				(best_length_ratio 0.2)
				(max_length 1)
				(best_width_ratio 0.9)
				(max_width 2)
				(curved_edges yes)
				(filter_ratio 0.9)
				(enabled yes)
				(allow_two_segments yes)
				(prefer_zone_connections yes)
			)
		)
		(pad "2" smd roundrect
			(at 0.48 0 180)
			(size 0.59 0.64)
			(layers "F.Cu" "F.Mask" "F.Paste")
			(roundrect_rratio 0.25)
			(net 942 "/2xUSB3.0+RJ45/EN_2")
			(pintype "passive")
			(teardrops
				(best_length_ratio 0.2)
				(max_length 1)
				(best_width_ratio 0.9)
				(max_width 2)
				(curved_edges yes)
				(filter_ratio 0.9)
				(enabled yes)
				(allow_two_segments yes)
				(prefer_zone_connections yes)
			)
		)
	)
	(footprint "antmicro-footprints:TP_SMD_0.75mm"
		(layer "F.Cu")
		(at 155.05 129.56)
		(property "Reference" "TP67"
			(at 0.45 -1.25 90)
			(layer "F.SilkS")
			(effects
				(font
					(size 0.7 0.7)
					(thickness 0.15)
				)
				(justify left bottom)
			)
		)
		(property "Value" "TP_0.75mm_SMD"
			(at 0 1.2 0)
			(layer "F.Fab")
			(effects
				(font
					(size 0.7 0.7)
					(thickness 0.15)
				)
				(justify left bottom)
			)
		)
		(property "Author" "Antmicro"
			(at 0 0 0)
			(layer "F.Fab")
			(hide yes)
			(effects
				(font
					(size 1 1)
					(thickness 0.15)
				)
			)
		)
		(property "License" "Apache-2.0"
			(at 0 0 0)
			(layer "F.Fab")
			(hide yes)
			(effects
				(font
					(size 1 1)
					(thickness 0.15)
				)
			)
		)
		(property "MPN" ""
			(at 0 0 0)
			(layer "F.Fab")
			(hide yes)
			(effects
				(font
					(size 1 1)
					(thickness 0.15)
				)
			)
		)
		(property "Manufacturer" ""
			(at 0 0 0)
			(layer "F.Fab")
			(hide yes)
			(effects
				(font
					(size 1 1)
					(thickness 0.15)
				)
			)
		)
		(property "Public" "False"
			(at 0 0 0)
			(layer "F.Fab")
			(hide yes)
			(effects
				(font
					(size 1 1)
					(thickness 0.15)
				)
			)
		)
		(sheetname "KR to SFI #1")
		(sheetfile "kr_sfi.kicad_sch")
		(attr exclude_from_pos_files exclude_from_bom)
		(fp_circle
			(center 0 0)
			(end 0.475 0)
			(stroke
				(width 0.05)
				(type default)
			)
			(fill no)
			(layer "F.CrtYd")
		)
		(pad "1" smd circle
			(at 0 0)
			(size 0.75 0.75)
			(layers "F.Cu" "F.Mask")
			(net 730 "Net-(U43C-CLKOUTA+)")
			(pinfunction "1")
			(pintype "passive")
			(teardrops
				(best_length_ratio 0.4)
				(max_length 1)
				(best_width_ratio 0.9)
				(max_width 2)
				(curved_edges yes)
				(filter_ratio 0.9)
				(enabled yes)
				(allow_two_segments yes)
				(prefer_zone_connections yes)
			)
		)
	)
	(footprint "antmicro-footprints:TP_SMD_0.75mm"
		(layer "F.Cu")
		(at 131.04 128.71)
		(property "Reference" "TP84"
			(at 0.51 -3.3 90)
			(layer "F.SilkS")
			(effects
				(font
					(size 0.7 0.7)
					(thickness 0.15)
				)
				(justify left bottom)
			)
		)
		(property "Value" "TP_0.75mm_SMD"
			(at 0 1.2 0)
			(layer "F.Fab")
			(effects
				(font
					(size 0.7 0.7)
					(thickness 0.15)
				)
				(justify left bottom)
			)
		)
		(property "Author" "Antmicro"
			(at 0 0 0)
			(layer "F.Fab")
			(hide yes)
			(effects
				(font
					(size 1 1)
					(thickness 0.15)
				)
			)
		)
		(property "License" "Apache-2.0"
			(at 0 0 0)
			(layer "F.Fab")
			(hide yes)
			(effects
				(font
					(size 1 1)
					(thickness 0.15)
				)
			)
		)
		(property "MPN" ""
			(at 0 0 0)
			(layer "F.Fab")
			(hide yes)
			(effects
				(font
					(size 1 1)
					(thickness 0.15)
				)
			)
		)
		(property "Manufacturer" ""
			(at 0 0 0)
			(layer "F.Fab")
			(hide yes)
			(effects
				(font
					(size 1 1)
					(thickness 0.15)
				)
			)
		)
		(property "Public" "False"
			(at 0 0 0)
			(layer "F.Fab")
			(hide yes)
			(effects
				(font
					(size 1 1)
					(thickness 0.15)
				)
			)
		)
		(sheetname "KR to SFI #2")
		(sheetfile "kr_sfi.kicad_sch")
		(attr exclude_from_pos_files exclude_from_bom)
		(fp_circle
			(center 0 0)
			(end 0.475 0)
			(stroke
				(width 0.05)
				(type default)
			)
			(fill no)
			(layer "F.CrtYd")
		)
		(pad "1" smd circle
			(at 0 0)
			(size 0.75 0.75)
			(layers "F.Cu" "F.Mask")
			(net 747 "Net-(U45C-PRBS_{PASS})")
			(pinfunction "1")
			(pintype "passive")
			(teardrops
				(best_length_ratio 0.4)
				(max_length 1)
				(best_width_ratio 0.9)
				(max_width 2)
				(curved_edges yes)
				(filter_ratio 0.9)
				(enabled yes)
				(allow_two_segments yes)
				(prefer_zone_connections yes)
			)
		)
	)
	(footprint "antmicro-footprints:TP_SMD_0.75mm"
		(layer "F.Cu")
		(at 152.45 129.56)
		(property "Reference" "TP62"
			(at 0.45 -1.25 90)
			(layer "F.SilkS")
			(effects
				(font
					(size 0.7 0.7)
					(thickness 0.15)
				)
				(justify left bottom)
			)
		)
		(property "Value" "TP_0.75mm_SMD"
			(at 0 1.2 0)
			(layer "F.Fab")
			(effects
				(font
					(size 0.7 0.7)
					(thickness 0.15)
				)
				(justify left bottom)
			)
		)
		(property "Author" "Antmicro"
			(at 0 0 0)
			(layer "F.Fab")
			(hide yes)
			(effects
				(font
					(size 1 1)
					(thickness 0.15)
				)
			)
		)
		(property "License" "Apache-2.0"
			(at 0 0 0)
			(layer "F.Fab")
			(hide yes)
			(effects
				(font
					(size 1 1)
					(thickness 0.15)
				)
			)
		)
		(property "MPN" ""
			(at 0 0 0)
			(layer "F.Fab")
			(hide yes)
			(effects
				(font
					(size 1 1)
					(thickness 0.15)
				)
			)
		)
		(property "Manufacturer" ""
			(at 0 0 0)
			(layer "F.Fab")
			(hide yes)
			(effects
				(font
					(size 1 1)
					(thickness 0.15)
				)
			)
		)
		(property "Public" "False"
			(at 0 0 0)
			(layer "F.Fab")
			(hide yes)
			(effects
				(font
					(size 1 1)
					(thickness 0.15)
				)
			)
		)
		(sheetname "KR to SFI #1")
		(sheetfile "kr_sfi.kicad_sch")
		(attr exclude_from_pos_files exclude_from_bom)
		(fp_circle
			(center 0 0)
			(end 0.475 0)
			(stroke
				(width 0.05)
				(type default)
			)
			(fill no)
			(layer "F.CrtYd")
		)
		(pad "1" smd circle
			(at 0 0)
			(size 0.75 0.75)
			(layers "F.Cu" "F.Mask")
			(net 725 "/2xSFP+/KR to SFI #1/TCK")
			(pinfunction "1")
			(pintype "passive")
			(teardrops
				(best_length_ratio 0.4)
				(max_length 1)
				(best_width_ratio 0.9)
				(max_width 2)
				(curved_edges yes)
				(filter_ratio 0.9)
				(enabled yes)
				(allow_two_segments yes)
				(prefer_zone_connections yes)
			)
		)
	)
	(footprint "antmicro-footprints:LED_0603_1608Metric_G"
		(layer "F.Cu")
		(at 138.62 168.44 180)
		(descr "LED SMD 0603 Green")
		(tags "LED SMD 0603 Green")
		(property "Reference" "D8"
			(at 1.12 -0.42 0)
			(layer "F.SilkS")
			(effects
				(font
					(size 0.7 0.7)
					(thickness 0.15)
				)
				(justify right bottom)
			)
		)
		(property "Value" "LED_G_0603_LTST-C190GKT"
			(at -0.001 1.599 0)
			(layer "F.Fab")
			(effects
				(font
					(size 0.7 0.7)
					(thickness 0.15)
				)
				(justify right bottom)
			)
		)
		(property "Datasheet" "https://media.digikey.com/pdf/Data%20Sheets/Lite-On%20PDFs/LTST-C190GKT.pdf"
			(at 0 0 180)
			(layer "F.Fab")
			(hide yes)
			(effects
				(font
					(size 1.27 1.27)
					(thickness 0.15)
				)
			)
		)
		(property "Author" "Antmicro"
			(at 277.24 336.88 0)
			(layer "F.Fab")
			(hide yes)
			(effects
				(font
					(size 1 1)
					(thickness 0.15)
				)
			)
		)
		(property "Color" "Green"
			(at 277.24 336.88 0)
			(layer "F.Fab")
			(hide yes)
			(effects
				(font
					(size 1 1)
					(thickness 0.15)
				)
			)
		)
		(property "License" "Apache-2.0"
			(at 277.24 336.88 0)
			(layer "F.Fab")
			(hide yes)
			(effects
				(font
					(size 1 1)
					(thickness 0.15)
				)
			)
		)
		(property "MPN" "LTST-C190GKT"
			(at 277.24 336.88 0)
			(layer "F.Fab")
			(hide yes)
			(effects
				(font
					(size 1 1)
					(thickness 0.15)
				)
			)
		)
		(property "Manufacturer" "Lite-On"
			(at 277.24 336.88 0)
			(layer "F.Fab")
			(hide yes)
			(effects
				(font
					(size 1 1)
					(thickness 0.15)
				)
			)
		)
		(property "Public" "False"
			(at 277.24 336.88 0)
			(layer "F.Fab")
			(hide yes)
			(effects
				(font
					(size 1 1)
					(thickness 0.15)
				)
			)
		)
		(sheetname "2xSFP+")
		(sheetfile "2xSFP+.kicad_sch")
		(attr smd)
		(fp_line
			(start 0.22 0.35)
			(end -0.22 0.35)
			(stroke
				(width 0.15)
				(type solid)
			)
			(layer "F.SilkS")
		)
		(fp_line
			(start 0.22 -0.35)
			(end -0.22 -0.35)
			(stroke
				(width 0.15)
				(type solid)
			)
			(layer "F.SilkS")
		)
		(fp_line
			(start 0.105328 0.201008)
			(end 0.105328 -0.198992)
			(stroke
				(width 0.1)
				(type solid)
			)
			(layer "F.SilkS")
		)
		(fp_line
			(start 0.105328 0.201008)
			(end -0.094672 0.001008)
			(stroke
				(width 0.1)
				(type solid)
			)
			(layer "F.SilkS")
		)
		(fp_line
			(start 0.105328 0.001008)
			(end 0.24 0.001)
			(stroke
				(width 0.1)
				(type solid)
			)
			(layer "F.SilkS")
		)
		(fp_line
			(start -0.094672 0.201008)
			(end -0.094672 -0.198992)
			(stroke
				(width 0.1)
				(type solid)
			)
			(layer "F.SilkS")
		)
		(fp_line
			(start -0.094672 0.001008)
			(end 0.105328 -0.198992)
			(stroke
				(width 0.1)
				(type solid)
			)
			(layer "F.SilkS")
		)
		(fp_line
			(start -0.094672 0.001008)
			(end -0.24 0.001008)
			(stroke
				(width 0.1)
				(type solid)
			)
			(layer "F.SilkS")
		)
		(fp_line
			(start -1.18 -0.319)
			(end -1.18 0.321)
			(stroke
				(width 0.15)
				(type solid)
			)
			(layer "F.SilkS")
		)
		(fp_rect
			(start 1.25 0.65)
			(end -1.25 -0.65)
			(stroke
				(width 0.05)
				(type solid)
			)
			(fill no)
			(layer "F.CrtYd")
		)
		(fp_line
			(start 0.599 0)
			(end 0.201 0)
			(stroke
				(width 0.15)
				(type solid)
			)
			(layer "F.Fab")
		)
		(fp_line
			(start 0.201 0.2)
			(end 0.201 0)
			(stroke
				(width 0.15)
				(type solid)
			)
			(layer "F.Fab")
		)
		(fp_line
			(start 0.201 0)
			(end 0.201 -0.202)
			(stroke
				(width 0.15)
				(type solid)
			)
			(layer "F.Fab")
		)
		(fp_line
			(start 0.201 -0.202)
			(end -0.101 0)
			(stroke
				(width 0.15)
				(type solid)
			)
			(layer "F.Fab")
		)
		(fp_line
			(start -0.101 0)
			(end 0.201 0.2)
			(stroke
				(width 0.15)
				(type solid)
			)
			(layer "F.Fab")
		)
		(fp_line
			(start -0.199 0.2)
			(end -0.199 0.1)
			(stroke
				(width 0.15)
				(type solid)
			)
			(layer "F.Fab")
		)
		(fp_line
			(start -0.199 0)
			(end -0.597 0)
			(stroke
				(width 0.15)
				(type solid)
			)
			(layer "F.Fab")
		)
		(fp_line
			(start -0.199 -0.202)
			(end -0.199 0.1)
			(stroke
				(width 0.15)
				(type solid)
			)
			(layer "F.Fab")
		)
		(fp_rect
			(start 0.848 0.4)
			(end -0.85 -0.402)
			(stroke
				(width 0.15)
				(type solid)
			)
			(fill no)
			(layer "F.Fab")
		)
		(pad "1" smd roundrect
			(at -0.7 0)
			(size 0.8 1)
			(layers "F.Cu" "F.Mask" "F.Paste")
			(roundrect_rratio 0.2)
			(net 940 "Net-(D8-C)")
			(pinfunction "C")
			(pintype "passive")
			(teardrops
				(best_length_ratio 0.2)
				(max_length 1)
				(best_width_ratio 0.9)
				(max_width 2)
				(curved_edges yes)
				(filter_ratio 0.9)
				(enabled yes)
				(allow_two_segments yes)
				(prefer_zone_connections yes)
			)
		)
		(pad "2" smd roundrect
			(at 0.7 0)
			(size 0.8 1)
			(layers "F.Cu" "F.Mask" "F.Paste")
			(roundrect_rratio 0.2)
			(net 2 "+3V3")
			(pinfunction "A")
			(pintype "passive")
			(teardrops
				(best_length_ratio 0.2)
				(max_length 1)
				(best_width_ratio 0.9)
				(max_width 2)
				(curved_edges yes)
				(filter_ratio 0.9)
				(enabled yes)
				(allow_two_segments yes)
				(prefer_zone_connections yes)
			)
		)
	)
	(footprint "antmicro-footprints:R_0402_1005Metric"
		(layer "F.Cu")
		(at 248.35 128.31 -90)
		(descr "Resistor SMD 0402")
		(tags "resistor SMD 0402")
		(property "Reference" "R173"
			(at -3.65 -0.4 90)
			(layer "F.SilkS")
			(effects
				(font
					(size 0.7 0.7)
					(thickness 0.15)
				)
				(justify right bottom)
			)
		)
		(property "Value" "R_100k_0402"
			(at -1.011843 1.772047 90)
			(layer "F.Fab")
			(effects
				(font
					(size 0.7 0.7)
					(thickness 0.15)
				)
				(justify right bottom)
			)
		)
		(property "Datasheet" "https://www.bourns.com/docs/product-datasheets/cr.pdf"
			(at 0 0 270)
			(layer "F.Fab")
			(hide yes)
			(effects
				(font
					(size 1.27 1.27)
					(thickness 0.15)
				)
			)
		)
		(property "Author" "Antmicro"
			(at 120.04 376.66 0)
			(layer "F.Fab")
			(hide yes)
			(effects
				(font
					(size 1 1)
					(thickness 0.15)
				)
			)
		)
		(property "License" "Apache-2.0"
			(at 120.04 376.66 0)
			(layer "F.Fab")
			(hide yes)
			(effects
				(font
					(size 1 1)
					(thickness 0.15)
				)
			)
		)
		(property "MPN" "CR0402-FX-1003GLF"
			(at 120.04 376.66 0)
			(layer "F.Fab")
			(hide yes)
			(effects
				(font
					(size 1 1)
					(thickness 0.15)
				)
			)
		)
		(property "Manufacturer" "Bourns"
			(at 120.04 376.66 0)
			(layer "F.Fab")
			(hide yes)
			(effects
				(font
					(size 1 1)
					(thickness 0.15)
				)
			)
		)
		(property "Public" "False"
			(at 120.04 376.66 0)
			(layer "F.Fab")
			(hide yes)
			(effects
				(font
					(size 1 1)
					(thickness 0.15)
				)
			)
		)
		(property "Tolerance" "1%"
			(at 120.04 376.66 0)
			(layer "F.Fab")
			(hide yes)
			(effects
				(font
					(size 1 1)
					(thickness 0.15)
				)
			)
		)
		(property "Val" "100k"
			(at 120.04 376.66 0)
			(layer "F.Fab")
			(hide yes)
			(effects
				(font
					(size 1 1)
					(thickness 0.15)
				)
			)
		)
		(sheetname "Com Express 7 MGMT")
		(sheetfile "com_express_7_mgmt.kicad_sch")
		(attr smd dnp)
		(fp_rect
			(start -0.925 -0.47)
			(end 0.925 0.47)
			(stroke
				(width 0.05)
				(type default)
			)
			(fill no)
			(layer "F.CrtYd")
		)
		(fp_rect
			(start -0.5 -0.25)
			(end 0.5 0.25)
			(stroke
				(width 0.15)
				(type solid)
			)
			(fill no)
			(layer "F.Fab")
		)
		(pad "1" smd roundrect
			(at -0.48 0 270)
			(size 0.59 0.64)
			(layers "F.Cu" "F.Mask" "F.Paste")
			(roundrect_rratio 0.25)
			(net 999 "Net-(C101-Pad1)")
			(pintype "passive")
			(teardrops
				(best_length_ratio 0.2)
				(max_length 1)
				(best_width_ratio 0.9)
				(max_width 2)
				(curved_edges yes)
				(filter_ratio 0.9)
				(enabled yes)
				(allow_two_segments yes)
				(prefer_zone_connections yes)
			)
		)
		(pad "2" smd roundrect
			(at 0.48 0 270)
			(size 0.59 0.64)
			(layers "F.Cu" "F.Mask" "F.Paste")
			(roundrect_rratio 0.25)
			(net 84 "/Com Express 7 MGMT/PWRBTN")
			(pintype "passive")
			(teardrops
				(best_length_ratio 0.2)
				(max_length 1)
				(best_width_ratio 0.9)
				(max_width 2)
				(curved_edges yes)
				(filter_ratio 0.9)
				(enabled yes)
				(allow_two_segments yes)
				(prefer_zone_connections yes)
			)
		)
	)
	(footprint "antmicro-footprints:R_0402_1005Metric"
		(layer "F.Cu")
		(at 143.45 83.06 180)
		(descr "Resistor SMD 0402")
		(tags "resistor SMD 0402")
		(property "Reference" "R137"
			(at 0.85 -0.5 0)
			(layer "F.SilkS")
			(effects
				(font
					(size 0.7 0.7)
					(thickness 0.15)
				)
				(justify right bottom)
			)
		)
		(property "Value" "R_0R_0402"
			(at -1.011843 1.772047 0)
			(layer "F.Fab")
			(effects
				(font
					(size 0.7 0.7)
					(thickness 0.15)
				)
				(justify right bottom)
			)
		)
		(property "Datasheet" "https://industrial.panasonic.com/cdbs/www-data/pdf/RDA0000/AOA0000C301.pdf"
			(at 0 0 180)
			(layer "F.Fab")
			(hide yes)
			(effects
				(font
					(size 1.27 1.27)
					(thickness 0.15)
				)
			)
		)
		(property "Author" "Antmicro"
			(at 286.9 166.12 0)
			(layer "F.Fab")
			(hide yes)
			(effects
				(font
					(size 1 1)
					(thickness 0.15)
				)
			)
		)
		(property "Current" "1A"
			(at 286.9 166.12 0)
			(layer "F.Fab")
			(hide yes)
			(effects
				(font
					(size 1 1)
					(thickness 0.15)
				)
			)
		)
		(property "License" "Apache-2.0"
			(at 286.9 166.12 0)
			(layer "F.Fab")
			(hide yes)
			(effects
				(font
					(size 1 1)
					(thickness 0.15)
				)
			)
		)
		(property "MPN" "ERJ2GE0R00X"
			(at 286.9 166.12 0)
			(layer "F.Fab")
			(hide yes)
			(effects
				(font
					(size 1 1)
					(thickness 0.15)
				)
			)
		)
		(property "Manufacturer" "Panasonic"
			(at 286.9 166.12 0)
			(layer "F.Fab")
			(hide yes)
			(effects
				(font
					(size 1 1)
					(thickness 0.15)
				)
			)
		)
		(property "Public" "False"
			(at 286.9 166.12 0)
			(layer "F.Fab")
			(hide yes)
			(effects
				(font
					(size 1 1)
					(thickness 0.15)
				)
			)
		)
		(property "Tolerance" ""
			(at 286.9 166.12 0)
			(layer "F.Fab")
			(hide yes)
			(effects
				(font
					(size 1 1)
					(thickness 0.15)
				)
			)
		)
		(property "Val" "0R"
			(at 286.9 166.12 0)
			(layer "F.Fab")
			(hide yes)
			(effects
				(font
					(size 1 1)
					(thickness 0.15)
				)
			)
		)
		(sheetname "M.2 key E")
		(sheetfile "m2keye.kicad_sch")
		(attr smd)
		(fp_rect
			(start -0.925 -0.47)
			(end 0.925 0.47)
			(stroke
				(width 0.05)
				(type default)
			)
			(fill no)
			(layer "F.CrtYd")
		)
		(fp_rect
			(start -0.5 -0.25)
			(end 0.5 0.25)
			(stroke
				(width 0.15)
				(type solid)
			)
			(fill no)
			(layer "F.Fab")
		)
		(pad "1" smd roundrect
			(at -0.48 0 180)
			(size 0.59 0.64)
			(layers "F.Cu" "F.Mask" "F.Paste")
			(roundrect_rratio 0.25)
			(net 38 "Net-(J100-SUSCLK)")
			(pintype "passive")
			(teardrops
				(best_length_ratio 0.2)
				(max_length 1)
				(best_width_ratio 0.9)
				(max_width 2)
				(curved_edges yes)
				(filter_ratio 0.9)
				(enabled yes)
				(allow_two_segments yes)
				(prefer_zone_connections yes)
			)
		)
		(pad "2" smd roundrect
			(at 0.48 0 180)
			(size 0.59 0.64)
			(layers "F.Cu" "F.Mask" "F.Paste")
			(roundrect_rratio 0.25)
			(net 587 "/M.2 key E/SUSCLK")
			(pintype "passive")
			(teardrops
				(best_length_ratio 0.2)
				(max_length 1)
				(best_width_ratio 0.9)
				(max_width 2)
				(curved_edges yes)
				(filter_ratio 0.9)
				(enabled yes)
				(allow_two_segments yes)
				(prefer_zone_connections yes)
			)
		)
	)
	(footprint "antmicro-footprints:R_0402_1005Metric"
		(layer "F.Cu")
		(at 143 133.88)
		(descr "Resistor SMD 0402")
		(tags "resistor SMD 0402")
		(property "Reference" "R271"
			(at -3.6 0.43 0)
			(layer "F.SilkS")
			(effects
				(font
					(size 0.7 0.7)
					(thickness 0.15)
				)
				(justify left bottom)
			)
		)
		(property "Value" "R_10k_0402"
			(at -1.011843 1.772047 0)
			(layer "F.Fab")
			(effects
				(font
					(size 0.7 0.7)
					(thickness 0.15)
				)
				(justify left bottom)
			)
		)
		(property "Datasheet" "https://www.bourns.com/docs/product-datasheets/cr.pdf"
			(at 0 0 0)
			(layer "F.Fab")
			(hide yes)
			(effects
				(font
					(size 1.27 1.27)
					(thickness 0.15)
				)
			)
		)
		(property "Author" "Antmicro"
			(at 0 0 0)
			(layer "F.Fab")
			(hide yes)
			(effects
				(font
					(size 1 1)
					(thickness 0.15)
				)
			)
		)
		(property "License" "Apache-2.0"
			(at 0 0 0)
			(layer "F.Fab")
			(hide yes)
			(effects
				(font
					(size 1 1)
					(thickness 0.15)
				)
			)
		)
		(property "MPN" "CR0402-FX-1002GLF"
			(at 0 0 0)
			(layer "F.Fab")
			(hide yes)
			(effects
				(font
					(size 1 1)
					(thickness 0.15)
				)
			)
		)
		(property "Manufacturer" "Bourns"
			(at 0 0 0)
			(layer "F.Fab")
			(hide yes)
			(effects
				(font
					(size 1 1)
					(thickness 0.15)
				)
			)
		)
		(property "Public" "False"
			(at 0 0 0)
			(layer "F.Fab")
			(hide yes)
			(effects
				(font
					(size 1 1)
					(thickness 0.15)
				)
			)
		)
		(property "Tolerance" "1%"
			(at 0 0 0)
			(layer "F.Fab")
			(hide yes)
			(effects
				(font
					(size 1 1)
					(thickness 0.15)
				)
			)
		)
		(property "Val" "10k"
			(at 0 0 0)
			(layer "F.Fab")
			(hide yes)
			(effects
				(font
					(size 1 1)
					(thickness 0.15)
				)
			)
		)
		(sheetname "KR to SFI #1")
		(sheetfile "kr_sfi.kicad_sch")
		(attr smd)
		(fp_rect
			(start -0.925 -0.47)
			(end 0.925 0.47)
			(stroke
				(width 0.05)
				(type default)
			)
			(fill no)
			(layer "F.CrtYd")
		)
		(fp_rect
			(start -0.5 -0.25)
			(end 0.5 0.25)
			(stroke
				(width 0.15)
				(type solid)
			)
			(fill no)
			(layer "F.Fab")
		)
		(pad "1" smd roundrect
			(at -0.48 0)
			(size 0.59 0.64)
			(layers "F.Cu" "F.Mask" "F.Paste")
			(roundrect_rratio 0.25)
			(net 1 "GND")
			(pintype "passive")
			(teardrops
				(best_length_ratio 0.2)
				(max_length 1)
				(best_width_ratio 0.9)
				(max_width 2)
				(curved_edges yes)
				(filter_ratio 0.9)
				(enabled yes)
				(allow_two_segments yes)
				(prefer_zone_connections yes)
			)
		)
		(pad "2" smd roundrect
			(at 0.48 0)
			(size 0.59 0.64)
			(layers "F.Cu" "F.Mask" "F.Paste")
			(roundrect_rratio 0.25)
			(net 663 "Net-(U43C-ST)")
			(pintype "passive")
			(teardrops
				(best_length_ratio 0.2)
				(max_length 1)
				(best_width_ratio 0.9)
				(max_width 2)
				(curved_edges yes)
				(filter_ratio 0.9)
				(enabled yes)
				(allow_two_segments yes)
				(prefer_zone_connections yes)
			)
		)
	)
	(footprint "antmicro-footprints:Bus_M.2_Socket_Key_E_TE_2199230-6"
		(layer "F.Cu")
		(at 149.8245 80.3095 -90)
		(property "Reference" "J100"
			(at 12.2505 2.0245 180)
			(layer "F.SilkS")
			(effects
				(font
					(size 0.7 0.7)
					(thickness 0.15)
				)
				(justify right bottom)
			)
		)
		(property "Value" "Bus_M.2_2199230-2"
			(at -10.999 5.75 90)
			(layer "F.Fab")
			(effects
				(font
					(size 0.7 0.7)
					(thickness 0.15)
				)
				(justify right bottom)
			)
		)
		(property "Datasheet" "https://eu.mouser.com/datasheet/2/418/9/ENG_DS_1_1773702_1NGFFQRG_EN_0214_1_1773702_1NGFF_-3328593.pdf"
			(at 0 0 270)
			(layer "F.Fab")
			(hide yes)
			(effects
				(font
					(size 1.27 1.27)
					(thickness 0.15)
				)
			)
		)
		(property "Author" "Antmicro"
			(at 69.515 230.134 0)
			(layer "F.Fab")
			(hide yes)
			(effects
				(font
					(size 1 1)
					(thickness 0.15)
				)
			)
		)
		(property "License" "Apache-2.0"
			(at 69.515 230.134 0)
			(layer "F.Fab")
			(hide yes)
			(effects
				(font
					(size 1 1)
					(thickness 0.15)
				)
			)
		)
		(property "MPN" "2199230-2"
			(at 69.515 230.134 0)
			(layer "F.Fab")
			(hide yes)
			(effects
				(font
					(size 1 1)
					(thickness 0.15)
				)
			)
		)
		(property "Manufacturer" "TE Connectivity"
			(at 69.515 230.134 0)
			(layer "F.Fab")
			(hide yes)
			(effects
				(font
					(size 1 1)
					(thickness 0.15)
				)
			)
		)
		(sheetname "M.2 key E")
		(sheetfile "m2keye.kicad_sch")
		(attr smd)
		(fp_line
			(start -9.599 4.1)
			(end -9.249 4.1)
			(stroke
				(width 0.15)
				(type solid)
			)
			(layer "F.SilkS")
		)
		(fp_line
			(start -3.75 4.1)
			(end -1.75 4.1)
			(stroke
				(width 0.15)
				(type solid)
			)
			(layer "F.SilkS")
		)
		(fp_line
			(start 9.251 4.1)
			(end 9.601 4.1)
			(stroke
				(width 0.15)
				(type solid)
			)
			(layer "F.SilkS")
		)
		(fp_line
			(start 9.601 4.1)
			(end 9.601 2.85)
			(stroke
				(width 0.15)
				(type solid)
			)
			(layer "F.SilkS")
		)
		(fp_line
			(start -10.999 2.85)
			(end -10.999 -1.5)
			(stroke
				(width 0.15)
				(type solid)
			)
			(layer "F.SilkS")
		)
		(fp_line
			(start -9.599 2.85)
			(end -9.599 4.1)
			(stroke
				(width 0.15)
				(type solid)
			)
			(layer "F.SilkS")
		)
		(fp_line
			(start -9.599 2.85)
			(end -10.999 2.85)
			(stroke
				(width 0.15)
				(type solid)
			)
			(layer "F.SilkS")
		)
		(fp_line
			(start 10.999 2.85)
			(end 9.601 2.85)
			(stroke
				(width 0.15)
				(type solid)
			)
			(layer "F.SilkS")
		)
		(fp_line
			(start 10.999 -1.5)
			(end 10.999 2.85)
			(stroke
				(width 0.15)
				(type solid)
			)
			(layer "F.SilkS")
		)
		(fp_line
			(start -3.499 -3.899)
			(end -1.499 -3.899)
			(stroke
				(width 0.15)
				(type solid)
			)
			(layer "F.SilkS")
		)
		(fp_circle
			(center -9.249 -5.64)
			(end -9.199 -5.64)
			(stroke
				(width 0.15)
				(type solid)
			)
			(fill yes)
			(layer "F.SilkS")
		)
		(fp_rect
			(start -11.94 -5.34)
			(end 11.95 5.35)
			(stroke
				(width 0.05)
				(type solid)
			)
			(fill no)
			(layer "F.CrtYd")
		)
		(fp_line
			(start -9.999 -0.25)
			(end 9.999 -0.25)
			(stroke
				(width 0.15)
				(type solid)
			)
			(layer "F.Fab")
		)
		(pad "" np_thru_hole circle
			(at -9.999 1.499 270)
			(size 1.1 1.1)
			(drill 1.1)
			(layers "*.Cu" "*.Mask")
		)
		(pad "" np_thru_hole circle
			(at 9.999 1.499 270)
			(size 1.6 1.6)
			(drill 1.6)
			(layers "*.Cu" "*.Mask")
		)
		(pad "1" smd rect
			(at -9.249 -3.749 270)
			(size 0.3 1.55)
			(layers "F.Cu" "F.Mask" "F.Paste")
			(net 1 "GND")
			(pinfunction "GND")
			(pintype "power_in")
			(teardrops
				(best_length_ratio 0.2)
				(max_length 1)
				(best_width_ratio 0.9)
				(max_width 2)
				(curved_edges yes)
				(filter_ratio 0.9)
				(enabled yes)
				(allow_two_segments yes)
				(prefer_zone_connections yes)
			)
		)
		(pad "2" smd rect
			(at -9.001 3.749 270)
			(size 0.3 1.55)
			(layers "F.Cu" "F.Mask" "F.Paste")
			(net 2 "+3V3")
			(pinfunction "3.3V")
			(pintype "power_in")
			(teardrops
				(best_length_ratio 0.2)
				(max_length 1)
				(best_width_ratio 0.9)
				(max_width 2)
				(curved_edges yes)
				(filter_ratio 0.9)
				(enabled yes)
				(allow_two_segments yes)
				(prefer_zone_connections yes)
			)
		)
		(pad "3" smd rect
			(at -8.751 -3.749 270)
			(size 0.3 1.55)
			(layers "F.Cu" "F.Mask" "F.Paste")
			(net 3 "/M.2 key E/WIFI_BT_USB_D_P")
			(pinfunction "USB_D_P")
			(pintype "bidirectional")
			(teardrops
				(best_length_ratio 0.2)
				(max_length 1)
				(best_width_ratio 0.9)
				(max_width 2)
				(curved_edges yes)
				(filter_ratio 0.9)
				(enabled yes)
				(allow_two_segments yes)
				(prefer_zone_connections yes)
			)
		)
		(pad "4" smd rect
			(at -8.501 3.749 270)
			(size 0.3 1.55)
			(layers "F.Cu" "F.Mask" "F.Paste")
			(net 2 "+3V3")
			(pinfunction "3.3V")
			(pintype "passive")
			(teardrops
				(best_length_ratio 0.2)
				(max_length 1)
				(best_width_ratio 0.9)
				(max_width 2)
				(curved_edges yes)
				(filter_ratio 0.9)
				(enabled yes)
				(allow_two_segments yes)
				(prefer_zone_connections yes)
			)
		)
		(pad "5" smd rect
			(at -8.251 -3.749 270)
			(size 0.3 1.55)
			(layers "F.Cu" "F.Mask" "F.Paste")
			(net 4 "/M.2 key E/WIFI_BT_USB_D_N")
			(pinfunction "USB_D_N")
			(pintype "bidirectional")
			(teardrops
				(best_length_ratio 0.2)
				(max_length 1)
				(best_width_ratio 0.9)
				(max_width 2)
				(curved_edges yes)
				(filter_ratio 0.9)
				(enabled yes)
				(allow_two_segments yes)
				(prefer_zone_connections yes)
			)
		)
		(pad "6" smd rect
			(at -8 3.749 270)
			(size 0.3 1.55)
			(layers "F.Cu" "F.Mask" "F.Paste")
			(net 5 "/M.2 key E/~{LED_1}")
			(pinfunction "~{LED_1}")
			(pintype "output")
			(teardrops
				(best_length_ratio 0.2)
				(max_length 1)
				(best_width_ratio 0.9)
				(max_width 2)
				(curved_edges yes)
				(filter_ratio 0.9)
				(enabled yes)
				(allow_two_segments yes)
				(prefer_zone_connections yes)
			)
		)
		(pad "7" smd rect
			(at -7.75 -3.749 270)
			(size 0.3 1.55)
			(layers "F.Cu" "F.Mask" "F.Paste")
			(net 1 "GND")
			(pinfunction "GND")
			(pintype "passive")
			(teardrops
				(best_length_ratio 0.2)
				(max_length 1)
				(best_width_ratio 0.9)
				(max_width 2)
				(curved_edges yes)
				(filter_ratio 0.9)
				(enabled yes)
				(allow_two_segments yes)
				(prefer_zone_connections yes)
			)
		)
		(pad "8" smd rect
			(at -7.5 3.749 270)
			(size 0.3 1.55)
			(layers "F.Cu" "F.Mask" "F.Paste")
			(net 7 "unconnected-(J100-PCM_CLK-Pad8)")
			(pinfunction "PCM_CLK")
			(pintype "bidirectional+no_connect")
			(teardrops
				(best_length_ratio 0.2)
				(max_length 1)
				(best_width_ratio 0.9)
				(max_width 2)
				(curved_edges yes)
				(filter_ratio 0.9)
				(enabled yes)
				(allow_two_segments yes)
				(prefer_zone_connections yes)
			)
		)
		(pad "9" smd rect
			(at -7.25 -3.749 270)
			(size 0.3 1.55)
			(layers "F.Cu" "F.Mask" "F.Paste")
			(net 8 "unconnected-(J100-SDIO_CLK-Pad9)")
			(pinfunction "SDIO_CLK")
			(pintype "input+no_connect")
			(teardrops
				(best_length_ratio 0.2)
				(max_length 1)
				(best_width_ratio 0.9)
				(max_width 2)
				(curved_edges yes)
				(filter_ratio 0.9)
				(enabled yes)
				(allow_two_segments yes)
				(prefer_zone_connections yes)
			)
		)
		(pad "10" smd rect
			(at -7 3.749 270)
			(size 0.3 1.55)
			(layers "F.Cu" "F.Mask" "F.Paste")
			(net 10 "unconnected-(J100-PCM_SYNC-Pad10)")
			(pinfunction "PCM_SYNC")
			(pintype "bidirectional+no_connect")
			(teardrops
				(best_length_ratio 0.2)
				(max_length 1)
				(best_width_ratio 0.9)
				(max_width 2)
				(curved_edges yes)
				(filter_ratio 0.9)
				(enabled yes)
				(allow_two_segments yes)
				(prefer_zone_connections yes)
			)
		)
		(pad "11" smd rect
			(at -6.75 -3.749 270)
			(size 0.3 1.55)
			(layers "F.Cu" "F.Mask" "F.Paste")
			(net 12 "unconnected-(J100-SDIO_CMD-Pad11)")
			(pinfunction "SDIO_CMD")
			(pintype "bidirectional+no_connect")
			(teardrops
				(best_length_ratio 0.2)
				(max_length 1)
				(best_width_ratio 0.9)
				(max_width 2)
				(curved_edges yes)
				(filter_ratio 0.9)
				(enabled yes)
				(allow_two_segments yes)
				(prefer_zone_connections yes)
			)
		)
		(pad "12" smd rect
			(at -6.5 3.749 270)
			(size 0.3 1.55)
			(layers "F.Cu" "F.Mask" "F.Paste")
			(net 13 "unconnected-(J100-PCM_IN-Pad12)")
			(pinfunction "PCM_IN")
			(pintype "bidirectional+no_connect")
			(teardrops
				(best_length_ratio 0.2)
				(max_length 1)
				(best_width_ratio 0.9)
				(max_width 2)
				(curved_edges yes)
				(filter_ratio 0.9)
				(enabled yes)
				(allow_two_segments yes)
				(prefer_zone_connections yes)
			)
		)
		(pad "13" smd rect
			(at -6.25 -3.749 270)
			(size 0.3 1.55)
			(layers "F.Cu" "F.Mask" "F.Paste")
			(net 15 "unconnected-(J100-SDIO_D0-Pad13)")
			(pinfunction "SDIO_D0")
			(pintype "bidirectional+no_connect")
			(teardrops
				(best_length_ratio 0.2)
				(max_length 1)
				(best_width_ratio 0.9)
				(max_width 2)
				(curved_edges yes)
				(filter_ratio 0.9)
				(enabled yes)
				(allow_two_segments yes)
				(prefer_zone_connections yes)
			)
		)
		(pad "14" smd rect
			(at -6 3.749 270)
			(size 0.3 1.55)
			(layers "F.Cu" "F.Mask" "F.Paste")
			(net 17 "unconnected-(J100-PCM_OUT-Pad14)")
			(pinfunction "PCM_OUT")
			(pintype "bidirectional+no_connect")
			(teardrops
				(best_length_ratio 0.2)
				(max_length 1)
				(best_width_ratio 0.9)
				(max_width 2)
				(curved_edges yes)
				(filter_ratio 0.9)
				(enabled yes)
				(allow_two_segments yes)
				(prefer_zone_connections yes)
			)
		)
		(pad "15" smd rect
			(at -5.75 -3.749 270)
			(size 0.3 1.55)
			(layers "F.Cu" "F.Mask" "F.Paste")
			(net 18 "unconnected-(J100-SDIO_D1-Pad15)")
			(pinfunction "SDIO_D1")
			(pintype "bidirectional+no_connect")
			(teardrops
				(best_length_ratio 0.2)
				(max_length 1)
				(best_width_ratio 0.9)
				(max_width 2)
				(curved_edges yes)
				(filter_ratio 0.9)
				(enabled yes)
				(allow_two_segments yes)
				(prefer_zone_connections yes)
			)
		)
		(pad "16" smd rect
			(at -5.5 3.749 270)
			(size 0.3 1.55)
			(layers "F.Cu" "F.Mask" "F.Paste")
			(net 6 "/M.2 key E/~{LED_2}")
			(pinfunction "~{LED_2}")
			(pintype "output")
			(teardrops
				(best_length_ratio 0.2)
				(max_length 1)
				(best_width_ratio 0.9)
				(max_width 2)
				(curved_edges yes)
				(filter_ratio 0.9)
				(enabled yes)
				(allow_two_segments yes)
				(prefer_zone_connections yes)
			)
		)
		(pad "17" smd rect
			(at -5.25 -3.749 270)
			(size 0.3 1.55)
			(layers "F.Cu" "F.Mask" "F.Paste")
			(net 20 "unconnected-(J100-SDIO_D2-Pad17)")
			(pinfunction "SDIO_D2")
			(pintype "bidirectional+no_connect")
			(teardrops
				(best_length_ratio 0.2)
				(max_length 1)
				(best_width_ratio 0.9)
				(max_width 2)
				(curved_edges yes)
				(filter_ratio 0.9)
				(enabled yes)
				(allow_two_segments yes)
				(prefer_zone_connections yes)
			)
		)
		(pad "18" smd rect
			(at -5.001 3.749 270)
			(size 0.3 1.55)
			(layers "F.Cu" "F.Mask" "F.Paste")
			(net 1 "GND")
			(pinfunction "GND")
			(pintype "passive")
			(teardrops
				(best_length_ratio 0.2)
				(max_length 1)
				(best_width_ratio 0.9)
				(max_width 2)
				(curved_edges yes)
				(filter_ratio 0.9)
				(enabled yes)
				(allow_two_segments yes)
				(prefer_zone_connections yes)
			)
		)
		(pad "19" smd rect
			(at -4.751 -3.749 270)
			(size 0.3 1.55)
			(layers "F.Cu" "F.Mask" "F.Paste")
			(net 22 "unconnected-(J100-SDIO_D3-Pad19)")
			(pinfunction "SDIO_D3")
			(pintype "bidirectional+no_connect")
			(teardrops
				(best_length_ratio 0.2)
				(max_length 1)
				(best_width_ratio 0.9)
				(max_width 2)
				(curved_edges yes)
				(filter_ratio 0.9)
				(enabled yes)
				(allow_two_segments yes)
				(prefer_zone_connections yes)
			)
		)
		(pad "20" smd rect
			(at -4.501 3.749 270)
			(size 0.3 1.55)
			(layers "F.Cu" "F.Mask" "F.Paste")
			(net 25 "unconnected-(J100-~{UART_WAKE}-Pad20)")
			(pinfunction "~{UART_WAKE}")
			(pintype "output+no_connect")
			(teardrops
				(best_length_ratio 0.2)
				(max_length 1)
				(best_width_ratio 0.9)
				(max_width 2)
				(curved_edges yes)
				(filter_ratio 0.9)
				(enabled yes)
				(allow_two_segments yes)
				(prefer_zone_connections yes)
			)
		)
		(pad "21" smd rect
			(at -4.251 -3.749 270)
			(size 0.3 1.55)
			(layers "F.Cu" "F.Mask" "F.Paste")
			(net 26 "unconnected-(J100-SDIO_~{WAKE}-Pad21)")
			(pinfunction "SDIO_~{WAKE}")
			(pintype "bidirectional+no_connect")
			(teardrops
				(best_length_ratio 0.2)
				(max_length 1)
				(best_width_ratio 0.9)
				(max_width 2)
				(curved_edges yes)
				(filter_ratio 0.9)
				(enabled yes)
				(allow_two_segments yes)
				(prefer_zone_connections yes)
			)
		)
		(pad "22" smd rect
			(at -4.001 3.749 270)
			(size 0.3 1.55)
			(layers "F.Cu" "F.Mask" "F.Paste")
			(net 27 "unconnected-(J100-UART_RXD-Pad22)")
			(pinfunction "UART_RXD")
			(pintype "bidirectional+no_connect")
			(teardrops
				(best_length_ratio 0.2)
				(max_length 1)
				(best_width_ratio 0.9)
				(max_width 2)
				(curved_edges yes)
				(filter_ratio 0.9)
				(enabled yes)
				(allow_two_segments yes)
				(prefer_zone_connections yes)
			)
		)
		(pad "23" smd rect
			(at -3.75 -3.749 270)
			(size 0.3 1.55)
			(layers "F.Cu" "F.Mask" "F.Paste")
			(net 28 "unconnected-(J100-SDIO_~{RESET}-Pad23)")
			(pinfunction "SDIO_~{RESET}")
			(pintype "input+no_connect")
			(teardrops
				(best_length_ratio 0.2)
				(max_length 1)
				(best_width_ratio 0.9)
				(max_width 2)
				(curved_edges yes)
				(filter_ratio 0.9)
				(enabled yes)
				(allow_two_segments yes)
				(prefer_zone_connections yes)
			)
		)
		(pad "32" smd rect
			(at -1.5 3.749 270)
			(size 0.3 1.55)
			(layers "F.Cu" "F.Mask" "F.Paste")
			(net 29 "unconnected-(J100-UART_TXD-Pad32)")
			(pinfunction "UART_TXD")
			(pintype "bidirectional+no_connect")
			(teardrops
				(best_length_ratio 0.2)
				(max_length 1)
				(best_width_ratio 0.9)
				(max_width 2)
				(curved_edges yes)
				(filter_ratio 0.9)
				(enabled yes)
				(allow_two_segments yes)
				(prefer_zone_connections yes)
			)
		)
		(pad "33" smd rect
			(at -1.25 -3.749 270)
			(size 0.3 1.55)
			(layers "F.Cu" "F.Mask" "F.Paste")
			(net 1 "GND")
			(pinfunction "GND")
			(pintype "passive")
			(teardrops
				(best_length_ratio 0.2)
				(max_length 1)
				(best_width_ratio 0.9)
				(max_width 2)
				(curved_edges yes)
				(filter_ratio 0.9)
				(enabled yes)
				(allow_two_segments yes)
				(prefer_zone_connections yes)
			)
		)
		(pad "34" smd rect
			(at -1 3.749 270)
			(size 0.3 1.55)
			(layers "F.Cu" "F.Mask" "F.Paste")
			(net 30 "unconnected-(J100-UART_CTS-Pad34)")
			(pinfunction "UART_CTS")
			(pintype "bidirectional+no_connect")
			(teardrops
				(best_length_ratio 0.2)
				(max_length 1)
				(best_width_ratio 0.9)
				(max_width 2)
				(curved_edges yes)
				(filter_ratio 0.9)
				(enabled yes)
				(allow_two_segments yes)
				(prefer_zone_connections yes)
			)
		)
		(pad "35" smd rect
			(at -0.75 -3.749 270)
			(size 0.3 1.55)
			(layers "F.Cu" "F.Mask" "F.Paste")
			(net 11 "/Com Express 7 Interfaces/PCIe_{B1x2}.TX0-")
			(pinfunction "PET0_P")
			(pintype "input")
			(teardrops
				(best_length_ratio 0.2)
				(max_length 1)
				(best_width_ratio 0.9)
				(max_width 2)
				(curved_edges yes)
				(filter_ratio 0.9)
				(enabled yes)
				(allow_two_segments yes)
				(prefer_zone_connections yes)
			)
		)
		(pad "36" smd rect
			(at -0.5 3.749 270)
			(size 0.3 1.55)
			(layers "F.Cu" "F.Mask" "F.Paste")
			(net 31 "unconnected-(J100-UART_RTS-Pad36)")
			(pinfunction "UART_RTS")
			(pintype "bidirectional+no_connect")
			(teardrops
				(best_length_ratio 0.2)
				(max_length 1)
				(best_width_ratio 0.9)
				(max_width 2)
				(curved_edges yes)
				(filter_ratio 0.9)
				(enabled yes)
				(allow_two_segments yes)
				(prefer_zone_connections yes)
			)
		)
		(pad "37" smd rect
			(at -0.25 -3.749 270)
			(size 0.3 1.55)
			(layers "F.Cu" "F.Mask" "F.Paste")
			(net 9 "/Com Express 7 Interfaces/PCIe_{B1x2}.TX0+")
			(pinfunction "PET0_N")
			(pintype "input")
			(teardrops
				(best_length_ratio 0.2)
				(max_length 1)
				(best_width_ratio 0.9)
				(max_width 2)
				(curved_edges yes)
				(filter_ratio 0.9)
				(enabled yes)
				(allow_two_segments yes)
				(prefer_zone_connections yes)
			)
		)
		(pad "38" smd rect
			(at 0 3.749 270)
			(size 0.3 1.55)
			(layers "F.Cu" "F.Mask" "F.Paste")
			(net 32 "unconnected-(J100-VENDOR_1-Pad38)")
			(pinfunction "VENDOR_1")
			(pintype "bidirectional+no_connect")
			(teardrops
				(best_length_ratio 0.2)
				(max_length 1)
				(best_width_ratio 0.9)
				(max_width 2)
				(curved_edges yes)
				(filter_ratio 0.9)
				(enabled yes)
				(allow_two_segments yes)
				(prefer_zone_connections yes)
			)
		)
		(pad "39" smd rect
			(at 0.25 -3.749 270)
			(size 0.3 1.55)
			(layers "F.Cu" "F.Mask" "F.Paste")
			(net 1 "GND")
			(pinfunction "GND")
			(pintype "passive")
			(teardrops
				(best_length_ratio 0.2)
				(max_length 1)
				(best_width_ratio 0.9)
				(max_width 2)
				(curved_edges yes)
				(filter_ratio 0.9)
				(enabled yes)
				(allow_two_segments yes)
				(prefer_zone_connections yes)
			)
		)
		(pad "40" smd rect
			(at 0.5 3.749 270)
			(size 0.3 1.55)
			(layers "F.Cu" "F.Mask" "F.Paste")
			(net 33 "unconnected-(J100-VENDOR_2-Pad40)")
			(pinfunction "VENDOR_2")
			(pintype "bidirectional+no_connect")
			(teardrops
				(best_length_ratio 0.2)
				(max_length 1)
				(best_width_ratio 0.9)
				(max_width 2)
				(curved_edges yes)
				(filter_ratio 0.9)
				(enabled yes)
				(allow_two_segments yes)
				(prefer_zone_connections yes)
			)
		)
		(pad "41" smd rect
			(at 0.75 -3.749 270)
			(size 0.3 1.55)
			(layers "F.Cu" "F.Mask" "F.Paste")
			(net 16 "/Com Express 7 Interfaces/PCIe_{B1x2}.RX0-")
			(pinfunction "PER0_P")
			(pintype "output")
			(teardrops
				(best_length_ratio 0.2)
				(max_length 1)
				(best_width_ratio 0.9)
				(max_width 2)
				(curved_edges yes)
				(filter_ratio 0.9)
				(enabled yes)
				(allow_two_segments yes)
				(prefer_zone_connections yes)
			)
		)
		(pad "42" smd rect
			(at 1 3.749 270)
			(size 0.3 1.55)
			(layers "F.Cu" "F.Mask" "F.Paste")
			(net 34 "unconnected-(J100-VENDOR_3-Pad42)")
			(pinfunction "VENDOR_3")
			(pintype "bidirectional+no_connect")
			(teardrops
				(best_length_ratio 0.2)
				(max_length 1)
				(best_width_ratio 0.9)
				(max_width 2)
				(curved_edges yes)
				(filter_ratio 0.9)
				(enabled yes)
				(allow_two_segments yes)
				(prefer_zone_connections yes)
			)
		)
		(pad "43" smd rect
			(at 1.25 -3.749 270)
			(size 0.3 1.55)
			(layers "F.Cu" "F.Mask" "F.Paste")
			(net 14 "/Com Express 7 Interfaces/PCIe_{B1x2}.RX0+")
			(pinfunction "PER0_N")
			(pintype "output")
			(teardrops
				(best_length_ratio 0.2)
				(max_length 1)
				(best_width_ratio 0.9)
				(max_width 2)
				(curved_edges yes)
				(filter_ratio 0.9)
				(enabled yes)
				(allow_two_segments yes)
				(prefer_zone_connections yes)
			)
		)
		(pad "44" smd rect
			(at 1.5 3.749 270)
			(size 0.3 1.55)
			(layers "F.Cu" "F.Mask" "F.Paste")
			(net 35 "unconnected-(J100-COEX3-Pad44)")
			(pinfunction "COEX3")
			(pintype "bidirectional+no_connect")
			(teardrops
				(best_length_ratio 0.2)
				(max_length 1)
				(best_width_ratio 0.9)
				(max_width 2)
				(curved_edges yes)
				(filter_ratio 0.9)
				(enabled yes)
				(allow_two_segments yes)
				(prefer_zone_connections yes)
			)
		)
		(pad "45" smd rect
			(at 1.75 -3.749 270)
			(size 0.3 1.55)
			(layers "F.Cu" "F.Mask" "F.Paste")
			(net 1 "GND")
			(pinfunction "GND")
			(pintype "passive")
			(teardrops
				(best_length_ratio 0.2)
				(max_length 1)
				(best_width_ratio 0.9)
				(max_width 2)
				(curved_edges yes)
				(filter_ratio 0.9)
				(enabled yes)
				(allow_two_segments yes)
				(prefer_zone_connections yes)
			)
		)
		(pad "46" smd rect
			(at 2 3.749 270)
			(size 0.3 1.55)
			(layers "F.Cu" "F.Mask" "F.Paste")
			(net 36 "unconnected-(J100-COEX_TXD-Pad46)")
			(pinfunction "COEX_TXD")
			(pintype "bidirectional+no_connect")
			(teardrops
				(best_length_ratio 0.2)
				(max_length 1)
				(best_width_ratio 0.9)
				(max_width 2)
				(curved_edges yes)
				(filter_ratio 0.9)
				(enabled yes)
				(allow_two_segments yes)
				(prefer_zone_connections yes)
			)
		)
		(pad "47" smd rect
			(at 2.25 -3.749 270)
			(size 0.3 1.55)
			(layers "F.Cu" "F.Mask" "F.Paste")
			(net 21 "/M.2 key E/PCIE_{REF}.CK-")
			(pinfunction "REFCLK0_P")
			(pintype "input")
			(teardrops
				(best_length_ratio 0.2)
				(max_length 1)
				(best_width_ratio 0.9)
				(max_width 2)
				(curved_edges yes)
				(filter_ratio 0.9)
				(enabled yes)
				(allow_two_segments yes)
				(prefer_zone_connections yes)
			)
		)
		(pad "48" smd rect
			(at 2.5 3.749 270)
			(size 0.3 1.55)
			(layers "F.Cu" "F.Mask" "F.Paste")
			(net 37 "unconnected-(J100-COEX_RXD-Pad48)")
			(pinfunction "COEX_RXD")
			(pintype "bidirectional+no_connect")
			(teardrops
				(best_length_ratio 0.2)
				(max_length 1)
				(best_width_ratio 0.9)
				(max_width 2)
				(curved_edges yes)
				(filter_ratio 0.9)
				(enabled yes)
				(allow_two_segments yes)
				(prefer_zone_connections yes)
			)
		)
		(pad "49" smd rect
			(at 2.75 -3.749 270)
			(size 0.3 1.55)
			(layers "F.Cu" "F.Mask" "F.Paste")
			(net 19 "/M.2 key E/PCIE_{REF}.CK+")
			(pinfunction "REFCLK0_N")
			(pintype "input")
			(teardrops
				(best_length_ratio 0.2)
				(max_length 1)
				(best_width_ratio 0.9)
				(max_width 2)
				(curved_edges yes)
				(filter_ratio 0.9)
				(enabled yes)
				(allow_two_segments yes)
				(prefer_zone_connections yes)
			)
		)
		(pad "50" smd rect
			(at 3 3.749 270)
			(size 0.3 1.55)
			(layers "F.Cu" "F.Mask" "F.Paste")
			(net 38 "Net-(J100-SUSCLK)")
			(pinfunction "SUSCLK")
			(pintype "input")
			(teardrops
				(best_length_ratio 0.2)
				(max_length 1)
				(best_width_ratio 0.9)
				(max_width 2)
				(curved_edges yes)
				(filter_ratio 0.9)
				(enabled yes)
				(allow_two_segments yes)
				(prefer_zone_connections yes)
			)
		)
		(pad "51" smd rect
			(at 3.25 -3.749 270)
			(size 0.3 1.55)
			(layers "F.Cu" "F.Mask" "F.Paste")
			(net 1 "GND")
			(pinfunction "GND")
			(pintype "passive")
			(teardrops
				(best_length_ratio 0.2)
				(max_length 1)
				(best_width_ratio 0.9)
				(max_width 2)
				(curved_edges yes)
				(filter_ratio 0.9)
				(enabled yes)
				(allow_two_segments yes)
				(prefer_zone_connections yes)
			)
		)
		(pad "52" smd rect
			(at 3.5 3.749 270)
			(size 0.3 1.55)
			(layers "F.Cu" "F.Mask" "F.Paste")
			(net 23 "/M.2 key E/~{PERST_D}")
			(pinfunction "~{PERST0}")
			(pintype "input")
			(teardrops
				(best_length_ratio 0.2)
				(max_length 1)
				(best_width_ratio 0.9)
				(max_width 2)
				(curved_edges yes)
				(filter_ratio 0.9)
				(enabled yes)
				(allow_two_segments yes)
				(prefer_zone_connections yes)
			)
		)
		(pad "53" smd rect
			(at 3.75 -3.749 270)
			(size 0.3 1.55)
			(layers "F.Cu" "F.Mask" "F.Paste")
			(net 24 "/M.2 key E/~{CLKREQ}")
			(pinfunction "~{CLKREQ0}")
			(pintype "output")
			(teardrops
				(best_length_ratio 0.2)
				(max_length 1)
				(best_width_ratio 0.9)
				(max_width 2)
				(curved_edges yes)
				(filter_ratio 0.9)
				(enabled yes)
				(allow_two_segments yes)
				(prefer_zone_connections yes)
			)
		)
		(pad "54" smd rect
			(at 4 3.749 270)
			(size 0.3 1.55)
			(layers "F.Cu" "F.Mask" "F.Paste")
			(net 39 "unconnected-(J100-W_DISABLE2-Pad54)")
			(pinfunction "W_DISABLE2")
			(pintype "input+no_connect")
			(teardrops
				(best_length_ratio 0.2)
				(max_length 1)
				(best_width_ratio 0.9)
				(max_width 2)
				(curved_edges yes)
				(filter_ratio 0.9)
				(enabled yes)
				(allow_two_segments yes)
				(prefer_zone_connections yes)
			)
		)
		(pad "55" smd rect
			(at 4.25 -3.749 270)
			(size 0.3 1.55)
			(layers "F.Cu" "F.Mask" "F.Paste")
			(net 40 "unconnected-(J100-~{PEWAKE0}-Pad55)")
			(pinfunction "~{PEWAKE0}")
			(pintype "output+no_connect")
			(teardrops
				(best_length_ratio 0.2)
				(max_length 1)
				(best_width_ratio 0.9)
				(max_width 2)
				(curved_edges yes)
				(filter_ratio 0.9)
				(enabled yes)
				(allow_two_segments yes)
				(prefer_zone_connections yes)
			)
		)
		(pad "56" smd rect
			(at 4.5 3.749 270)
			(size 0.3 1.55)
			(layers "F.Cu" "F.Mask" "F.Paste")
			(net 900 "unconnected-(J100-W_DISABLE1-Pad56)")
			(pinfunction "W_DISABLE1")
			(pintype "input+no_connect")
			(teardrops
				(best_length_ratio 0.2)
				(max_length 1)
				(best_width_ratio 0.9)
				(max_width 2)
				(curved_edges yes)
				(filter_ratio 0.9)
				(enabled yes)
				(allow_two_segments yes)
				(prefer_zone_connections yes)
			)
		)
		(pad "57" smd rect
			(at 4.75 -3.749 270)
			(size 0.3 1.55)
			(layers "F.Cu" "F.Mask" "F.Paste")
			(net 1 "GND")
			(pinfunction "GND")
			(pintype "passive")
			(teardrops
				(best_length_ratio 0.2)
				(max_length 1)
				(best_width_ratio 0.9)
				(max_width 2)
				(curved_edges yes)
				(filter_ratio 0.9)
				(enabled yes)
				(allow_two_segments yes)
				(prefer_zone_connections yes)
			)
		)
		(pad "58" smd rect
			(at 5 3.749 270)
			(size 0.3 1.55)
			(layers "F.Cu" "F.Mask" "F.Paste")
			(net 901 "unconnected-(J100-I2C_DATA-Pad58)")
			(pinfunction "I2C_DATA")
			(pintype "bidirectional+no_connect")
			(teardrops
				(best_length_ratio 0.2)
				(max_length 1)
				(best_width_ratio 0.9)
				(max_width 2)
				(curved_edges yes)
				(filter_ratio 0.9)
				(enabled yes)
				(allow_two_segments yes)
				(prefer_zone_connections yes)
			)
		)
		(pad "59" smd rect
			(at 5.25 -3.749 270)
			(size 0.3 1.55)
			(layers "F.Cu" "F.Mask" "F.Paste")
			(net 902 "unconnected-(J100-PET1_P-Pad59)")
			(pinfunction "PET1_P")
			(pintype "input+no_connect")
			(teardrops
				(best_length_ratio 0.2)
				(max_length 1)
				(best_width_ratio 0.9)
				(max_width 2)
				(curved_edges yes)
				(filter_ratio 0.9)
				(enabled yes)
				(allow_two_segments yes)
				(prefer_zone_connections yes)
			)
		)
		(pad "60" smd rect
			(at 5.5 3.749 270)
			(size 0.3 1.55)
			(layers "F.Cu" "F.Mask" "F.Paste")
			(net 903 "unconnected-(J100-I2C_CLK-Pad60)")
			(pinfunction "I2C_CLK")
			(pintype "bidirectional+no_connect")
			(teardrops
				(best_length_ratio 0.2)
				(max_length 1)
				(best_width_ratio 0.9)
				(max_width 2)
				(curved_edges yes)
				(filter_ratio 0.9)
				(enabled yes)
				(allow_two_segments yes)
				(prefer_zone_connections yes)
			)
		)
		(pad "61" smd rect
			(at 5.75 -3.749 270)
			(size 0.3 1.55)
			(layers "F.Cu" "F.Mask" "F.Paste")
			(net 904 "unconnected-(J100-PET1_N-Pad61)")
			(pinfunction "PET1_N")
			(pintype "input+no_connect")
			(teardrops
				(best_length_ratio 0.2)
				(max_length 1)
				(best_width_ratio 0.9)
				(max_width 2)
				(curved_edges yes)
				(filter_ratio 0.9)
				(enabled yes)
				(allow_two_segments yes)
				(prefer_zone_connections yes)
			)
		)
		(pad "62" smd rect
			(at 6 3.749 270)
			(size 0.3 1.55)
			(layers "F.Cu" "F.Mask" "F.Paste")
			(net 905 "unconnected-(J100-~{ALERT}-Pad62)")
			(pinfunction "~{ALERT}")
			(pintype "output+no_connect")
			(teardrops
				(best_length_ratio 0.2)
				(max_length 1)
				(best_width_ratio 0.9)
				(max_width 2)
				(curved_edges yes)
				(filter_ratio 0.9)
				(enabled yes)
				(allow_two_segments yes)
				(prefer_zone_connections yes)
			)
		)
		(pad "63" smd rect
			(at 6.25 -3.749 270)
			(size 0.3 1.55)
			(layers "F.Cu" "F.Mask" "F.Paste")
			(net 1 "GND")
			(pinfunction "GND")
			(pintype "passive")
			(teardrops
				(best_length_ratio 0.2)
				(max_length 1)
				(best_width_ratio 0.9)
				(max_width 2)
				(curved_edges yes)
				(filter_ratio 0.9)
				(enabled yes)
				(allow_two_segments yes)
				(prefer_zone_connections yes)
			)
		)
		(pad "64" smd rect
			(at 6.5 3.749 270)
			(size 0.3 1.55)
			(layers "F.Cu" "F.Mask" "F.Paste")
			(net 906 "unconnected-(J100-RFU-Pad64)")
			(pinfunction "RFU")
			(pintype "no_connect")
			(teardrops
				(best_length_ratio 0.2)
				(max_length 1)
				(best_width_ratio 0.9)
				(max_width 2)
				(curved_edges yes)
				(filter_ratio 0.9)
				(enabled yes)
				(allow_two_segments yes)
				(prefer_zone_connections yes)
			)
		)
		(pad "65" smd rect
			(at 6.75 -3.749 270)
			(size 0.3 1.55)
			(layers "F.Cu" "F.Mask" "F.Paste")
			(net 907 "unconnected-(J100-PER1_P-Pad65)")
			(pinfunction "PER1_P")
			(pintype "output+no_connect")
			(teardrops
				(best_length_ratio 0.2)
				(max_length 1)
				(best_width_ratio 0.9)
				(max_width 2)
				(curved_edges yes)
				(filter_ratio 0.9)
				(enabled yes)
				(allow_two_segments yes)
				(prefer_zone_connections yes)
			)
		)
		(pad "66" smd rect
			(at 6.999 3.749 270)
			(size 0.3 1.55)
			(layers "F.Cu" "F.Mask" "F.Paste")
			(net 908 "unconnected-(J100-UIM_SWP-Pad66)")
			(pinfunction "UIM_SWP")
			(pintype "bidirectional+no_connect")
			(teardrops
				(best_length_ratio 0.2)
				(max_length 1)
				(best_width_ratio 0.9)
				(max_width 2)
				(curved_edges yes)
				(filter_ratio 0.9)
				(enabled yes)
				(allow_two_segments yes)
				(prefer_zone_connections yes)
			)
		)
		(pad "67" smd rect
			(at 7.249 -3.749 270)
			(size 0.3 1.55)
			(layers "F.Cu" "F.Mask" "F.Paste")
			(net 909 "unconnected-(J100-PER1_N-Pad67)")
			(pinfunction "PER1_N")
			(pintype "output+no_connect")
			(teardrops
				(best_length_ratio 0.2)
				(max_length 1)
				(best_width_ratio 0.9)
				(max_width 2)
				(curved_edges yes)
				(filter_ratio 0.9)
				(enabled yes)
				(allow_two_segments yes)
				(prefer_zone_connections yes)
			)
		)
		(pad "68" smd rect
			(at 7.499 3.749 270)
			(size 0.3 1.55)
			(layers "F.Cu" "F.Mask" "F.Paste")
			(net 910 "unconnected-(J100-UIM_POWER_SNK-Pad68)")
			(pinfunction "UIM_POWER_SNK")
			(pintype "bidirectional+no_connect")
			(teardrops
				(best_length_ratio 0.2)
				(max_length 1)
				(best_width_ratio 0.9)
				(max_width 2)
				(curved_edges yes)
				(filter_ratio 0.9)
				(enabled yes)
				(allow_two_segments yes)
				(prefer_zone_connections yes)
			)
		)
		(pad "69" smd rect
			(at 7.749 -3.749 270)
			(size 0.3 1.55)
			(layers "F.Cu" "F.Mask" "F.Paste")
			(net 1 "GND")
			(pinfunction "GND")
			(pintype "passive")
			(teardrops
				(best_length_ratio 0.2)
				(max_length 1)
				(best_width_ratio 0.9)
				(max_width 2)
				(curved_edges yes)
				(filter_ratio 0.9)
				(enabled yes)
				(allow_two_segments yes)
				(prefer_zone_connections yes)
			)
		)
		(pad "70" smd rect
			(at 7.999 3.749 270)
			(size 0.3 1.55)
			(layers "F.Cu" "F.Mask" "F.Paste")
			(net 911 "unconnected-(J100-UIM_POWER_SRC-Pad70)")
			(pinfunction "UIM_POWER_SRC")
			(pintype "bidirectional+no_connect")
			(teardrops
				(best_length_ratio 0.2)
				(max_length 1)
				(best_width_ratio 0.9)
				(max_width 2)
				(curved_edges yes)
				(filter_ratio 0.9)
				(enabled yes)
				(allow_two_segments yes)
				(prefer_zone_connections yes)
			)
		)
		(pad "71" smd rect
			(at 8.249 -3.749 270)
			(size 0.3 1.55)
			(layers "F.Cu" "F.Mask" "F.Paste")
			(net 912 "unconnected-(J100-REFCLK1_P-Pad71)")
			(pinfunction "REFCLK1_P")
			(pintype "input+no_connect")
			(teardrops
				(best_length_ratio 0.2)
				(max_length 1)
				(best_width_ratio 0.9)
				(max_width 2)
				(curved_edges yes)
				(filter_ratio 0.9)
				(enabled yes)
				(allow_two_segments yes)
				(prefer_zone_connections yes)
			)
		)
		(pad "72" smd rect
			(at 8.499 3.749 270)
			(size 0.3 1.55)
			(layers "F.Cu" "F.Mask" "F.Paste")
			(net 2 "+3V3")
			(pinfunction "3.3V")
			(pintype "passive")
			(teardrops
				(best_length_ratio 0.2)
				(max_length 1)
				(best_width_ratio 0.9)
				(max_width 2)
				(curved_edges yes)
				(filter_ratio 0.9)
				(enabled yes)
				(allow_two_segments yes)
				(prefer_zone_connections yes)
			)
		)
		(pad "73" smd rect
			(at 8.749 -3.749 270)
			(size 0.3 1.55)
			(layers "F.Cu" "F.Mask" "F.Paste")
			(net 913 "unconnected-(J100-REFCLK1_N-Pad73)")
			(pinfunction "REFCLK1_N")
			(pintype "input+no_connect")
			(teardrops
				(best_length_ratio 0.2)
				(max_length 1)
				(best_width_ratio 0.9)
				(max_width 2)
				(curved_edges yes)
				(filter_ratio 0.9)
				(enabled yes)
				(allow_two_segments yes)
				(prefer_zone_connections yes)
			)
		)
		(pad "74" smd rect
			(at 8.999 3.749 270)
			(size 0.3 1.55)
			(layers "F.Cu" "F.Mask" "F.Paste")
			(net 2 "+3V3")
			(pinfunction "3.3V")
			(pintype "passive")
			(teardrops
				(best_length_ratio 0.2)
				(max_length 1)
				(best_width_ratio 0.9)
				(max_width 2)
				(curved_edges yes)
				(filter_ratio 0.9)
				(enabled yes)
				(allow_two_segments yes)
				(prefer_zone_connections yes)
			)
		)
		(pad "75" smd rect
			(at 9.249 -3.749 270)
			(size 0.3 1.55)
			(layers "F.Cu" "F.Mask" "F.Paste")
			(net 1 "GND")
			(pinfunction "GND")
			(pintype "passive")
			(teardrops
				(best_length_ratio 0.2)
				(max_length 1)
				(best_width_ratio 0.9)
				(max_width 2)
				(curved_edges yes)
				(filter_ratio 0.9)
				(enabled yes)
				(allow_two_segments yes)
				(prefer_zone_connections yes)
			)
		)
		(pad "MP" smd rect
			(at -10.35 -3.001 270)
			(size 1.2 2.75)
			(layers "F.Cu" "F.Mask" "F.Paste")
			(net 1 "GND")
			(pinfunction "MP")
			(pintype "passive")
			(teardrops
				(best_length_ratio 0.2)
				(max_length 1)
				(best_width_ratio 0.9)
				(max_width 2)
				(curved_edges yes)
				(filter_ratio 0.9)
				(enabled yes)
				(allow_two_segments yes)
				(prefer_zone_connections yes)
			)
		)
		(pad "MP" smd rect
			(at 10.351 -3.001 270)
			(size 1.2 2.75)
			(layers "F.Cu" "F.Mask" "F.Paste")
			(net 1 "GND")
			(pinfunction "MP")
			(pintype "passive")
			(teardrops
				(best_length_ratio 0.2)
				(max_length 1)
				(best_width_ratio 0.9)
				(max_width 2)
				(curved_edges yes)
				(filter_ratio 0.9)
				(enabled yes)
				(allow_two_segments yes)
				(prefer_zone_connections yes)
			)
		)
	)
	(footprint "antmicro-footprints:R_0201"
		(layer "F.Cu")
		(at 129.17 147.935 -90)
		(descr "Resistor SMD 0201")
		(tags "resistor SMD 0201")
		(property "Reference" "R313"
			(at 3.6 -0.58 90)
			(layer "F.SilkS")
			(effects
				(font
					(size 0.7 0.7)
					(thickness 0.15)
				)
				(justify right bottom)
			)
		)
		(property "Value" "R_0R_0201"
			(at 0 1.25 90)
			(layer "F.Fab")
			(effects
				(font
					(size 0.7 0.7)
					(thickness 0.15)
				)
				(justify right bottom)
			)
		)
		(property "Datasheet" "https://www.bourns.com/docs/product-datasheets/cr.pdf"
			(at 0 0 270)
			(layer "F.Fab")
			(hide yes)
			(effects
				(font
					(size 1.27 1.27)
					(thickness 0.15)
				)
			)
		)
		(property "Author" "Antmicro"
			(at -18.765 277.105 0)
			(layer "F.Fab")
			(hide yes)
			(effects
				(font
					(size 1 1)
					(thickness 0.15)
				)
			)
		)
		(property "License" "Apache-2.0"
			(at -18.765 277.105 0)
			(layer "F.Fab")
			(hide yes)
			(effects
				(font
					(size 1 1)
					(thickness 0.15)
				)
			)
		)
		(property "MPN" "CR0201-FX-0R00GLF"
			(at -18.765 277.105 0)
			(layer "F.Fab")
			(hide yes)
			(effects
				(font
					(size 1 1)
					(thickness 0.15)
				)
			)
		)
		(property "Manufacturer" "Bourns"
			(at -18.765 277.105 0)
			(layer "F.Fab")
			(hide yes)
			(effects
				(font
					(size 1 1)
					(thickness 0.15)
				)
			)
		)
		(property "Tolerance" "1%"
			(at -18.765 277.105 0)
			(layer "F.Fab")
			(hide yes)
			(effects
				(font
					(size 1 1)
					(thickness 0.15)
				)
			)
		)
		(property "Val" "0R"
			(at -18.765 277.105 0)
			(layer "F.Fab")
			(hide yes)
			(effects
				(font
					(size 1 1)
					(thickness 0.15)
				)
			)
		)
		(sheetname "KR to SFI #2")
		(sheetfile "kr_sfi.kicad_sch")
		(attr smd dnp)
		(fp_rect
			(start -0.7 -0.35)
			(end 0.7 0.35)
			(stroke
				(width 0.05)
				(type default)
			)
			(fill no)
			(layer "F.CrtYd")
		)
		(fp_rect
			(start -0.3 -0.15)
			(end 0.298 0.148)
			(stroke
				(width 0.15)
				(type solid)
			)
			(fill no)
			(layer "F.Fab")
		)
		(pad "" smd roundrect
			(at -0.346 0 270)
			(size 0.318 0.36)
			(layers "F.Paste")
			(roundrect_rratio 0.25)
			(teardrops
				(best_length_ratio 0.2)
				(max_length 1)
				(best_width_ratio 0.9)
				(max_width 2)
				(curved_edges yes)
				(filter_ratio 0.9)
				(enabled yes)
				(allow_two_segments yes)
				(prefer_zone_connections yes)
			)
		)
		(pad "" smd roundrect
			(at 0.344 0 270)
			(size 0.318 0.36)
			(layers "F.Paste")
			(roundrect_rratio 0.25)
			(teardrops
				(best_length_ratio 0.2)
				(max_length 1)
				(best_width_ratio 0.9)
				(max_width 2)
				(curved_edges yes)
				(filter_ratio 0.9)
				(enabled yes)
				(allow_two_segments yes)
				(prefer_zone_connections yes)
			)
		)
		(pad "1" smd roundrect
			(at -0.32 0 270)
			(size 0.46 0.4)
			(layers "F.Cu" "F.Mask")
			(roundrect_rratio 0.25)
			(net 879 "/2xSFP+/SFI1.TX+")
			(pintype "passive")
			(teardrops
				(best_length_ratio 0.2)
				(max_length 1)
				(best_width_ratio 0.9)
				(max_width 2)
				(curved_edges yes)
				(filter_ratio 0.9)
				(enabled yes)
				(allow_two_segments yes)
				(prefer_zone_connections yes)
			)
		)
		(pad "2" smd roundrect
			(at 0.32 0 270)
			(size 0.46 0.4)
			(layers "F.Cu" "F.Mask")
			(roundrect_rratio 0.25)
			(net 955 "/2xSFP+/KR to SFI #2/BYP_TX+")
			(pintype "passive")
			(teardrops
				(best_length_ratio 0.2)
				(max_length 1)
				(best_width_ratio 0.9)
				(max_width 2)
				(curved_edges yes)
				(filter_ratio 0.9)
				(enabled yes)
				(allow_two_segments yes)
				(prefer_zone_connections yes)
			)
		)
	)
	(footprint "antmicro-footprints:R_0402_1005Metric"
		(layer "F.Cu")
		(at 128.9 81.76 -90)
		(descr "Resistor SMD 0402")
		(tags "resistor SMD 0402")
		(property "Reference" "R237"
			(at -3.650001 -0.45 90)
			(layer "F.SilkS")
			(effects
				(font
					(size 0.7 0.7)
					(thickness 0.15)
				)
				(justify right bottom)
			)
		)
		(property "Value" "R_0R_0402"
			(at -1.011843 1.772047 90)
			(layer "F.Fab")
			(effects
				(font
					(size 0.7 0.7)
					(thickness 0.15)
				)
				(justify right bottom)
			)
		)
		(property "Datasheet" "https://industrial.panasonic.com/cdbs/www-data/pdf/RDA0000/AOA0000C301.pdf"
			(at 0 0 270)
			(layer "F.Fab")
			(hide yes)
			(effects
				(font
					(size 1.27 1.27)
					(thickness 0.15)
				)
			)
		)
		(property "Author" "Antmicro"
			(at 47.14 210.66 0)
			(layer "F.Fab")
			(hide yes)
			(effects
				(font
					(size 1 1)
					(thickness 0.15)
				)
			)
		)
		(property "Current" "1A"
			(at 47.14 210.66 0)
			(layer "F.Fab")
			(hide yes)
			(effects
				(font
					(size 1 1)
					(thickness 0.15)
				)
			)
		)
		(property "License" "Apache-2.0"
			(at 47.14 210.66 0)
			(layer "F.Fab")
			(hide yes)
			(effects
				(font
					(size 1 1)
					(thickness 0.15)
				)
			)
		)
		(property "MPN" "ERJ2GE0R00X"
			(at 47.14 210.66 0)
			(layer "F.Fab")
			(hide yes)
			(effects
				(font
					(size 1 1)
					(thickness 0.15)
				)
			)
		)
		(property "Manufacturer" "Panasonic"
			(at 47.14 210.66 0)
			(layer "F.Fab")
			(hide yes)
			(effects
				(font
					(size 1 1)
					(thickness 0.15)
				)
			)
		)
		(property "Public" "False"
			(at 47.14 210.66 0)
			(layer "F.Fab")
			(hide yes)
			(effects
				(font
					(size 1 1)
					(thickness 0.15)
				)
			)
		)
		(property "Tolerance" ""
			(at 47.14 210.66 0)
			(layer "F.Fab")
			(hide yes)
			(effects
				(font
					(size 1 1)
					(thickness 0.15)
				)
			)
		)
		(property "Val" "0R"
			(at 47.14 210.66 0)
			(layer "F.Fab")
			(hide yes)
			(effects
				(font
					(size 1 1)
					(thickness 0.15)
				)
			)
		)
		(sheetname "GPIO expander")
		(sheetfile "gpio_exp.kicad_sch")
		(attr smd)
		(fp_rect
			(start -0.925 -0.47)
			(end 0.925 0.47)
			(stroke
				(width 0.05)
				(type default)
			)
			(fill no)
			(layer "F.CrtYd")
		)
		(fp_rect
			(start -0.5 -0.25)
			(end 0.5 0.25)
			(stroke
				(width 0.15)
				(type solid)
			)
			(fill no)
			(layer "F.Fab")
		)
		(pad "1" smd roundrect
			(at -0.48 0 270)
			(size 0.59 0.64)
			(layers "F.Cu" "F.Mask" "F.Paste")
			(roundrect_rratio 0.25)
			(net 1 "GND")
			(pintype "passive")
			(teardrops
				(best_length_ratio 0.2)
				(max_length 1)
				(best_width_ratio 0.9)
				(max_width 2)
				(curved_edges yes)
				(filter_ratio 0.9)
				(enabled yes)
				(allow_two_segments yes)
				(prefer_zone_connections yes)
			)
		)
		(pad "2" smd roundrect
			(at 0.48 0 270)
			(size 0.59 0.64)
			(layers "F.Cu" "F.Mask" "F.Paste")
			(roundrect_rratio 0.25)
			(net 638 "Net-(U41-A1)")
			(pintype "passive")
			(teardrops
				(best_length_ratio 0.2)
				(max_length 1)
				(best_width_ratio 0.9)
				(max_width 2)
				(curved_edges yes)
				(filter_ratio 0.9)
				(enabled yes)
				(allow_two_segments yes)
				(prefer_zone_connections yes)
			)
		)
	)
	(footprint "antmicro-footprints:R_0402_1005Metric"
		(layer "F.Cu")
		(at 124.84 133.88)
		(descr "Resistor SMD 0402")
		(tags "resistor SMD 0402")
		(property "Reference" "R305"
			(at -3.69 0.43 0)
			(layer "F.SilkS")
			(effects
				(font
					(size 0.7 0.7)
					(thickness 0.15)
				)
				(justify left bottom)
			)
		)
		(property "Value" "R_10k_0402"
			(at -1.011843 1.772047 0)
			(layer "F.Fab")
			(effects
				(font
					(size 0.7 0.7)
					(thickness 0.15)
				)
				(justify left bottom)
			)
		)
		(property "Datasheet" "https://www.bourns.com/docs/product-datasheets/cr.pdf"
			(at 0 0 0)
			(layer "F.Fab")
			(hide yes)
			(effects
				(font
					(size 1.27 1.27)
					(thickness 0.15)
				)
			)
		)
		(property "Author" "Antmicro"
			(at 0 0 0)
			(layer "F.Fab")
			(hide yes)
			(effects
				(font
					(size 1 1)
					(thickness 0.15)
				)
			)
		)
		(property "License" "Apache-2.0"
			(at 0 0 0)
			(layer "F.Fab")
			(hide yes)
			(effects
				(font
					(size 1 1)
					(thickness 0.15)
				)
			)
		)
		(property "MPN" "CR0402-FX-1002GLF"
			(at 0 0 0)
			(layer "F.Fab")
			(hide yes)
			(effects
				(font
					(size 1 1)
					(thickness 0.15)
				)
			)
		)
		(property "Manufacturer" "Bourns"
			(at 0 0 0)
			(layer "F.Fab")
			(hide yes)
			(effects
				(font
					(size 1 1)
					(thickness 0.15)
				)
			)
		)
		(property "Public" "False"
			(at 0 0 0)
			(layer "F.Fab")
			(hide yes)
			(effects
				(font
					(size 1 1)
					(thickness 0.15)
				)
			)
		)
		(property "Tolerance" "1%"
			(at 0 0 0)
			(layer "F.Fab")
			(hide yes)
			(effects
				(font
					(size 1 1)
					(thickness 0.15)
				)
			)
		)
		(property "Val" "10k"
			(at 0 0 0)
			(layer "F.Fab")
			(hide yes)
			(effects
				(font
					(size 1 1)
					(thickness 0.15)
				)
			)
		)
		(sheetname "KR to SFI #2")
		(sheetfile "kr_sfi.kicad_sch")
		(attr smd)
		(fp_rect
			(start -0.925 -0.47)
			(end 0.925 0.47)
			(stroke
				(width 0.05)
				(type default)
			)
			(fill no)
			(layer "F.CrtYd")
		)
		(fp_rect
			(start -0.5 -0.25)
			(end 0.5 0.25)
			(stroke
				(width 0.15)
				(type solid)
			)
			(fill no)
			(layer "F.Fab")
		)
		(pad "1" smd roundrect
			(at -0.48 0)
			(size 0.59 0.64)
			(layers "F.Cu" "F.Mask" "F.Paste")
			(roundrect_rratio 0.25)
			(net 1 "GND")
			(pintype "passive")
			(teardrops
				(best_length_ratio 0.2)
				(max_length 1)
				(best_width_ratio 0.9)
				(max_width 2)
				(curved_edges yes)
				(filter_ratio 0.9)
				(enabled yes)
				(allow_two_segments yes)
				(prefer_zone_connections yes)
			)
		)
		(pad "2" smd roundrect
			(at 0.48 0)
			(size 0.59 0.64)
			(layers "F.Cu" "F.Mask" "F.Paste")
			(roundrect_rratio 0.25)
			(net 684 "Net-(U45C-ST)")
			(pintype "passive")
			(teardrops
				(best_length_ratio 0.2)
				(max_length 1)
				(best_width_ratio 0.9)
				(max_width 2)
				(curved_edges yes)
				(filter_ratio 0.9)
				(enabled yes)
				(allow_two_segments yes)
				(prefer_zone_connections yes)
			)
		)
	)
	(footprint "antmicro-footprints:R_0201"
		(layer "F.Cu")
		(at 152.57 147.935 -90)
		(descr "Resistor SMD 0201")
		(tags "resistor SMD 0201")
		(property "Reference" "R250"
			(at 6.495 -0.28 270)
			(layer "F.SilkS")
			(effects
				(font
					(size 0.7 0.7)
					(thickness 0.15)
				)
				(justify left bottom)
			)
		)
		(property "Value" "R_0R_0201"
			(at 0 1.25 270)
			(layer "F.Fab")
			(effects
				(font
					(size 0.7 0.7)
					(thickness 0.15)
				)
				(justify left bottom)
			)
		)
		(property "Datasheet" "https://www.bourns.com/docs/product-datasheets/cr.pdf"
			(at 0 0 270)
			(layer "F.Fab")
			(hide yes)
			(effects
				(font
					(size 1.27 1.27)
					(thickness 0.15)
				)
			)
		)
		(property "Author" "Antmicro"
			(at 4.635 300.505 0)
			(layer "F.Fab")
			(hide yes)
			(effects
				(font
					(size 1 1)
					(thickness 0.15)
				)
			)
		)
		(property "License" "Apache-2.0"
			(at 4.635 300.505 0)
			(layer "F.Fab")
			(hide yes)
			(effects
				(font
					(size 1 1)
					(thickness 0.15)
				)
			)
		)
		(property "MPN" "CR0201-FX-0R00GLF"
			(at 4.635 300.505 0)
			(layer "F.Fab")
			(hide yes)
			(effects
				(font
					(size 1 1)
					(thickness 0.15)
				)
			)
		)
		(property "Manufacturer" "Bourns"
			(at 4.635 300.505 0)
			(layer "F.Fab")
			(hide yes)
			(effects
				(font
					(size 1 1)
					(thickness 0.15)
				)
			)
		)
		(property "Tolerance" "1%"
			(at 4.635 300.505 0)
			(layer "F.Fab")
			(hide yes)
			(effects
				(font
					(size 1 1)
					(thickness 0.15)
				)
			)
		)
		(property "Val" "0R"
			(at 4.635 300.505 0)
			(layer "F.Fab")
			(hide yes)
			(effects
				(font
					(size 1 1)
					(thickness 0.15)
				)
			)
		)
		(sheetname "KR to SFI #1")
		(sheetfile "kr_sfi.kicad_sch")
		(attr smd dnp)
		(fp_rect
			(start -0.7 -0.35)
			(end 0.7 0.35)
			(stroke
				(width 0.05)
				(type default)
			)
			(fill no)
			(layer "F.CrtYd")
		)
		(fp_rect
			(start -0.3 -0.15)
			(end 0.298 0.148)
			(stroke
				(width 0.15)
				(type solid)
			)
			(fill no)
			(layer "F.Fab")
		)
		(pad "" smd roundrect
			(at -0.346 0 270)
			(size 0.318 0.36)
			(layers "F.Paste")
			(roundrect_rratio 0.25)
			(teardrops
				(best_length_ratio 0.2)
				(max_length 1)
				(best_width_ratio 0.9)
				(max_width 2)
				(curved_edges yes)
				(filter_ratio 0.9)
				(enabled yes)
				(allow_two_segments yes)
				(prefer_zone_connections yes)
			)
		)
		(pad "" smd roundrect
			(at 0.344 0 270)
			(size 0.318 0.36)
			(layers "F.Paste")
			(roundrect_rratio 0.25)
			(teardrops
				(best_length_ratio 0.2)
				(max_length 1)
				(best_width_ratio 0.9)
				(max_width 2)
				(curved_edges yes)
				(filter_ratio 0.9)
				(enabled yes)
				(allow_two_segments yes)
				(prefer_zone_connections yes)
			)
		)
		(pad "1" smd roundrect
			(at -0.32 0 270)
			(size 0.46 0.4)
			(layers "F.Cu" "F.Mask")
			(roundrect_rratio 0.25)
			(net 433 "/2xSFP+/10GKR_SFP0.RX-")
			(pintype "passive")
			(teardrops
				(best_length_ratio 0.2)
				(max_length 1)
				(best_width_ratio 0.9)
				(max_width 2)
				(curved_edges yes)
				(filter_ratio 0.9)
				(enabled yes)
				(allow_two_segments yes)
				(prefer_zone_connections yes)
			)
		)
		(pad "2" smd roundrect
			(at 0.32 0 270)
			(size 0.46 0.4)
			(layers "F.Cu" "F.Mask")
			(roundrect_rratio 0.25)
			(net 967 "/2xSFP+/KR to SFI #1/BYP_RX-")
			(pintype "passive")
			(teardrops
				(best_length_ratio 0.2)
				(max_length 1)
				(best_width_ratio 0.9)
				(max_width 2)
				(curved_edges yes)
				(filter_ratio 0.9)
				(enabled yes)
				(allow_two_segments yes)
				(prefer_zone_connections yes)
			)
		)
	)
	(footprint "antmicro-footprints:R_0201"
		(layer "F.Cu")
		(at 131.41 147.336 -90)
		(descr "Resistor SMD 0201")
		(tags "resistor SMD 0201")
		(property "Reference" "R307"
			(at 4.073 -0.29 270)
			(layer "F.SilkS")
			(effects
				(font
					(size 0.7 0.7)
					(thickness 0.15)
				)
				(justify left bottom)
			)
		)
		(property "Value" "R_0R_0201"
			(at 0 1.25 270)
			(layer "F.Fab")
			(effects
				(font
					(size 0.7 0.7)
					(thickness 0.15)
				)
				(justify left bottom)
			)
		)
		(property "Datasheet" "https://www.bourns.com/docs/product-datasheets/cr.pdf"
			(at 0 0 270)
			(layer "F.Fab")
			(hide yes)
			(effects
				(font
					(size 1.27 1.27)
					(thickness 0.15)
				)
			)
		)
		(property "Author" "Antmicro"
			(at -15.926 278.746 0)
			(layer "F.Fab")
			(hide yes)
			(effects
				(font
					(size 1 1)
					(thickness 0.15)
				)
			)
		)
		(property "License" "Apache-2.0"
			(at -15.926 278.746 0)
			(layer "F.Fab")
			(hide yes)
			(effects
				(font
					(size 1 1)
					(thickness 0.15)
				)
			)
		)
		(property "MPN" "CR0201-FX-0R00GLF"
			(at -15.926 278.746 0)
			(layer "F.Fab")
			(hide yes)
			(effects
				(font
					(size 1 1)
					(thickness 0.15)
				)
			)
		)
		(property "Manufacturer" "Bourns"
			(at -15.926 278.746 0)
			(layer "F.Fab")
			(hide yes)
			(effects
				(font
					(size 1 1)
					(thickness 0.15)
				)
			)
		)
		(property "Tolerance" "1%"
			(at -15.926 278.746 0)
			(layer "F.Fab")
			(hide yes)
			(effects
				(font
					(size 1 1)
					(thickness 0.15)
				)
			)
		)
		(property "Val" "0R"
			(at -15.926 278.746 0)
			(layer "F.Fab")
			(hide yes)
			(effects
				(font
					(size 1 1)
					(thickness 0.15)
				)
			)
		)
		(sheetname "KR to SFI #2")
		(sheetfile "kr_sfi.kicad_sch")
		(attr smd)
		(fp_rect
			(start -0.7 -0.35)
			(end 0.7 0.35)
			(stroke
				(width 0.05)
				(type default)
			)
			(fill no)
			(layer "F.CrtYd")
		)
		(fp_rect
			(start -0.3 -0.15)
			(end 0.298 0.148)
			(stroke
				(width 0.15)
				(type solid)
			)
			(fill no)
			(layer "F.Fab")
		)
		(pad "" smd roundrect
			(at -0.346 0 270)
			(size 0.318 0.36)
			(layers "F.Paste")
			(roundrect_rratio 0.25)
			(teardrops
				(best_length_ratio 0.2)
				(max_length 1)
				(best_width_ratio 0.9)
				(max_width 2)
				(curved_edges yes)
				(filter_ratio 0.9)
				(enabled yes)
				(allow_two_segments yes)
				(prefer_zone_connections yes)
			)
		)
		(pad "" smd roundrect
			(at 0.344 0 270)
			(size 0.318 0.36)
			(layers "F.Paste")
			(roundrect_rratio 0.25)
			(teardrops
				(best_length_ratio 0.2)
				(max_length 1)
				(best_width_ratio 0.9)
				(max_width 2)
				(curved_edges yes)
				(filter_ratio 0.9)
				(enabled yes)
				(allow_two_segments yes)
				(prefer_zone_connections yes)
			)
		)
		(pad "1" smd roundrect
			(at -0.32 0 270)
			(size 0.46 0.4)
			(layers "F.Cu" "F.Mask")
			(roundrect_rratio 0.25)
			(net 950 "/2xSFP+/KR to SFI #2/SFI_R.RX+")
			(pintype "passive")
			(teardrops
				(best_length_ratio 0.2)
				(max_length 1)
				(best_width_ratio 0.9)
				(max_width 2)
				(curved_edges yes)
				(filter_ratio 0.9)
				(enabled yes)
				(allow_two_segments yes)
				(prefer_zone_connections yes)
			)
		)
		(pad "2" smd roundrect
			(at 0.32 0 270)
			(size 0.46 0.4)
			(layers "F.Cu" "F.Mask")
			(roundrect_rratio 0.25)
			(net 878 "/2xSFP+/SFI1.RX+")
			(pintype "passive")
			(teardrops
				(best_length_ratio 0.2)
				(max_length 1)
				(best_width_ratio 0.9)
				(max_width 2)
				(curved_edges yes)
				(filter_ratio 0.9)
				(enabled yes)
				(allow_two_segments yes)
				(prefer_zone_connections yes)
			)
		)
	)
	(footprint "antmicro-footprints:TP_SMD_0.75mm"
		(layer "F.Cu")
		(at 129.74 128.71)
		(property "Reference" "TP85"
			(at 0.51 -3.3 90)
			(layer "F.SilkS")
			(effects
				(font
					(size 0.7 0.7)
					(thickness 0.15)
				)
				(justify left bottom)
			)
		)
		(property "Value" "TP_0.75mm_SMD"
			(at 0 1.2 0)
			(layer "F.Fab")
			(effects
				(font
					(size 0.7 0.7)
					(thickness 0.15)
				)
				(justify left bottom)
			)
		)
		(property "Author" "Antmicro"
			(at 0 0 0)
			(layer "F.Fab")
			(hide yes)
			(effects
				(font
					(size 1 1)
					(thickness 0.15)
				)
			)
		)
		(property "License" "Apache-2.0"
			(at 0 0 0)
			(layer "F.Fab")
			(hide yes)
			(effects
				(font
					(size 1 1)
					(thickness 0.15)
				)
			)
		)
		(property "MPN" ""
			(at 0 0 0)
			(layer "F.Fab")
			(hide yes)
			(effects
				(font
					(size 1 1)
					(thickness 0.15)
				)
			)
		)
		(property "Manufacturer" ""
			(at 0 0 0)
			(layer "F.Fab")
			(hide yes)
			(effects
				(font
					(size 1 1)
					(thickness 0.15)
				)
			)
		)
		(property "Public" "False"
			(at 0 0 0)
			(layer "F.Fab")
			(hide yes)
			(effects
				(font
					(size 1 1)
					(thickness 0.15)
				)
			)
		)
		(sheetname "KR to SFI #2")
		(sheetfile "kr_sfi.kicad_sch")
		(attr exclude_from_pos_files exclude_from_bom)
		(fp_circle
			(center 0 0)
			(end 0.475 0)
			(stroke
				(width 0.05)
				(type default)
			)
			(fill no)
			(layer "F.CrtYd")
		)
		(pad "1" smd circle
			(at 0 0)
			(size 0.75 0.75)
			(layers "F.Cu" "F.Mask")
			(net 748 "Net-(U45C-AMUXA)")
			(pinfunction "1")
			(pintype "passive")
			(teardrops
				(best_length_ratio 0.4)
				(max_length 1)
				(best_width_ratio 0.9)
				(max_width 2)
				(curved_edges yes)
				(filter_ratio 0.9)
				(enabled yes)
				(allow_two_segments yes)
				(prefer_zone_connections yes)
			)
		)
	)
	(footprint "antmicro-footprints:C_0603_1608Metric"
		(layer "F.Cu")
		(at 226.7 159.9)
		(descr "Capacitor SMD 0603")
		(tags "capacitor 0603")
		(property "Reference" "C93"
			(at -3.49 -0.4 0)
			(layer "F.SilkS")
			(effects
				(font
					(size 0.7 0.7)
					(thickness 0.15)
				)
				(justify left top)
			)
		)
		(property "Value" "C_22u_16V_0603"
			(at 1.79743 -50.894712 0)
			(layer "F.Fab")
			(hide yes)
			(effects
				(font
					(size 0.7 0.7)
					(thickness 0.15)
				)
				(justify left top)
			)
		)
		(property "Datasheet" "https://product.samsungsem.com/mlcc/CL10A226MO7JZN.do"
			(at 0 0 0)
			(layer "F.Fab")
			(hide yes)
			(effects
				(font
					(size 1.27 1.27)
					(thickness 0.15)
				)
			)
		)
		(property "Author" "Antmicro"
			(at 359.1 320.92 0)
			(layer "F.Fab")
			(hide yes)
			(effects
				(font
					(size 1 1)
					(thickness 0.15)
				)
			)
		)
		(property "Dielectric" ""
			(at 359.1 320.92 0)
			(layer "F.Fab")
			(hide yes)
			(effects
				(font
					(size 1 1)
					(thickness 0.15)
				)
			)
		)
		(property "License" "Apache-2.0"
			(at 359.1 320.92 0)
			(layer "F.Fab")
			(hide yes)
			(effects
				(font
					(size 1 1)
					(thickness 0.15)
				)
			)
		)
		(property "MPN" "CL10A226MO7JZNC"
			(at 359.1 320.92 0)
			(layer "F.Fab")
			(hide yes)
			(effects
				(font
					(size 1 1)
					(thickness 0.15)
				)
			)
		)
		(property "Manufacturer" "Samsung Electro-Mechanics"
			(at 359.1 320.92 0)
			(layer "F.Fab")
			(hide yes)
			(effects
				(font
					(size 1 1)
					(thickness 0.15)
				)
			)
		)
		(property "Public" "False"
			(at 359.1 320.92 0)
			(layer "F.Fab")
			(hide yes)
			(effects
				(font
					(size 1 1)
					(thickness 0.15)
				)
			)
		)
		(property "Val" "22u"
			(at 359.1 320.92 0)
			(layer "F.Fab")
			(hide yes)
			(effects
				(font
					(size 1 1)
					(thickness 0.15)
				)
			)
		)
		(property "Voltage" "16V"
			(at 359.1 320.92 0)
			(layer "F.Fab")
			(hide yes)
			(effects
				(font
					(size 1 1)
					(thickness 0.15)
				)
			)
		)
		(sheetname "Com Express 7 MGMT")
		(sheetfile "com_express_7_mgmt.kicad_sch")
		(attr smd)
		(fp_line
			(start -0.15 -0.4)
			(end 0.15 -0.4)
			(stroke
				(width 0.15)
				(type solid)
			)
			(layer "F.SilkS")
		)
		(fp_line
			(start -0.15 0.4)
			(end 0.15 0.4)
			(stroke
				(width 0.15)
				(type solid)
			)
			(layer "F.SilkS")
		)
		(fp_rect
			(start -1.25 -0.65)
			(end 1.25 0.65)
			(stroke
				(width 0.05)
				(type solid)
			)
			(fill no)
			(layer "F.CrtYd")
		)
		(fp_rect
			(start -0.8 -0.4)
			(end 0.8 0.4)
			(stroke
				(width 0.15)
				(type solid)
			)
			(fill no)
			(layer "F.Fab")
		)
		(pad "1" smd roundrect
			(at -0.7 0)
			(size 0.8 1)
			(layers "F.Cu" "F.Mask" "F.Paste")
			(roundrect_rratio 0.2)
			(net 1 "GND")
			(pintype "passive")
			(teardrops
				(best_length_ratio 0.2)
				(max_length 1)
				(best_width_ratio 0.9)
				(max_width 2)
				(curved_edges yes)
				(filter_ratio 0.9)
				(enabled yes)
				(allow_two_segments yes)
				(prefer_zone_connections yes)
			)
		)
		(pad "2" smd roundrect
			(at 0.7 0)
			(size 0.8 1)
			(layers "F.Cu" "F.Mask" "F.Paste")
			(roundrect_rratio 0.2)
			(net 65 "+12V")
			(pintype "passive")
			(teardrops
				(best_length_ratio 0.2)
				(max_length 1)
				(best_width_ratio 0.9)
				(max_width 2)
				(curved_edges yes)
				(filter_ratio 0.9)
				(enabled yes)
				(allow_two_segments yes)
				(prefer_zone_connections yes)
			)
		)
	)
	(footprint "antmicro-footprints:C_Pol_EIA-B"
		(layer "F.Cu")
		(at 110.8 91.81 -90)
		(property "Reference" "C4"
			(at 2.35 -0.45 90)
			(layer "F.SilkS")
			(effects
				(font
					(size 0.7 0.7)
					(thickness 0.15)
				)
				(justify right bottom)
			)
		)
		(property "Value" "C_Pol_100u_10V_KEMET-T520-B"
			(at 0 2.85 90)
			(layer "F.Fab")
			(effects
				(font
					(size 0.7 0.7)
					(thickness 0.15)
				)
				(justify right bottom)
			)
		)
		(property "Datasheet" "https://www.kemet.com/en/us/capacitors/product/T520B107M010ATE070.html"
			(at 0 0 270)
			(layer "F.Fab")
			(hide yes)
			(effects
				(font
					(size 1.27 1.27)
					(thickness 0.15)
				)
			)
		)
		(property "Author" "Antmicro"
			(at 18.99 202.61 0)
			(layer "F.Fab")
			(hide yes)
			(effects
				(font
					(size 1 1)
					(thickness 0.15)
				)
			)
		)
		(property "Dielectric" "template_dielectric"
			(at 18.99 202.61 0)
			(layer "F.Fab")
			(hide yes)
			(effects
				(font
					(size 1 1)
					(thickness 0.15)
				)
			)
		)
		(property "License" "Apache-2.0"
			(at 18.99 202.61 0)
			(layer "F.Fab")
			(hide yes)
			(effects
				(font
					(size 1 1)
					(thickness 0.15)
				)
			)
		)
		(property "MPN" "T520B107M010ATE070"
			(at 18.99 202.61 0)
			(layer "F.Fab")
			(hide yes)
			(effects
				(font
					(size 1 1)
					(thickness 0.15)
				)
			)
		)
		(property "Manufacturer" "KEMET"
			(at 18.99 202.61 0)
			(layer "F.Fab")
			(hide yes)
			(effects
				(font
					(size 1 1)
					(thickness 0.15)
				)
			)
		)
		(property "Public" "False"
			(at 18.99 202.61 0)
			(layer "F.Fab")
			(hide yes)
			(effects
				(font
					(size 1 1)
					(thickness 0.15)
				)
			)
		)
		(property "Val" "100u"
			(at 18.99 202.61 0)
			(layer "F.Fab")
			(hide yes)
			(effects
				(font
					(size 1 1)
					(thickness 0.15)
				)
			)
		)
		(property "Voltage" "10V"
			(at 18.99 202.61 0)
			(layer "F.Fab")
			(hide yes)
			(effects
				(font
					(size 1 1)
					(thickness 0.15)
				)
			)
		)
		(sheetname "2xUSB3.0+RJ45")
		(sheetfile "usb3+rj45.kicad_sch")
		(attr smd)
		(fp_line
			(start 1.8 1.6)
			(end -1.8 1.6)
			(stroke
				(width 0.15)
				(type solid)
			)
			(layer "F.SilkS")
		)
		(fp_line
			(start -1.8 1.3)
			(end -1.8 1.6)
			(stroke
				(width 0.15)
				(type solid)
			)
			(layer "F.SilkS")
		)
		(fp_line
			(start 1.8 1.3)
			(end 1.8 1.6)
			(stroke
				(width 0.15)
				(type solid)
			)
			(layer "F.SilkS")
		)
		(fp_line
			(start -1.8 -1.3)
			(end -1.8 -1.6)
			(stroke
				(width 0.15)
				(type solid)
			)
			(layer "F.SilkS")
		)
		(fp_line
			(start 1.8 -1.3)
			(end 1.8 -1.6)
			(stroke
				(width 0.15)
				(type solid)
			)
			(layer "F.SilkS")
		)
		(fp_line
			(start -2.325 -1.475)
			(end -2.325 -1.878)
			(stroke
				(width 0.15)
				(type solid)
			)
			(layer "F.SilkS")
		)
		(fp_line
			(start -1.8 -1.6)
			(end 1.8 -1.6)
			(stroke
				(width 0.15)
				(type solid)
			)
			(layer "F.SilkS")
		)
		(fp_line
			(start -2.521 -1.676)
			(end -2.123 -1.676)
			(stroke
				(width 0.15)
				(type solid)
			)
			(layer "F.SilkS")
		)
		(fp_line
			(start 1.96 1.75)
			(end -1.97 1.75)
			(stroke
				(width 0.05)
				(type solid)
			)
			(layer "F.CrtYd")
		)
		(fp_line
			(start -1.97 1.35)
			(end -1.97 1.75)
			(stroke
				(width 0.05)
				(type solid)
			)
			(layer "F.CrtYd")
		)
		(fp_line
			(start -1.97 1.35)
			(end -2.41 1.35)
			(stroke
				(width 0.05)
				(type solid)
			)
			(layer "F.CrtYd")
		)
		(fp_line
			(start 1.96 1.35)
			(end 1.96 1.75)
			(stroke
				(width 0.05)
				(type solid)
			)
			(layer "F.CrtYd")
		)
		(fp_line
			(start 2.4 1.35)
			(end 1.96 1.35)
			(stroke
				(width 0.05)
				(type solid)
			)
			(layer "F.CrtYd")
		)
		(fp_line
			(start -2.411 -1.35)
			(end -2.41 1.35)
			(stroke
				(width 0.05)
				(type solid)
			)
			(layer "F.CrtYd")
		)
		(fp_line
			(start -1.97 -1.35)
			(end -2.41 -1.35)
			(stroke
				(width 0.05)
				(type solid)
			)
			(layer "F.CrtYd")
		)
		(fp_line
			(start 2.399 -1.35)
			(end 2.4 1.35)
			(stroke
				(width 0.05)
				(type solid)
			)
			(layer "F.CrtYd")
		)
		(fp_line
			(start 2.399 -1.35)
			(end 1.959 -1.35)
			(stroke
				(width 0.05)
				(type solid)
			)
			(layer "F.CrtYd")
		)
		(fp_line
			(start -1.97 -1.75)
			(end -1.97 -1.35)
			(stroke
				(width 0.05)
				(type solid)
			)
			(layer "F.CrtYd")
		)
		(fp_line
			(start 1.959 -1.75)
			(end 1.959 -1.35)
			(stroke
				(width 0.05)
				(type solid)
			)
			(layer "F.CrtYd")
		)
		(fp_line
			(start 1.959 -1.75)
			(end -1.97 -1.75)
			(stroke
				(width 0.05)
				(type solid)
			)
			(layer "F.CrtYd")
		)
		(fp_line
			(start -1.7 1.324)
			(end -1.551 1.475)
			(stroke
				(width 0.15)
				(type solid)
			)
			(layer "F.Fab")
		)
		(fp_rect
			(start -1.72 -1.5)
			(end 1.719 1.499)
			(stroke
				(width 0.15)
				(type solid)
			)
			(fill no)
			(layer "F.Fab")
		)
		(pad "1" smd roundrect
			(at -1.551 0 270)
			(size 1.2 2.2)
			(layers "F.Cu" "F.Mask" "F.Paste")
			(roundrect_rratio 0.1)
			(net 43 "/2xUSB3.0+RJ45/P2_VBUS")
			(pintype "passive")
			(teardrops
				(best_length_ratio 0.2)
				(max_length 1)
				(best_width_ratio 0.9)
				(max_width 2)
				(curved_edges yes)
				(filter_ratio 0.9)
				(enabled yes)
				(allow_two_segments yes)
				(prefer_zone_connections yes)
			)
		)
		(pad "2" smd roundrect
			(at 1.55 0 270)
			(size 1.2 2.2)
			(layers "F.Cu" "F.Mask" "F.Paste")
			(roundrect_rratio 0.1)
			(net 1 "GND")
			(pintype "passive")
			(teardrops
				(best_length_ratio 0.2)
				(max_length 1)
				(best_width_ratio 0.9)
				(max_width 2)
				(curved_edges yes)
				(filter_ratio 0.9)
				(enabled yes)
				(allow_two_segments yes)
				(prefer_zone_connections yes)
			)
		)
	)
	(footprint "antmicro-footprints:TP_SMD_0.75mm"
		(layer "F.Cu")
		(at 136.89 129.56)
		(property "Reference" "TP87"
			(at 0.46 -1.25 90)
			(layer "F.SilkS")
			(effects
				(font
					(size 0.7 0.7)
					(thickness 0.15)
				)
				(justify left bottom)
			)
		)
		(property "Value" "TP_0.75mm_SMD"
			(at 0 1.2 0)
			(layer "F.Fab")
			(effects
				(font
					(size 0.7 0.7)
					(thickness 0.15)
				)
				(justify left bottom)
			)
		)
		(property "Author" "Antmicro"
			(at 0 0 0)
			(layer "F.Fab")
			(hide yes)
			(effects
				(font
					(size 1 1)
					(thickness 0.15)
				)
			)
		)
		(property "License" "Apache-2.0"
			(at 0 0 0)
			(layer "F.Fab")
			(hide yes)
			(effects
				(font
					(size 1 1)
					(thickness 0.15)
				)
			)
		)
		(property "MPN" ""
			(at 0 0 0)
			(layer "F.Fab")
			(hide yes)
			(effects
				(font
					(size 1 1)
					(thickness 0.15)
				)
			)
		)
		(property "Manufacturer" ""
			(at 0 0 0)
			(layer "F.Fab")
			(hide yes)
			(effects
				(font
					(size 1 1)
					(thickness 0.15)
				)
			)
		)
		(property "Public" "False"
			(at 0 0 0)
			(layer "F.Fab")
			(hide yes)
			(effects
				(font
					(size 1 1)
					(thickness 0.15)
				)
			)
		)
		(sheetname "KR to SFI #2")
		(sheetfile "kr_sfi.kicad_sch")
		(attr exclude_from_pos_files exclude_from_bom)
		(fp_circle
			(center 0 0)
			(end 0.475 0)
			(stroke
				(width 0.05)
				(type default)
			)
			(fill no)
			(layer "F.CrtYd")
		)
		(pad "1" smd circle
			(at 0 0)
			(size 0.75 0.75)
			(layers "F.Cu" "F.Mask")
			(net 750 "Net-(U45C-CLKOUTA+)")
			(pinfunction "1")
			(pintype "passive")
			(teardrops
				(best_length_ratio 0.4)
				(max_length 1)
				(best_width_ratio 0.9)
				(max_width 2)
				(curved_edges yes)
				(filter_ratio 0.9)
				(enabled yes)
				(allow_two_segments yes)
				(prefer_zone_connections yes)
			)
		)
	)
	(footprint "antmicro-footprints:R_0402_1005Metric"
		(layer "F.Cu")
		(at 130.119 117.85 180)
		(descr "Resistor SMD 0402")
		(tags "resistor SMD 0402")
		(property "Reference" "R20"
			(at 0.781 0.42 0)
			(layer "F.SilkS")
			(effects
				(font
					(size 0.7 0.7)
					(thickness 0.15)
				)
				(justify right top)
			)
		)
		(property "Value" "R_0R_0402"
			(at -1.011843 1.772046 0)
			(layer "F.Fab")
			(effects
				(font
					(size 0.7 0.7)
					(thickness 0.15)
				)
				(justify right top)
			)
		)
		(property "Datasheet" "https://industrial.panasonic.com/cdbs/www-data/pdf/RDA0000/AOA0000C301.pdf"
			(at 0 0 0)
			(layer "F.Fab")
			(hide yes)
			(effects
				(font
					(size 1.27 1.27)
					(thickness 0.15)
				)
			)
		)
		(property "Author" "Antmicro"
			(at 357.371 -61.189 90)
			(layer "F.Fab")
			(hide yes)
			(effects
				(font
					(size 1 1)
					(thickness 0.15)
				)
			)
		)
		(property "Current" "1A"
			(at 357.371 -61.189 90)
			(layer "F.Fab")
			(hide yes)
			(effects
				(font
					(size 1 1)
					(thickness 0.15)
				)
			)
		)
		(property "License" "Apache-2.0"
			(at 357.371 -61.189 90)
			(layer "F.Fab")
			(hide yes)
			(effects
				(font
					(size 1 1)
					(thickness 0.15)
				)
			)
		)
		(property "MPN" "ERJ2GE0R00X"
			(at 357.371 -61.189 90)
			(layer "F.Fab")
			(hide yes)
			(effects
				(font
					(size 1 1)
					(thickness 0.15)
				)
			)
		)
		(property "Manufacturer" "Panasonic"
			(at 357.371 -61.189 90)
			(layer "F.Fab")
			(hide yes)
			(effects
				(font
					(size 1 1)
					(thickness 0.15)
				)
			)
		)
		(property "Public" "False"
			(at 357.371 -61.189 90)
			(layer "F.Fab")
			(hide yes)
			(effects
				(font
					(size 1 1)
					(thickness 0.15)
				)
			)
		)
		(property "Tolerance" ""
			(at 357.371 -61.189 90)
			(layer "F.Fab")
			(hide yes)
			(effects
				(font
					(size 1 1)
					(thickness 0.15)
				)
			)
		)
		(property "Val" "0R"
			(at 357.371 -61.189 90)
			(layer "F.Fab")
			(hide yes)
			(effects
				(font
					(size 1 1)
					(thickness 0.15)
				)
			)
		)
		(sheetname "2xUSB3.0+RJ45")
		(sheetfile "usb3+rj45.kicad_sch")
		(attr smd)
		(fp_rect
			(start -0.925 -0.47)
			(end 0.925 0.47)
			(stroke
				(width 0.05)
				(type default)
			)
			(fill no)
			(layer "F.CrtYd")
		)
		(fp_rect
			(start -0.5 -0.25)
			(end 0.5 0.25)
			(stroke
				(width 0.15)
				(type solid)
			)
			(fill no)
			(layer "F.Fab")
		)
		(pad "1" smd roundrect
			(at -0.48 0 180)
			(size 0.59 0.64)
			(layers "F.Cu" "F.Mask" "F.Paste")
			(roundrect_rratio 0.25)
			(net 313 "/2xUSB3.0+RJ45/USB_1.D+")
			(pintype "passive")
			(teardrops
				(best_length_ratio 0.2)
				(max_length 1)
				(best_width_ratio 0.9)
				(max_width 2)
				(curved_edges yes)
				(filter_ratio 0.9)
				(enabled yes)
				(allow_two_segments yes)
				(prefer_zone_connections yes)
			)
		)
		(pad "2" smd roundrect
			(at 0.48 0 180)
			(size 0.59 0.64)
			(layers "F.Cu" "F.Mask" "F.Paste")
			(roundrect_rratio 0.25)
			(net 124 "/2xUSB3.0+RJ45/P1_D+")
			(pintype "passive")
			(teardrops
				(best_length_ratio 0.2)
				(max_length 1)
				(best_width_ratio 0.9)
				(max_width 2)
				(curved_edges yes)
				(filter_ratio 0.9)
				(enabled yes)
				(allow_two_segments yes)
				(prefer_zone_connections yes)
			)
		)
	)
	(footprint "antmicro-footprints:Mech_SolidRun_LX2160A-CEX7"
		(layer "F.Cu")
		(at 157.93 171.81 90)
		(property "Reference" "A3"
			(at 0 -0.5 90)
			(unlocked yes)
			(layer "F.SilkS")
			(hide yes)
			(effects
				(font
					(size 0.7 0.7)
					(thickness 0.15)
				)
				(justify left bottom)
			)
		)
		(property "Value" "Mech_SolidRun_LX2160A-CEX7"
			(at 0 1 90)
			(unlocked yes)
			(layer "F.Fab")
			(effects
				(font
					(size 0.7 0.7)
					(thickness 0.15)
				)
				(justify left bottom)
			)
		)
		(property "Datasheet" "https://www.solid-run.com/embedded-networking/nxp-lx2160a-family/cex7-lx2160/#documentation"
			(at 0 0 90)
			(layer "F.Fab")
			(hide yes)
			(effects
				(font
					(size 1.27 1.27)
					(thickness 0.15)
				)
			)
		)
		(property "Author" "Antmicro"
			(at 329.74 13.88 0)
			(layer "F.Fab")
			(hide yes)
			(effects
				(font
					(size 1 1)
					(thickness 0.15)
				)
			)
		)
		(property "Displayed name" "LX2160A-CEX7"
			(at 329.74 13.88 0)
			(layer "F.Fab")
			(hide yes)
			(effects
				(font
					(size 1 1)
					(thickness 0.15)
				)
			)
		)
		(property "License" "Apache-2.0"
			(at 329.74 13.88 0)
			(layer "F.Fab")
			(hide yes)
			(effects
				(font
					(size 1 1)
					(thickness 0.15)
				)
			)
		)
		(property "MPN" "SRX2160S01D00GE064V21C0"
			(at 329.74 13.88 0)
			(layer "F.Fab")
			(hide yes)
			(effects
				(font
					(size 1 1)
					(thickness 0.15)
				)
			)
		)
		(property "Manufacturer" "SolidRun"
			(at 329.74 13.88 0)
			(layer "F.Fab")
			(hide yes)
			(effects
				(font
					(size 1 1)
					(thickness 0.15)
				)
			)
		)
		(sheetname "Com Express 7 Interfaces")
		(sheetfile "com_express_7_interfaces.kicad_sch")
		(attr through_hole exclude_from_pos_files exclude_from_bom allow_missing_courtyard
			dnp
		)
		(fp_rect
			(start 0 0)
			(end 95 125)
			(stroke
				(width 0.15)
				(type solid)
			)
			(fill no)
			(layer "F.Fab")
		)
		(fp_circle
			(center 91 4)
			(end 94 4)
			(stroke
				(width 0.1)
				(type default)
			)
			(fill no)
			(layer "F.Fab")
		)
		(fp_circle
			(center 4 4)
			(end 7 4)
			(stroke
				(width 0.1)
				(type default)
			)
			(fill no)
			(layer "F.Fab")
		)
		(fp_circle
			(center 18 16.5)
			(end 19 16.5)
			(stroke
				(width 0.1)
				(type default)
			)
			(fill no)
			(layer "F.Fab")
		)
		(fp_circle
			(center 6 16.5)
			(end 7 16.5)
			(stroke
				(width 0.1)
				(type default)
			)
			(fill no)
			(layer "F.Fab")
		)
		(fp_circle
			(center 4 80)
			(end 7 80)
			(stroke
				(width 0.1)
				(type default)
			)
			(fill no)
			(layer "F.Fab")
		)
		(fp_circle
			(center 91 121)
			(end 94 121)
			(stroke
				(width 0.1)
				(type default)
			)
			(fill no)
			(layer "F.Fab")
		)
		(fp_circle
			(center 4 121)
			(end 7 121)
			(stroke
				(width 0.1)
				(type default)
			)
			(fill no)
			(layer "F.Fab")
		)
	)
	(footprint "antmicro-footprints:R_0402_1005Metric"
		(layer "F.Cu")
		(at 261.54 83.349999 90)
		(descr "Resistor SMD 0402")
		(tags "resistor SMD 0402")
		(property "Reference" "R155"
			(at -1.460001 1.36 90)
			(layer "F.SilkS")
			(effects
				(font
					(size 0.7 0.7)
					(thickness 0.15)
				)
				(justify left bottom)
			)
		)
		(property "Value" "R_10k_0402"
			(at -1.011843 1.772047 90)
			(layer "F.Fab")
			(effects
				(font
					(size 0.7 0.7)
					(thickness 0.15)
				)
				(justify left bottom)
			)
		)
		(property "Datasheet" "https://www.bourns.com/docs/product-datasheets/cr.pdf"
			(at 0 0 90)
			(layer "F.Fab")
			(hide yes)
			(effects
				(font
					(size 1.27 1.27)
					(thickness 0.15)
				)
			)
		)
		(property "Author" "Antmicro"
			(at 344.889999 -178.190001 0)
			(layer "F.Fab")
			(hide yes)
			(effects
				(font
					(size 1 1)
					(thickness 0.15)
				)
			)
		)
		(property "License" "Apache-2.0"
			(at 344.889999 -178.190001 0)
			(layer "F.Fab")
			(hide yes)
			(effects
				(font
					(size 1 1)
					(thickness 0.15)
				)
			)
		)
		(property "MPN" "CR0402-FX-1002GLF"
			(at 344.889999 -178.190001 0)
			(layer "F.Fab")
			(hide yes)
			(effects
				(font
					(size 1 1)
					(thickness 0.15)
				)
			)
		)
		(property "Manufacturer" "Bourns"
			(at 344.889999 -178.190001 0)
			(layer "F.Fab")
			(hide yes)
			(effects
				(font
					(size 1 1)
					(thickness 0.15)
				)
			)
		)
		(property "Public" "False"
			(at 344.889999 -178.190001 0)
			(layer "F.Fab")
			(hide yes)
			(effects
				(font
					(size 1 1)
					(thickness 0.15)
				)
			)
		)
		(property "Tolerance" "1%"
			(at 344.889999 -178.190001 0)
			(layer "F.Fab")
			(hide yes)
			(effects
				(font
					(size 1 1)
					(thickness 0.15)
				)
			)
		)
		(property "Val" "10k"
			(at 344.889999 -178.190001 0)
			(layer "F.Fab")
			(hide yes)
			(effects
				(font
					(size 1 1)
					(thickness 0.15)
				)
			)
		)
		(sheetname "Misc")
		(sheetfile "misc.kicad_sch")
		(attr smd)
		(fp_rect
			(start -0.925 -0.47)
			(end 0.925 0.47)
			(stroke
				(width 0.05)
				(type default)
			)
			(fill no)
			(layer "F.CrtYd")
		)
		(fp_rect
			(start -0.5 -0.25)
			(end 0.5 0.25)
			(stroke
				(width 0.15)
				(type solid)
			)
			(fill no)
			(layer "F.Fab")
		)
		(pad "1" smd roundrect
			(at -0.48 0 90)
			(size 0.59 0.64)
			(layers "F.Cu" "F.Mask" "F.Paste")
			(roundrect_rratio 0.25)
			(net 596 "/Misc/PWM2")
			(pintype "passive")
			(teardrops
				(best_length_ratio 0.2)
				(max_length 1)
				(best_width_ratio 0.9)
				(max_width 2)
				(curved_edges yes)
				(filter_ratio 0.9)
				(enabled yes)
				(allow_two_segments yes)
				(prefer_zone_connections yes)
			)
		)
		(pad "2" smd roundrect
			(at 0.48 0 90)
			(size 0.59 0.64)
			(layers "F.Cu" "F.Mask" "F.Paste")
			(roundrect_rratio 0.25)
			(net 2 "+3V3")
			(pintype "passive")
			(teardrops
				(best_length_ratio 0.2)
				(max_length 1)
				(best_width_ratio 0.9)
				(max_width 2)
				(curved_edges yes)
				(filter_ratio 0.9)
				(enabled yes)
				(allow_two_segments yes)
				(prefer_zone_connections yes)
			)
		)
	)
	(footprint "antmicro-footprints:C_0402_1005Metric"
		(layer "F.Cu")
		(at 120.4 148.421 -90)
		(descr "Capacitor SMD 0402")
		(tags "capacitor SMD 0402")
		(property "Reference" "C127"
			(at -12.611 -0.6 90)
			(layer "F.SilkS")
			(effects
				(font
					(size 0.7 0.7)
					(thickness 0.15)
				)
				(justify right bottom)
			)
		)
		(property "Value" "C_100n_0402"
			(at -1.022927 2.155213 90)
			(layer "F.Fab")
			(effects
				(font
					(size 0.7 0.7)
					(thickness 0.15)
				)
				(justify right bottom)
			)
		)
		(property "Datasheet" "https://www.murata.com/products/productdetail?partno=GRM155R61H104KE14%23"
			(at 0 0 270)
			(layer "F.Fab")
			(hide yes)
			(effects
				(font
					(size 1.27 1.27)
					(thickness 0.15)
				)
			)
		)
		(property "Author" "Antmicro"
			(at -28.021 268.821 0)
			(layer "F.Fab")
			(hide yes)
			(effects
				(font
					(size 1 1)
					(thickness 0.15)
				)
			)
		)
		(property "Dielectric" "X5R"
			(at -28.021 268.821 0)
			(layer "F.Fab")
			(hide yes)
			(effects
				(font
					(size 1 1)
					(thickness 0.15)
				)
			)
		)
		(property "License" "Apache-2.0"
			(at -28.021 268.821 0)
			(layer "F.Fab")
			(hide yes)
			(effects
				(font
					(size 1 1)
					(thickness 0.15)
				)
			)
		)
		(property "MPN" "GRM155R61H104KE14D"
			(at -28.021 268.821 0)
			(layer "F.Fab")
			(hide yes)
			(effects
				(font
					(size 1 1)
					(thickness 0.15)
				)
			)
		)
		(property "Manufacturer" "Murata"
			(at -28.021 268.821 0)
			(layer "F.Fab")
			(hide yes)
			(effects
				(font
					(size 1 1)
					(thickness 0.15)
				)
			)
		)
		(property "Public" "False"
			(at -28.021 268.821 0)
			(layer "F.Fab")
			(hide yes)
			(effects
				(font
					(size 1 1)
					(thickness 0.15)
				)
			)
		)
		(property "Val" "100n"
			(at -28.021 268.821 0)
			(layer "F.Fab")
			(hide yes)
			(effects
				(font
					(size 1 1)
					(thickness 0.15)
				)
			)
		)
		(property "Voltage" "50V"
			(at -28.021 268.821 0)
			(layer "F.Fab")
			(hide yes)
			(effects
				(font
					(size 1 1)
					(thickness 0.15)
				)
			)
		)
		(sheetname "PCIe redriver")
		(sheetfile "pcie_redriver.kicad_sch")
		(attr smd)
		(fp_rect
			(start -0.925 -0.47)
			(end 0.925 0.47)
			(stroke
				(width 0.05)
				(type default)
			)
			(fill no)
			(layer "F.CrtYd")
		)
		(fp_line
			(start -0.494 0.248)
			(end -0.494 -0.25)
			(stroke
				(width 0.15)
				(type solid)
			)
			(layer "F.Fab")
		)
		(fp_line
			(start 0.504 0.248)
			(end -0.494 0.248)
			(stroke
				(width 0.15)
				(type solid)
			)
			(layer "F.Fab")
		)
		(fp_line
			(start -0.494 -0.25)
			(end 0.504 -0.25)
			(stroke
				(width 0.15)
				(type solid)
			)
			(layer "F.Fab")
		)
		(fp_line
			(start 0.504 -0.25)
			(end 0.504 0.248)
			(stroke
				(width 0.15)
				(type solid)
			)
			(layer "F.Fab")
		)
		(pad "1" smd roundrect
			(at -0.48 0 270)
			(size 0.59 0.64)
			(layers "F.Cu" "F.Mask" "F.Paste")
			(roundrect_rratio 0.25)
			(net 1 "GND")
			(pintype "passive")
			(teardrops
				(best_length_ratio 0.2)
				(max_length 1)
				(best_width_ratio 0.9)
				(max_width 2)
				(curved_edges yes)
				(filter_ratio 0.9)
				(enabled yes)
				(allow_two_segments yes)
				(prefer_zone_connections yes)
			)
		)
		(pad "2" smd roundrect
			(at 0.48 0 270)
			(size 0.59 0.64)
			(layers "F.Cu" "F.Mask" "F.Paste")
			(roundrect_rratio 0.25)
			(net 2 "+3V3")
			(pintype "passive")
			(teardrops
				(best_length_ratio 0.2)
				(max_length 1)
				(best_width_ratio 0.9)
				(max_width 2)
				(curved_edges yes)
				(filter_ratio 0.9)
				(enabled yes)
				(allow_two_segments yes)
				(prefer_zone_connections yes)
			)
		)
	)
	(footprint "antmicro-footprints:Mech_Lightpipe_Bivar_SLP3-300-250-F"
		(layer "F.Cu")
		(at 105.1505 71.051 -90)
		(property "Reference" "H4"
			(at 0.559 -1.5995 270)
			(unlocked yes)
			(layer "F.SilkS")
			(effects
				(font
					(size 0.7 0.7)
					(thickness 0.15)
				)
				(justify left bottom)
			)
		)
		(property "Value" "Lightpipe_Bivar_SLP3-300-250-F"
			(at 0 6.6 270)
			(unlocked yes)
			(layer "F.Fab")
			(effects
				(font
					(size 0.7 0.7)
					(thickness 0.15)
				)
				(justify left bottom)
			)
		)
		(property "Datasheet" "https://www.bivar.com/parts_content/Datasheets/SLP3-XXX-XXX-X.pdf"
			(at 0 0 90)
			(layer "F.Fab")
			(hide yes)
			(effects
				(font
					(size 1.27 1.27)
					(thickness 0.15)
				)
			)
		)
		(property "Manufacturer" "BIVAR"
			(at 0 0 270)
			(unlocked yes)
			(layer "F.Fab")
			(hide yes)
			(effects
				(font
					(size 1 1)
					(thickness 0.15)
				)
			)
		)
		(property "MPN" "SLP3-150-300-F"
			(at 0 0 270)
			(unlocked yes)
			(layer "F.Fab")
			(hide yes)
			(effects
				(font
					(size 1 1)
					(thickness 0.15)
				)
			)
		)
		(property "Author" "Antmicro"
			(at 0 0 270)
			(unlocked yes)
			(layer "F.Fab")
			(hide yes)
			(effects
				(font
					(size 1 1)
					(thickness 0.15)
				)
			)
		)
		(property "License" "Apache-2.0"
			(at 0 0 270)
			(unlocked yes)
			(layer "F.Fab")
			(hide yes)
			(effects
				(font
					(size 1 1)
					(thickness 0.15)
				)
			)
		)
		(sheetname "Misc")
		(sheetfile "misc.kicad_sch")
		(attr through_hole)
		(fp_rect
			(start -1.04 -1.225)
			(end 3.559 5.326)
			(stroke
				(width 0.15)
				(type solid)
			)
			(fill no)
			(layer "F.SilkS")
		)
		(fp_rect
			(start -1.3 4.196)
			(end 3.819 5.596)
			(stroke
				(width 0.05)
				(type solid)
			)
			(fill no)
			(layer "F.CrtYd")
		)
		(fp_rect
			(start -1.301 -1.504)
			(end 3.819 1.196)
			(stroke
				(width 0.05)
				(type solid)
			)
			(fill no)
			(layer "F.CrtYd")
		)
		(fp_line
			(start 0.55 2.5)
			(end 1.25 2.5)
			(stroke
				(width 0.15)
				(type solid)
			)
			(layer "F.Fab")
		)
		(fp_line
			(start 1.25 2.5)
			(end 1.25 3.201)
			(stroke
				(width 0.15)
				(type solid)
			)
			(layer "F.Fab")
		)
		(fp_line
			(start 1.25 2.5)
			(end 1.95 2.5)
			(stroke
				(width 0.15)
				(type solid)
			)
			(layer "F.Fab")
		)
		(fp_line
			(start 1.25 1.8)
			(end 1.25 2.5)
			(stroke
				(width 0.15)
				(type solid)
			)
			(layer "F.Fab")
		)
		(fp_rect
			(start -0.791 1.376)
			(end 3.309 3.625)
			(stroke
				(width 0.15)
				(type solid)
			)
			(fill no)
			(layer "F.Fab")
		)
		(pad "" np_thru_hole circle
			(at 0 0 270)
			(size 1.2 1.2)
			(drill 1.3208)
			(layers "F&B.Cu" "*.Mask")
		)
		(pad "" np_thru_hole circle
			(at 2.5 0 270)
			(size 1.2 1.2)
			(drill 1.3208)
			(layers "F&B.Cu" "*.Mask")
		)
	)
	(footprint "antmicro-footprints:C_0402_1005Metric"
		(layer "F.Cu")
		(at 117.4 148.421 -90)
		(descr "Capacitor SMD 0402")
		(tags "capacitor SMD 0402")
		(property "Reference" "C115"
			(at -12.611 -1.6 90)
			(layer "F.SilkS")
			(effects
				(font
					(size 0.7 0.7)
					(thickness 0.15)
				)
				(justify right bottom)
			)
		)
		(property "Value" "C_100n_0402"
			(at -1.022927 2.155213 90)
			(layer "F.Fab")
			(effects
				(font
					(size 0.7 0.7)
					(thickness 0.15)
				)
				(justify right bottom)
			)
		)
		(property "Datasheet" "https://www.murata.com/products/productdetail?partno=GRM155R61H104KE14%23"
			(at 0 0 270)
			(layer "F.Fab")
			(hide yes)
			(effects
				(font
					(size 1.27 1.27)
					(thickness 0.15)
				)
			)
		)
		(property "Author" "Antmicro"
			(at -31.021 265.821 0)
			(layer "F.Fab")
			(hide yes)
			(effects
				(font
					(size 1 1)
					(thickness 0.15)
				)
			)
		)
		(property "Dielectric" "X5R"
			(at -31.021 265.821 0)
			(layer "F.Fab")
			(hide yes)
			(effects
				(font
					(size 1 1)
					(thickness 0.15)
				)
			)
		)
		(property "License" "Apache-2.0"
			(at -31.021 265.821 0)
			(layer "F.Fab")
			(hide yes)
			(effects
				(font
					(size 1 1)
					(thickness 0.15)
				)
			)
		)
		(property "MPN" "GRM155R61H104KE14D"
			(at -31.021 265.821 0)
			(layer "F.Fab")
			(hide yes)
			(effects
				(font
					(size 1 1)
					(thickness 0.15)
				)
			)
		)
		(property "Manufacturer" "Murata"
			(at -31.021 265.821 0)
			(layer "F.Fab")
			(hide yes)
			(effects
				(font
					(size 1 1)
					(thickness 0.15)
				)
			)
		)
		(property "Public" "False"
			(at -31.021 265.821 0)
			(layer "F.Fab")
			(hide yes)
			(effects
				(font
					(size 1 1)
					(thickness 0.15)
				)
			)
		)
		(property "Val" "100n"
			(at -31.021 265.821 0)
			(layer "F.Fab")
			(hide yes)
			(effects
				(font
					(size 1 1)
					(thickness 0.15)
				)
			)
		)
		(property "Voltage" "50V"
			(at -31.021 265.821 0)
			(layer "F.Fab")
			(hide yes)
			(effects
				(font
					(size 1 1)
					(thickness 0.15)
				)
			)
		)
		(sheetname "PCIe redriver")
		(sheetfile "pcie_redriver.kicad_sch")
		(attr smd)
		(fp_rect
			(start -0.925 -0.47)
			(end 0.925 0.47)
			(stroke
				(width 0.05)
				(type default)
			)
			(fill no)
			(layer "F.CrtYd")
		)
		(fp_line
			(start -0.494 0.248)
			(end -0.494 -0.25)
			(stroke
				(width 0.15)
				(type solid)
			)
			(layer "F.Fab")
		)
		(fp_line
			(start 0.504 0.248)
			(end -0.494 0.248)
			(stroke
				(width 0.15)
				(type solid)
			)
			(layer "F.Fab")
		)
		(fp_line
			(start -0.494 -0.25)
			(end 0.504 -0.25)
			(stroke
				(width 0.15)
				(type solid)
			)
			(layer "F.Fab")
		)
		(fp_line
			(start 0.504 -0.25)
			(end 0.504 0.248)
			(stroke
				(width 0.15)
				(type solid)
			)
			(layer "F.Fab")
		)
		(pad "1" smd roundrect
			(at -0.48 0 270)
			(size 0.59 0.64)
			(layers "F.Cu" "F.Mask" "F.Paste")
			(roundrect_rratio 0.25)
			(net 1 "GND")
			(pintype "passive")
			(teardrops
				(best_length_ratio 0.2)
				(max_length 1)
				(best_width_ratio 0.9)
				(max_width 2)
				(curved_edges yes)
				(filter_ratio 0.9)
				(enabled yes)
				(allow_two_segments yes)
				(prefer_zone_connections yes)
			)
		)
		(pad "2" smd roundrect
			(at 0.48 0 270)
			(size 0.59 0.64)
			(layers "F.Cu" "F.Mask" "F.Paste")
			(roundrect_rratio 0.25)
			(net 2 "+3V3")
			(pintype "passive")
			(teardrops
				(best_length_ratio 0.2)
				(max_length 1)
				(best_width_ratio 0.9)
				(max_width 2)
				(curved_edges yes)
				(filter_ratio 0.9)
				(enabled yes)
				(allow_two_segments yes)
				(prefer_zone_connections yes)
			)
		)
	)
	(footprint "antmicro-footprints:C_0402_1005Metric"
		(layer "F.Cu")
		(at 302.500002 90.06 180)
		(descr "Capacitor SMD 0402")
		(tags "capacitor SMD 0402")
		(property "Reference" "C205"
			(at -1.399998 0.45 0)
			(layer "F.SilkS")
			(effects
				(font
					(size 0.7 0.7)
					(thickness 0.15)
				)
				(justify right bottom)
			)
		)
		(property "Value" "C_100n_0402"
			(at -1.022927 2.155213 0)
			(layer "F.Fab")
			(effects
				(font
					(size 0.7 0.7)
					(thickness 0.15)
				)
				(justify right bottom)
			)
		)
		(property "Datasheet" "https://www.murata.com/products/productdetail?partno=GRM155R61H104KE14%23"
			(at 0 0 180)
			(layer "F.Fab")
			(hide yes)
			(effects
				(font
					(size 1.27 1.27)
					(thickness 0.15)
				)
			)
		)
		(property "Author" "Antmicro"
			(at 605.000004 180.12 0)
			(layer "F.Fab")
			(hide yes)
			(effects
				(font
					(size 1 1)
					(thickness 0.15)
				)
			)
		)
		(property "Dielectric" "X5R"
			(at 605.000004 180.12 0)
			(layer "F.Fab")
			(hide yes)
			(effects
				(font
					(size 1 1)
					(thickness 0.15)
				)
			)
		)
		(property "License" "Apache-2.0"
			(at 605.000004 180.12 0)
			(layer "F.Fab")
			(hide yes)
			(effects
				(font
					(size 1 1)
					(thickness 0.15)
				)
			)
		)
		(property "MPN" "GRM155R61H104KE14D"
			(at 605.000004 180.12 0)
			(layer "F.Fab")
			(hide yes)
			(effects
				(font
					(size 1 1)
					(thickness 0.15)
				)
			)
		)
		(property "Manufacturer" "Murata"
			(at 605.000004 180.12 0)
			(layer "F.Fab")
			(hide yes)
			(effects
				(font
					(size 1 1)
					(thickness 0.15)
				)
			)
		)
		(property "Public" "False"
			(at 605.000004 180.12 0)
			(layer "F.Fab")
			(hide yes)
			(effects
				(font
					(size 1 1)
					(thickness 0.15)
				)
			)
		)
		(property "Val" "100n"
			(at 605.000004 180.12 0)
			(layer "F.Fab")
			(hide yes)
			(effects
				(font
					(size 1 1)
					(thickness 0.15)
				)
			)
		)
		(property "Voltage" "50V"
			(at 605.000004 180.12 0)
			(layer "F.Fab")
			(hide yes)
			(effects
				(font
					(size 1 1)
					(thickness 0.15)
				)
			)
		)
		(sheetname "Power")
		(sheetfile "power.kicad_sch")
		(attr smd)
		(fp_rect
			(start -0.925 -0.47)
			(end 0.925 0.47)
			(stroke
				(width 0.05)
				(type default)
			)
			(fill no)
			(layer "F.CrtYd")
		)
		(fp_line
			(start 0.504 0.248)
			(end -0.494 0.248)
			(stroke
				(width 0.15)
				(type solid)
			)
			(layer "F.Fab")
		)
		(fp_line
			(start 0.504 -0.25)
			(end 0.504 0.248)
			(stroke
				(width 0.15)
				(type solid)
			)
			(layer "F.Fab")
		)
		(fp_line
			(start -0.494 0.248)
			(end -0.494 -0.25)
			(stroke
				(width 0.15)
				(type solid)
			)
			(layer "F.Fab")
		)
		(fp_line
			(start -0.494 -0.25)
			(end 0.504 -0.25)
			(stroke
				(width 0.15)
				(type solid)
			)
			(layer "F.Fab")
		)
		(pad "1" smd roundrect
			(at -0.48 0 180)
			(size 0.59 0.64)
			(layers "F.Cu" "F.Mask" "F.Paste")
			(roundrect_rratio 0.25)
			(net 1 "GND")
			(pintype "passive")
			(teardrops
				(best_length_ratio 0.2)
				(max_length 1)
				(best_width_ratio 0.9)
				(max_width 2)
				(curved_edges yes)
				(filter_ratio 0.9)
				(enabled yes)
				(allow_two_segments yes)
				(prefer_zone_connections yes)
			)
		)
		(pad "2" smd roundrect
			(at 0.48 0 180)
			(size 0.59 0.64)
			(layers "F.Cu" "F.Mask" "F.Paste")
			(roundrect_rratio 0.25)
			(net 73 "+3V3_AON")
			(pintype "passive")
			(teardrops
				(best_length_ratio 0.2)
				(max_length 1)
				(best_width_ratio 0.9)
				(max_width 2)
				(curved_edges yes)
				(filter_ratio 0.9)
				(enabled yes)
				(allow_two_segments yes)
				(prefer_zone_connections yes)
			)
		)
	)
	(footprint "antmicro-footprints:MS621FE-FL11E"
		(layer "F.Cu")
		(at 314.2 72.81 90)
		(property "Reference" "BT1"
			(at 1.3 -5.05 180)
			(layer "F.SilkS")
			(effects
				(font
					(size 0.7 0.7)
					(thickness 0.15)
				)
				(justify left bottom)
			)
		)
		(property "Value" "Battery_Holder_MS621FE-FL11E"
			(at -0.001 6.2 90)
			(layer "F.Fab")
			(effects
				(font
					(size 0.7 0.7)
					(thickness 0.15)
				)
				(justify left bottom)
			)
		)
		(property "Datasheet" "https://www.sii.co.jp/en/me/datasheets/ms-rechargeable/ms621fe/"
			(at 0 0 90)
			(layer "F.Fab")
			(hide yes)
			(effects
				(font
					(size 1.27 1.27)
					(thickness 0.15)
				)
			)
		)
		(property "Author" "Antmicro"
			(at 387.01 -241.39 0)
			(layer "F.Fab")
			(hide yes)
			(effects
				(font
					(size 1 1)
					(thickness 0.15)
				)
			)
		)
		(property "License" "Apache-2.0"
			(at 387.01 -241.39 0)
			(layer "F.Fab")
			(hide yes)
			(effects
				(font
					(size 1 1)
					(thickness 0.15)
				)
			)
		)
		(property "MPN" "MS621FE-FL11E"
			(at 387.01 -241.39 0)
			(layer "F.Fab")
			(hide yes)
			(effects
				(font
					(size 1 1)
					(thickness 0.15)
				)
			)
		)
		(property "Manufacturer" "Seiko Instruments"
			(at 387.01 -241.39 0)
			(layer "F.Fab")
			(hide yes)
			(effects
				(font
					(size 1 1)
					(thickness 0.15)
				)
			)
		)
		(sheetname "Com Express 7 MGMT")
		(sheetfile "com_express_7_mgmt.kicad_sch")
		(attr smd)
		(fp_arc
			(start 1.2 -2.15)
			(mid 0 4.834)
			(end -1.2 -2.15)
			(stroke
				(width 0.15)
				(type solid)
			)
			(layer "F.SilkS")
		)
		(fp_line
			(start 1.275 -5.2)
			(end -1.275 -5.2)
			(stroke
				(width 0.05)
				(type solid)
			)
			(layer "F.CrtYd")
		)
		(fp_line
			(start 1.275 -5.2)
			(end 1.275 -2.425)
			(stroke
				(width 0.05)
				(type solid)
			)
			(layer "F.CrtYd")
		)
		(fp_line
			(start -1.275 -5.2)
			(end -1.275 -2.425)
			(stroke
				(width 0.05)
				(type solid)
			)
			(layer "F.CrtYd")
		)
		(fp_arc
			(start 1.275 -2.425)
			(mid 0 5.143374)
			(end -1.275 -2.425)
			(stroke
				(width 0.05)
				(type solid)
			)
			(layer "F.CrtYd")
		)
		(fp_line
			(start 1.2 -5.05)
			(end -0.8 -5.05)
			(stroke
				(width 0.15)
				(type solid)
			)
			(layer "F.Fab")
		)
		(fp_line
			(start 1.2 -5.05)
			(end 1.2 -2.04)
			(stroke
				(width 0.15)
				(type solid)
			)
			(layer "F.Fab")
		)
		(fp_line
			(start -0.8 -5.05)
			(end -1.2 -4.65)
			(stroke
				(width 0.15)
				(type solid)
			)
			(layer "F.Fab")
		)
		(fp_line
			(start -1.2 -4.65)
			(end -1.2 -2.04)
			(stroke
				(width 0.15)
				(type solid)
			)
			(layer "F.Fab")
		)
		(fp_circle
			(center -0.001 1.25)
			(end -0.001 -2.25)
			(stroke
				(width 0.15)
				(type solid)
			)
			(fill no)
			(layer "F.Fab")
		)
		(fp_text user "COPPER KEEPOUT"
			(at -0.2 -3.14 0)
			(unlocked yes)
			(layer "F.Fab")
			(effects
				(font
					(size 0.4 0.4)
					(thickness 0.1)
				)
				(justify left bottom)
			)
		)
		(pad "1" smd rect
			(at -0.75 -4.05)
			(size 1.8 0.75)
			(layers "F.Cu" "F.Mask" "F.Paste")
			(net 41 "Net-(BT1-+)")
			(pinfunction "+")
			(pintype "passive")
			(teardrops
				(best_length_ratio 0.2)
				(max_length 1)
				(best_width_ratio 0.9)
				(max_width 2)
				(curved_edges yes)
				(filter_ratio 0.9)
				(enabled yes)
				(allow_two_segments yes)
				(prefer_zone_connections yes)
			)
		)
		(pad "2" smd rect
			(at 0.75 -4.05)
			(size 1.8 0.75)
			(layers "F.Cu" "F.Mask" "F.Paste")
			(net 1 "GND")
			(pinfunction "-")
			(pintype "passive")
			(teardrops
				(best_length_ratio 0.2)
				(max_length 1)
				(best_width_ratio 0.9)
				(max_width 2)
				(curved_edges yes)
				(filter_ratio 0.9)
				(enabled yes)
				(allow_two_segments yes)
				(prefer_zone_connections yes)
			)
		)
		(zone
			(net 0)
			(net_name "")
			(layers "F.Cu" "F.CrtYd")
			(hatch edge 0.508)
			(connect_pads
				(clearance 0)
			)
			(min_thickness 0.254)
			(filled_areas_thickness no)
			(keepout
				(tracks allowed)
				(vias not_allowed)
				(pads not_allowed)
				(copperpour not_allowed)
				(footprints allowed)
			)
			(placement
				(enabled no)
				(sheetname "")
			)
			(fill
				(thermal_gap 0.508)
				(thermal_bridge_width 0.508)
			)
			(polygon
				(pts
					(xy 316.7 73.97) (xy 311.06 73.97) (xy 311.06 71.65) (xy 316.7 71.65)
				)
			)
		)
	)
	(footprint "antmicro-footprints:C_0402_1005Metric"
		(layer "F.Cu")
		(at 130.9 81.760001 -90)
		(descr "Capacitor SMD 0402")
		(tags "capacitor SMD 0402")
		(property "Reference" "C147"
			(at -3.650001 -0.4 90)
			(layer "F.SilkS")
			(effects
				(font
					(size 0.7 0.7)
					(thickness 0.15)
				)
				(justify right bottom)
			)
		)
		(property "Value" "C_100n_0402"
			(at -1.022927 2.155213 90)
			(layer "F.Fab")
			(effects
				(font
					(size 0.7 0.7)
					(thickness 0.15)
				)
				(justify right bottom)
			)
		)
		(property "Datasheet" "https://www.murata.com/products/productdetail?partno=GRM155R61H104KE14%23"
			(at 0 0 270)
			(layer "F.Fab")
			(hide yes)
			(effects
				(font
					(size 1.27 1.27)
					(thickness 0.15)
				)
			)
		)
		(property "Author" "Antmicro"
			(at 49.139999 212.660001 0)
			(layer "F.Fab")
			(hide yes)
			(effects
				(font
					(size 1 1)
					(thickness 0.15)
				)
			)
		)
		(property "Dielectric" "X5R"
			(at 49.139999 212.660001 0)
			(layer "F.Fab")
			(hide yes)
			(effects
				(font
					(size 1 1)
					(thickness 0.15)
				)
			)
		)
		(property "License" "Apache-2.0"
			(at 49.139999 212.660001 0)
			(layer "F.Fab")
			(hide yes)
			(effects
				(font
					(size 1 1)
					(thickness 0.15)
				)
			)
		)
		(property "MPN" "GRM155R61H104KE14D"
			(at 49.139999 212.660001 0)
			(layer "F.Fab")
			(hide yes)
			(effects
				(font
					(size 1 1)
					(thickness 0.15)
				)
			)
		)
		(property "Manufacturer" "Murata"
			(at 49.139999 212.660001 0)
			(layer "F.Fab")
			(hide yes)
			(effects
				(font
					(size 1 1)
					(thickness 0.15)
				)
			)
		)
		(property "Public" "False"
			(at 49.139999 212.660001 0)
			(layer "F.Fab")
			(hide yes)
			(effects
				(font
					(size 1 1)
					(thickness 0.15)
				)
			)
		)
		(property "Val" "100n"
			(at 49.139999 212.660001 0)
			(layer "F.Fab")
			(hide yes)
			(effects
				(font
					(size 1 1)
					(thickness 0.15)
				)
			)
		)
		(property "Voltage" "50V"
			(at 49.139999 212.660001 0)
			(layer "F.Fab")
			(hide yes)
			(effects
				(font
					(size 1 1)
					(thickness 0.15)
				)
			)
		)
		(sheetname "GPIO expander")
		(sheetfile "gpio_exp.kicad_sch")
		(attr smd)
		(fp_rect
			(start -0.925 -0.47)
			(end 0.925 0.47)
			(stroke
				(width 0.05)
				(type default)
			)
			(fill no)
			(layer "F.CrtYd")
		)
		(fp_line
			(start -0.494 0.248)
			(end -0.494 -0.25)
			(stroke
				(width 0.15)
				(type solid)
			)
			(layer "F.Fab")
		)
		(fp_line
			(start 0.504 0.248)
			(end -0.494 0.248)
			(stroke
				(width 0.15)
				(type solid)
			)
			(layer "F.Fab")
		)
		(fp_line
			(start -0.494 -0.25)
			(end 0.504 -0.25)
			(stroke
				(width 0.15)
				(type solid)
			)
			(layer "F.Fab")
		)
		(fp_line
			(start 0.504 -0.25)
			(end 0.504 0.248)
			(stroke
				(width 0.15)
				(type solid)
			)
			(layer "F.Fab")
		)
		(pad "1" smd roundrect
			(at -0.48 0 270)
			(size 0.59 0.64)
			(layers "F.Cu" "F.Mask" "F.Paste")
			(roundrect_rratio 0.25)
			(net 1 "GND")
			(pintype "passive")
			(teardrops
				(best_length_ratio 0.2)
				(max_length 1)
				(best_width_ratio 0.9)
				(max_width 2)
				(curved_edges yes)
				(filter_ratio 0.9)
				(enabled yes)
				(allow_two_segments yes)
				(prefer_zone_connections yes)
			)
		)
		(pad "2" smd roundrect
			(at 0.48 0 270)
			(size 0.59 0.64)
			(layers "F.Cu" "F.Mask" "F.Paste")
			(roundrect_rratio 0.25)
			(net 2 "+3V3")
			(pintype "passive")
			(teardrops
				(best_length_ratio 0.2)
				(max_length 1)
				(best_width_ratio 0.9)
				(max_width 2)
				(curved_edges yes)
				(filter_ratio 0.9)
				(enabled yes)
				(allow_two_segments yes)
				(prefer_zone_connections yes)
			)
		)
	)
	(footprint "antmicro-footprints:R_0402_1005Metric"
		(layer "F.Cu")
		(at 258.12 161.08 -90)
		(descr "Resistor SMD 0402")
		(tags "resistor SMD 0402")
		(property "Reference" "R181"
			(at -3.65 -0.45 90)
			(layer "F.SilkS")
			(effects
				(font
					(size 0.7 0.7)
					(thickness 0.15)
				)
				(justify right bottom)
			)
		)
		(property "Value" "R_1k_0402"
			(at -1.011843 1.772046 90)
			(layer "F.Fab")
			(effects
				(font
					(size 0.7 0.7)
					(thickness 0.15)
				)
				(justify right bottom)
			)
		)
		(property "Datasheet" "https://www.bourns.com/docs/product-datasheets/cr.pdf"
			(at 0 0 90)
			(layer "F.Fab")
			(hide yes)
			(effects
				(font
					(size 1.27 1.27)
					(thickness 0.15)
				)
			)
		)
		(property "Author" "Antmicro"
			(at 337.8 291.82 90)
			(layer "F.Fab")
			(hide yes)
			(effects
				(font
					(size 1 1)
					(thickness 0.15)
				)
			)
		)
		(property "License" "Apache-2.0"
			(at 337.8 291.82 90)
			(layer "F.Fab")
			(hide yes)
			(effects
				(font
					(size 1 1)
					(thickness 0.15)
				)
			)
		)
		(property "MPN" "CR0402-FX-1001GLF"
			(at 337.8 291.82 90)
			(layer "F.Fab")
			(hide yes)
			(effects
				(font
					(size 1 1)
					(thickness 0.15)
				)
			)
		)
		(property "Manufacturer" "Bourns"
			(at 337.8 291.82 90)
			(layer "F.Fab")
			(hide yes)
			(effects
				(font
					(size 1 1)
					(thickness 0.15)
				)
			)
		)
		(property "Public" "False"
			(at 337.8 291.82 90)
			(layer "F.Fab")
			(hide yes)
			(effects
				(font
					(size 1 1)
					(thickness 0.15)
				)
			)
		)
		(property "Tolerance" "1%"
			(at 337.8 291.82 90)
			(layer "F.Fab")
			(hide yes)
			(effects
				(font
					(size 1 1)
					(thickness 0.15)
				)
			)
		)
		(property "Val" "1k"
			(at 337.8 291.82 90)
			(layer "F.Fab")
			(hide yes)
			(effects
				(font
					(size 1 1)
					(thickness 0.15)
				)
			)
		)
		(sheetname "Com Express 7 MGMT")
		(sheetfile "com_express_7_mgmt.kicad_sch")
		(attr smd)
		(fp_rect
			(start -0.925 -0.47)
			(end 0.925 0.47)
			(stroke
				(width 0.05)
				(type default)
			)
			(fill no)
			(layer "F.CrtYd")
		)
		(fp_rect
			(start -0.5 -0.25)
			(end 0.5 0.25)
			(stroke
				(width 0.15)
				(type solid)
			)
			(fill no)
			(layer "F.Fab")
		)
		(pad "1" smd roundrect
			(at -0.48 0 270)
			(size 0.59 0.64)
			(layers "F.Cu" "F.Mask" "F.Paste")
			(roundrect_rratio 0.25)
			(net 601 "Net-(U36-~{WP}(D2))")
			(pintype "passive")
			(teardrops
				(best_length_ratio 0.2)
				(max_length 1)
				(best_width_ratio 0.9)
				(max_width 2)
				(curved_edges yes)
				(filter_ratio 0.9)
				(enabled yes)
				(allow_two_segments yes)
				(prefer_zone_connections yes)
			)
		)
		(pad "2" smd roundrect
			(at 0.48 0 270)
			(size 0.59 0.64)
			(layers "F.Cu" "F.Mask" "F.Paste")
			(roundrect_rratio 0.25)
			(net 85 "/Com Express 7 MGMT/MAFS_POWER")
			(pintype "passive")
			(teardrops
				(best_length_ratio 0.2)
				(max_length 1)
				(best_width_ratio 0.9)
				(max_width 2)
				(curved_edges yes)
				(filter_ratio 0.9)
				(enabled yes)
				(allow_two_segments yes)
				(prefer_zone_connections yes)
			)
		)
	)
	(footprint "antmicro-footprints:C_0402_1005Metric"
		(layer "F.Cu")
		(at 112.15 134.56 180)
		(descr "Capacitor SMD 0402")
		(tags "capacitor SMD 0402")
		(property "Reference" "C202"
			(at -3.85 -0.55 0)
			(layer "F.SilkS")
			(effects
				(font
					(size 0.7 0.7)
					(thickness 0.15)
				)
				(justify right bottom)
			)
		)
		(property "Value" "C_100n_0402"
			(at -1.022927 2.155213 0)
			(layer "F.Fab")
			(effects
				(font
					(size 0.7 0.7)
					(thickness 0.15)
				)
				(justify right bottom)
			)
		)
		(property "Datasheet" "https://www.murata.com/products/productdetail?partno=GRM155R61H104KE14%23"
			(at 0 0 180)
			(layer "F.Fab")
			(hide yes)
			(effects
				(font
					(size 1.27 1.27)
					(thickness 0.15)
				)
			)
		)
		(property "Author" "Antmicro"
			(at 224.3 269.12 0)
			(layer "F.Fab")
			(hide yes)
			(effects
				(font
					(size 1 1)
					(thickness 0.15)
				)
			)
		)
		(property "Dielectric" "X5R"
			(at 224.3 269.12 0)
			(layer "F.Fab")
			(hide yes)
			(effects
				(font
					(size 1 1)
					(thickness 0.15)
				)
			)
		)
		(property "License" "Apache-2.0"
			(at 224.3 269.12 0)
			(layer "F.Fab")
			(hide yes)
			(effects
				(font
					(size 1 1)
					(thickness 0.15)
				)
			)
		)
		(property "MPN" "GRM155R61H104KE14D"
			(at 224.3 269.12 0)
			(layer "F.Fab")
			(hide yes)
			(effects
				(font
					(size 1 1)
					(thickness 0.15)
				)
			)
		)
		(property "Manufacturer" "Murata"
			(at 224.3 269.12 0)
			(layer "F.Fab")
			(hide yes)
			(effects
				(font
					(size 1 1)
					(thickness 0.15)
				)
			)
		)
		(property "Public" "False"
			(at 224.3 269.12 0)
			(layer "F.Fab")
			(hide yes)
			(effects
				(font
					(size 1 1)
					(thickness 0.15)
				)
			)
		)
		(property "Val" "100n"
			(at 224.3 269.12 0)
			(layer "F.Fab")
			(hide yes)
			(effects
				(font
					(size 1 1)
					(thickness 0.15)
				)
			)
		)
		(property "Voltage" "50V"
			(at 224.3 269.12 0)
			(layer "F.Fab")
			(hide yes)
			(effects
				(font
					(size 1 1)
					(thickness 0.15)
				)
			)
		)
		(sheetname "SD card")
		(sheetfile "sd_card.kicad_sch")
		(attr smd)
		(fp_rect
			(start -0.925 -0.47)
			(end 0.925 0.47)
			(stroke
				(width 0.05)
				(type default)
			)
			(fill no)
			(layer "F.CrtYd")
		)
		(fp_line
			(start 0.504 0.248)
			(end -0.494 0.248)
			(stroke
				(width 0.15)
				(type solid)
			)
			(layer "F.Fab")
		)
		(fp_line
			(start 0.504 -0.25)
			(end 0.504 0.248)
			(stroke
				(width 0.15)
				(type solid)
			)
			(layer "F.Fab")
		)
		(fp_line
			(start -0.494 0.248)
			(end -0.494 -0.25)
			(stroke
				(width 0.15)
				(type solid)
			)
			(layer "F.Fab")
		)
		(fp_line
			(start -0.494 -0.25)
			(end 0.504 -0.25)
			(stroke
				(width 0.15)
				(type solid)
			)
			(layer "F.Fab")
		)
		(pad "1" smd roundrect
			(at -0.48 0 180)
			(size 0.59 0.64)
			(layers "F.Cu" "F.Mask" "F.Paste")
			(roundrect_rratio 0.25)
			(net 1 "GND")
			(pintype "passive")
			(teardrops
				(best_length_ratio 0.2)
				(max_length 1)
				(best_width_ratio 0.9)
				(max_width 2)
				(curved_edges yes)
				(filter_ratio 0.9)
				(enabled yes)
				(allow_two_segments yes)
				(prefer_zone_connections yes)
			)
		)
		(pad "2" smd roundrect
			(at 0.48 0 180)
			(size 0.59 0.64)
			(layers "F.Cu" "F.Mask" "F.Paste")
			(roundrect_rratio 0.25)
			(net 2 "+3V3")
			(pintype "passive")
			(teardrops
				(best_length_ratio 0.2)
				(max_length 1)
				(best_width_ratio 0.9)
				(max_width 2)
				(curved_edges yes)
				(filter_ratio 0.9)
				(enabled yes)
				(allow_two_segments yes)
				(prefer_zone_connections yes)
			)
		)
	)
	(footprint "antmicro-footprints:TP_SMD_0.75mm"
		(layer "F.Cu")
		(at 127.14 128.71)
		(property "Reference" "TP77"
			(at 0.46 -3.3 90)
			(layer "F.SilkS")
			(effects
				(font
					(size 0.7 0.7)
					(thickness 0.15)
				)
				(justify left bottom)
			)
		)
		(property "Value" "TP_0.75mm_SMD"
			(at 0 1.2 0)
			(layer "F.Fab")
			(effects
				(font
					(size 0.7 0.7)
					(thickness 0.15)
				)
				(justify left bottom)
			)
		)
		(property "Author" "Antmicro"
			(at 0 0 0)
			(layer "F.Fab")
			(hide yes)
			(effects
				(font
					(size 1 1)
					(thickness 0.15)
				)
			)
		)
		(property "License" "Apache-2.0"
			(at 0 0 0)
			(layer "F.Fab")
			(hide yes)
			(effects
				(font
					(size 1 1)
					(thickness 0.15)
				)
			)
		)
		(property "MPN" ""
			(at 0 0 0)
			(layer "F.Fab")
			(hide yes)
			(effects
				(font
					(size 1 1)
					(thickness 0.15)
				)
			)
		)
		(property "Manufacturer" ""
			(at 0 0 0)
			(layer "F.Fab")
			(hide yes)
			(effects
				(font
					(size 1 1)
					(thickness 0.15)
				)
			)
		)
		(property "Public" "False"
			(at 0 0 0)
			(layer "F.Fab")
			(hide yes)
			(effects
				(font
					(size 1 1)
					(thickness 0.15)
				)
			)
		)
		(sheetname "KR to SFI #2")
		(sheetfile "kr_sfi.kicad_sch")
		(attr exclude_from_pos_files exclude_from_bom)
		(fp_circle
			(center 0 0)
			(end 0.475 0)
			(stroke
				(width 0.05)
				(type default)
			)
			(fill no)
			(layer "F.CrtYd")
		)
		(pad "1" smd circle
			(at 0 0)
			(size 0.75 0.75)
			(layers "F.Cu" "F.Mask")
			(net 740 "Net-(U45C-REFCLK1+)")
			(pinfunction "1")
			(pintype "passive")
			(teardrops
				(best_length_ratio 0.4)
				(max_length 1)
				(best_width_ratio 0.9)
				(max_width 2)
				(curved_edges yes)
				(filter_ratio 0.9)
				(enabled yes)
				(allow_two_segments yes)
				(prefer_zone_connections yes)
			)
		)
	)
	(footprint "antmicro-footprints:R_0201"
		(layer "F.Cu")
		(at 129.17 147.31 -90)
		(descr "Resistor SMD 0201")
		(tags "resistor SMD 0201")
		(property "Reference" "R306"
			(at 4.099 -0.58 270)
			(layer "F.SilkS")
			(effects
				(font
					(size 0.7 0.7)
					(thickness 0.15)
				)
				(justify left bottom)
			)
		)
		(property "Value" "R_0R_0201"
			(at 0 1.25 270)
			(layer "F.Fab")
			(effects
				(font
					(size 0.7 0.7)
					(thickness 0.15)
				)
				(justify left bottom)
			)
		)
		(property "Datasheet" "https://www.bourns.com/docs/product-datasheets/cr.pdf"
			(at 0 0 270)
			(layer "F.Fab")
			(hide yes)
			(effects
				(font
					(size 1.27 1.27)
					(thickness 0.15)
				)
			)
		)
		(property "Author" "Antmicro"
			(at -18.14 276.48 0)
			(layer "F.Fab")
			(hide yes)
			(effects
				(font
					(size 1 1)
					(thickness 0.15)
				)
			)
		)
		(property "License" "Apache-2.0"
			(at -18.14 276.48 0)
			(layer "F.Fab")
			(hide yes)
			(effects
				(font
					(size 1 1)
					(thickness 0.15)
				)
			)
		)
		(property "MPN" "CR0201-FX-0R00GLF"
			(at -18.14 276.48 0)
			(layer "F.Fab")
			(hide yes)
			(effects
				(font
					(size 1 1)
					(thickness 0.15)
				)
			)
		)
		(property "Manufacturer" "Bourns"
			(at -18.14 276.48 0)
			(layer "F.Fab")
			(hide yes)
			(effects
				(font
					(size 1 1)
					(thickness 0.15)
				)
			)
		)
		(property "Tolerance" "1%"
			(at -18.14 276.48 0)
			(layer "F.Fab")
			(hide yes)
			(effects
				(font
					(size 1 1)
					(thickness 0.15)
				)
			)
		)
		(property "Val" "0R"
			(at -18.14 276.48 0)
			(layer "F.Fab")
			(hide yes)
			(effects
				(font
					(size 1 1)
					(thickness 0.15)
				)
			)
		)
		(sheetname "KR to SFI #2")
		(sheetfile "kr_sfi.kicad_sch")
		(attr smd)
		(fp_rect
			(start -0.7 -0.35)
			(end 0.7 0.35)
			(stroke
				(width 0.05)
				(type default)
			)
			(fill no)
			(layer "F.CrtYd")
		)
		(fp_rect
			(start -0.3 -0.15)
			(end 0.298 0.148)
			(stroke
				(width 0.15)
				(type solid)
			)
			(fill no)
			(layer "F.Fab")
		)
		(pad "" smd roundrect
			(at -0.346 0 270)
			(size 0.318 0.36)
			(layers "F.Paste")
			(roundrect_rratio 0.25)
			(teardrops
				(best_length_ratio 0.2)
				(max_length 1)
				(best_width_ratio 0.9)
				(max_width 2)
				(curved_edges yes)
				(filter_ratio 0.9)
				(enabled yes)
				(allow_two_segments yes)
				(prefer_zone_connections yes)
			)
		)
		(pad "" smd roundrect
			(at 0.344 0 270)
			(size 0.318 0.36)
			(layers "F.Paste")
			(roundrect_rratio 0.25)
			(teardrops
				(best_length_ratio 0.2)
				(max_length 1)
				(best_width_ratio 0.9)
				(max_width 2)
				(curved_edges yes)
				(filter_ratio 0.9)
				(enabled yes)
				(allow_two_segments yes)
				(prefer_zone_connections yes)
			)
		)
		(pad "1" smd roundrect
			(at -0.32 0 270)
			(size 0.46 0.4)
			(layers "F.Cu" "F.Mask")
			(roundrect_rratio 0.25)
			(net 947 "/2xSFP+/KR to SFI #2/SFI_R.TX+")
			(pintype "passive")
			(teardrops
				(best_length_ratio 0.2)
				(max_length 1)
				(best_width_ratio 0.9)
				(max_width 2)
				(curved_edges yes)
				(filter_ratio 0.9)
				(enabled yes)
				(allow_two_segments yes)
				(prefer_zone_connections yes)
			)
		)
		(pad "2" smd roundrect
			(at 0.32 0 270)
			(size 0.46 0.4)
			(layers "F.Cu" "F.Mask")
			(roundrect_rratio 0.25)
			(net 879 "/2xSFP+/SFI1.TX+")
			(pintype "passive")
			(teardrops
				(best_length_ratio 0.2)
				(max_length 1)
				(best_width_ratio 0.9)
				(max_width 2)
				(curved_edges yes)
				(filter_ratio 0.9)
				(enabled yes)
				(allow_two_segments yes)
				(prefer_zone_connections yes)
			)
		)
	)
	(footprint "antmicro-footprints:C_0402_1005Metric"
		(layer "F.Cu")
		(at 120.4 146.301 90)
		(descr "Capacitor SMD 0402")
		(tags "capacitor SMD 0402")
		(property "Reference" "C128"
			(at 10.541 0.6 90)
			(layer "F.SilkS")
			(effects
				(font
					(size 0.7 0.7)
					(thickness 0.15)
				)
				(justify left bottom)
			)
		)
		(property "Value" "C_100n_0402"
			(at -1.022927 2.155213 90)
			(layer "F.Fab")
			(effects
				(font
					(size 0.7 0.7)
					(thickness 0.15)
				)
				(justify left bottom)
			)
		)
		(property "Datasheet" "https://www.murata.com/products/productdetail?partno=GRM155R61H104KE14%23"
			(at 0 0 90)
			(layer "F.Fab")
			(hide yes)
			(effects
				(font
					(size 1.27 1.27)
					(thickness 0.15)
				)
			)
		)
		(property "Author" "Antmicro"
			(at 266.701 25.901 0)
			(layer "F.Fab")
			(hide yes)
			(effects
				(font
					(size 1 1)
					(thickness 0.15)
				)
			)
		)
		(property "Dielectric" "X5R"
			(at 266.701 25.901 0)
			(layer "F.Fab")
			(hide yes)
			(effects
				(font
					(size 1 1)
					(thickness 0.15)
				)
			)
		)
		(property "License" "Apache-2.0"
			(at 266.701 25.901 0)
			(layer "F.Fab")
			(hide yes)
			(effects
				(font
					(size 1 1)
					(thickness 0.15)
				)
			)
		)
		(property "MPN" "GRM155R61H104KE14D"
			(at 266.701 25.901 0)
			(layer "F.Fab")
			(hide yes)
			(effects
				(font
					(size 1 1)
					(thickness 0.15)
				)
			)
		)
		(property "Manufacturer" "Murata"
			(at 266.701 25.901 0)
			(layer "F.Fab")
			(hide yes)
			(effects
				(font
					(size 1 1)
					(thickness 0.15)
				)
			)
		)
		(property "Public" "False"
			(at 266.701 25.901 0)
			(layer "F.Fab")
			(hide yes)
			(effects
				(font
					(size 1 1)
					(thickness 0.15)
				)
			)
		)
		(property "Val" "100n"
			(at 266.701 25.901 0)
			(layer "F.Fab")
			(hide yes)
			(effects
				(font
					(size 1 1)
					(thickness 0.15)
				)
			)
		)
		(property "Voltage" "50V"
			(at 266.701 25.901 0)
			(layer "F.Fab")
			(hide yes)
			(effects
				(font
					(size 1 1)
					(thickness 0.15)
				)
			)
		)
		(sheetname "PCIe redriver")
		(sheetfile "pcie_redriver.kicad_sch")
		(attr smd)
		(fp_rect
			(start -0.925 -0.47)
			(end 0.925 0.47)
			(stroke
				(width 0.05)
				(type default)
			)
			(fill no)
			(layer "F.CrtYd")
		)
		(fp_line
			(start 0.504 -0.25)
			(end 0.504 0.248)
			(stroke
				(width 0.15)
				(type solid)
			)
			(layer "F.Fab")
		)
		(fp_line
			(start -0.494 -0.25)
			(end 0.504 -0.25)
			(stroke
				(width 0.15)
				(type solid)
			)
			(layer "F.Fab")
		)
		(fp_line
			(start 0.504 0.248)
			(end -0.494 0.248)
			(stroke
				(width 0.15)
				(type solid)
			)
			(layer "F.Fab")
		)
		(fp_line
			(start -0.494 0.248)
			(end -0.494 -0.25)
			(stroke
				(width 0.15)
				(type solid)
			)
			(layer "F.Fab")
		)
		(pad "1" smd roundrect
			(at -0.48 0 90)
			(size 0.59 0.64)
			(layers "F.Cu" "F.Mask" "F.Paste")
			(roundrect_rratio 0.25)
			(net 1 "GND")
			(pintype "passive")
			(teardrops
				(best_length_ratio 0.2)
				(max_length 1)
				(best_width_ratio 0.9)
				(max_width 2)
				(curved_edges yes)
				(filter_ratio 0.9)
				(enabled yes)
				(allow_two_segments yes)
				(prefer_zone_connections yes)
			)
		)
		(pad "2" smd roundrect
			(at 0.48 0 90)
			(size 0.59 0.64)
			(layers "F.Cu" "F.Mask" "F.Paste")
			(roundrect_rratio 0.25)
			(net 2 "+3V3")
			(pintype "passive")
			(teardrops
				(best_length_ratio 0.2)
				(max_length 1)
				(best_width_ratio 0.9)
				(max_width 2)
				(curved_edges yes)
				(filter_ratio 0.9)
				(enabled yes)
				(allow_two_segments yes)
				(prefer_zone_connections yes)
			)
		)
	)
	(footprint "antmicro-footprints:R_0201"
		(layer "F.Cu")
		(at 147.33 147.31 -90)
		(descr "Resistor SMD 0201")
		(tags "resistor SMD 0201")
		(property "Reference" "R272"
			(at 4.125 -0.57 270)
			(layer "F.SilkS")
			(effects
				(font
					(size 0.7 0.7)
					(thickness 0.15)
				)
				(justify left bottom)
			)
		)
		(property "Value" "R_0R_0201"
			(at 0 1.25 270)
			(layer "F.Fab")
			(effects
				(font
					(size 0.7 0.7)
					(thickness 0.15)
				)
				(justify left bottom)
			)
		)
		(property "Datasheet" "https://www.bourns.com/docs/product-datasheets/cr.pdf"
			(at 0 0 270)
			(layer "F.Fab")
			(hide yes)
			(effects
				(font
					(size 1.27 1.27)
					(thickness 0.15)
				)
			)
		)
		(property "Author" "Antmicro"
			(at 0.02 294.64 0)
			(layer "F.Fab")
			(hide yes)
			(effects
				(font
					(size 1 1)
					(thickness 0.15)
				)
			)
		)
		(property "License" "Apache-2.0"
			(at 0.02 294.64 0)
			(layer "F.Fab")
			(hide yes)
			(effects
				(font
					(size 1 1)
					(thickness 0.15)
				)
			)
		)
		(property "MPN" "CR0201-FX-0R00GLF"
			(at 0.02 294.64 0)
			(layer "F.Fab")
			(hide yes)
			(effects
				(font
					(size 1 1)
					(thickness 0.15)
				)
			)
		)
		(property "Manufacturer" "Bourns"
			(at 0.02 294.64 0)
			(layer "F.Fab")
			(hide yes)
			(effects
				(font
					(size 1 1)
					(thickness 0.15)
				)
			)
		)
		(property "Tolerance" "1%"
			(at 0.02 294.64 0)
			(layer "F.Fab")
			(hide yes)
			(effects
				(font
					(size 1 1)
					(thickness 0.15)
				)
			)
		)
		(property "Val" "0R"
			(at 0.02 294.64 0)
			(layer "F.Fab")
			(hide yes)
			(effects
				(font
					(size 1 1)
					(thickness 0.15)
				)
			)
		)
		(sheetname "KR to SFI #1")
		(sheetfile "kr_sfi.kicad_sch")
		(attr smd)
		(fp_rect
			(start -0.7 -0.35)
			(end 0.7 0.35)
			(stroke
				(width 0.05)
				(type default)
			)
			(fill no)
			(layer "F.CrtYd")
		)
		(fp_rect
			(start -0.3 -0.15)
			(end 0.298 0.148)
			(stroke
				(width 0.15)
				(type solid)
			)
			(fill no)
			(layer "F.Fab")
		)
		(pad "" smd roundrect
			(at -0.346 0 270)
			(size 0.318 0.36)
			(layers "F.Paste")
			(roundrect_rratio 0.25)
			(teardrops
				(best_length_ratio 0.2)
				(max_length 1)
				(best_width_ratio 0.9)
				(max_width 2)
				(curved_edges yes)
				(filter_ratio 0.9)
				(enabled yes)
				(allow_two_segments yes)
				(prefer_zone_connections yes)
			)
		)
		(pad "" smd roundrect
			(at 0.344 0 270)
			(size 0.318 0.36)
			(layers "F.Paste")
			(roundrect_rratio 0.25)
			(teardrops
				(best_length_ratio 0.2)
				(max_length 1)
				(best_width_ratio 0.9)
				(max_width 2)
				(curved_edges yes)
				(filter_ratio 0.9)
				(enabled yes)
				(allow_two_segments yes)
				(prefer_zone_connections yes)
			)
		)
		(pad "1" smd roundrect
			(at -0.32 0 270)
			(size 0.46 0.4)
			(layers "F.Cu" "F.Mask")
			(roundrect_rratio 0.25)
			(net 666 "/2xSFP+/KR to SFI #1/SFI_R.TX+")
			(pintype "passive")
			(teardrops
				(best_length_ratio 0.2)
				(max_length 1)
				(best_width_ratio 0.9)
				(max_width 2)
				(curved_edges yes)
				(filter_ratio 0.9)
				(enabled yes)
				(allow_two_segments yes)
				(prefer_zone_connections yes)
			)
		)
		(pad "2" smd roundrect
			(at 0.32 0 270)
			(size 0.46 0.4)
			(layers "F.Cu" "F.Mask")
			(roundrect_rratio 0.25)
			(net 172 "/2xSFP+/SFI0.TX+")
			(pintype "passive")
			(teardrops
				(best_length_ratio 0.2)
				(max_length 1)
				(best_width_ratio 0.9)
				(max_width 2)
				(curved_edges yes)
				(filter_ratio 0.9)
				(enabled yes)
				(allow_two_segments yes)
				(prefer_zone_connections yes)
			)
		)
	)
	(footprint "antmicro-footprints:LED_0603_1608Metric_G"
		(layer "F.Cu")
		(at 283.36 75.7 -90)
		(descr "LED SMD 0603 Green")
		(tags "LED SMD 0603 Green")
		(property "Reference" "D14"
			(at -1.14 0.66 90)
			(layer "F.SilkS")
			(effects
				(font
					(size 0.7 0.7)
					(thickness 0.15)
				)
				(justify right bottom)
			)
		)
		(property "Value" "LED_G_0603_LTST-C190GKT"
			(at -0.001 1.599 90)
			(layer "F.Fab")
			(effects
				(font
					(size 0.7 0.7)
					(thickness 0.15)
				)
				(justify right bottom)
			)
		)
		(property "Datasheet" "https://media.digikey.com/pdf/Data%20Sheets/Lite-On%20PDFs/LTST-C190GKT.pdf"
			(at 0 0 270)
			(layer "F.Fab")
			(hide yes)
			(effects
				(font
					(size 1.27 1.27)
					(thickness 0.15)
				)
			)
		)
		(property "Author" "Antmicro"
			(at 207.66 359.06 0)
			(layer "F.Fab")
			(hide yes)
			(effects
				(font
					(size 1 1)
					(thickness 0.15)
				)
			)
		)
		(property "Color" "Green"
			(at 207.66 359.06 0)
			(layer "F.Fab")
			(hide yes)
			(effects
				(font
					(size 1 1)
					(thickness 0.15)
				)
			)
		)
		(property "License" "Apache-2.0"
			(at 207.66 359.06 0)
			(layer "F.Fab")
			(hide yes)
			(effects
				(font
					(size 1 1)
					(thickness 0.15)
				)
			)
		)
		(property "MPN" "LTST-C190GKT"
			(at 207.66 359.06 0)
			(layer "F.Fab")
			(hide yes)
			(effects
				(font
					(size 1 1)
					(thickness 0.15)
				)
			)
		)
		(property "Manufacturer" "Lite-On"
			(at 207.66 359.06 0)
			(layer "F.Fab")
			(hide yes)
			(effects
				(font
					(size 1 1)
					(thickness 0.15)
				)
			)
		)
		(property "Public" "False"
			(at 207.66 359.06 0)
			(layer "F.Fab")
			(hide yes)
			(effects
				(font
					(size 1 1)
					(thickness 0.15)
				)
			)
		)
		(sheetname "M.2 key M #2")
		(sheetfile "m2keym.kicad_sch")
		(attr smd)
		(fp_line
			(start 0.22 0.35)
			(end -0.22 0.35)
			(stroke
				(width 0.15)
				(type solid)
			)
			(layer "F.SilkS")
		)
		(fp_line
			(start -0.094672 0.201008)
			(end -0.094672 -0.198992)
			(stroke
				(width 0.1)
				(type solid)
			)
			(layer "F.SilkS")
		)
		(fp_line
			(start 0.105328 0.201008)
			(end -0.094672 0.001008)
			(stroke
				(width 0.1)
				(type solid)
			)
			(layer "F.SilkS")
		)
		(fp_line
			(start 0.105328 0.201008)
			(end 0.105328 -0.198992)
			(stroke
				(width 0.1)
				(type solid)
			)
			(layer "F.SilkS")
		)
		(fp_line
			(start -0.094672 0.001008)
			(end -0.24 0.001008)
			(stroke
				(width 0.1)
				(type solid)
			)
			(layer "F.SilkS")
		)
		(fp_line
			(start -0.094672 0.001008)
			(end 0.105328 -0.198992)
			(stroke
				(width 0.1)
				(type solid)
			)
			(layer "F.SilkS")
		)
		(fp_line
			(start 0.105328 0.001008)
			(end 0.24 0.001)
			(stroke
				(width 0.1)
				(type solid)
			)
			(layer "F.SilkS")
		)
		(fp_line
			(start -1.18 -0.319)
			(end -1.18 0.321)
			(stroke
				(width 0.15)
				(type solid)
			)
			(layer "F.SilkS")
		)
		(fp_line
			(start 0.22 -0.35)
			(end -0.22 -0.35)
			(stroke
				(width 0.15)
				(type solid)
			)
			(layer "F.SilkS")
		)
		(fp_rect
			(start 1.25 0.65)
			(end -1.25 -0.65)
			(stroke
				(width 0.05)
				(type solid)
			)
			(fill no)
			(layer "F.CrtYd")
		)
		(fp_line
			(start -0.199 0.2)
			(end -0.199 0.1)
			(stroke
				(width 0.15)
				(type solid)
			)
			(layer "F.Fab")
		)
		(fp_line
			(start 0.201 0.2)
			(end 0.201 0)
			(stroke
				(width 0.15)
				(type solid)
			)
			(layer "F.Fab")
		)
		(fp_line
			(start -0.199 0)
			(end -0.597 0)
			(stroke
				(width 0.15)
				(type solid)
			)
			(layer "F.Fab")
		)
		(fp_line
			(start -0.101 0)
			(end 0.201 0.2)
			(stroke
				(width 0.15)
				(type solid)
			)
			(layer "F.Fab")
		)
		(fp_line
			(start 0.201 0)
			(end 0.201 -0.202)
			(stroke
				(width 0.15)
				(type solid)
			)
			(layer "F.Fab")
		)
		(fp_line
			(start 0.599 0)
			(end 0.201 0)
			(stroke
				(width 0.15)
				(type solid)
			)
			(layer "F.Fab")
		)
		(fp_line
			(start -0.199 -0.202)
			(end -0.199 0.1)
			(stroke
				(width 0.15)
				(type solid)
			)
			(layer "F.Fab")
		)
		(fp_line
			(start 0.201 -0.202)
			(end -0.101 0)
			(stroke
				(width 0.15)
				(type solid)
			)
			(layer "F.Fab")
		)
		(fp_rect
			(start 0.848 0.4)
			(end -0.85 -0.402)
			(stroke
				(width 0.15)
				(type solid)
			)
			(fill no)
			(layer "F.Fab")
		)
		(pad "1" smd roundrect
			(at -0.7 0 90)
			(size 0.8 1)
			(layers "F.Cu" "F.Mask" "F.Paste")
			(roundrect_rratio 0.2)
			(net 936 "Net-(D14-C)")
			(pinfunction "C")
			(pintype "passive")
			(teardrops
				(best_length_ratio 0.2)
				(max_length 1)
				(best_width_ratio 0.9)
				(max_width 2)
				(curved_edges yes)
				(filter_ratio 0.9)
				(enabled yes)
				(allow_two_segments yes)
				(prefer_zone_connections yes)
			)
		)
		(pad "2" smd roundrect
			(at 0.7 0 90)
			(size 0.8 1)
			(layers "F.Cu" "F.Mask" "F.Paste")
			(roundrect_rratio 0.2)
			(net 892 "Net-(D14-A)")
			(pinfunction "A")
			(pintype "passive")
			(teardrops
				(best_length_ratio 0.2)
				(max_length 1)
				(best_width_ratio 0.9)
				(max_width 2)
				(curved_edges yes)
				(filter_ratio 0.9)
				(enabled yes)
				(allow_two_segments yes)
				(prefer_zone_connections yes)
			)
		)
	)
	(footprint "antmicro-footprints:SW_1-1825027-1_THT"
		(layer "F.Cu")
		(at 98.398 119.71 -90)
		(descr "Tactile Switches, Round Actuator Style, NO, 5.74mm")
		(property "Reference" "SW1"
			(at 7.35 0.498 180)
			(layer "F.SilkS")
			(effects
				(font
					(size 0.7 0.7)
					(thickness 0.15)
				)
				(justify right bottom)
			)
		)
		(property "Value" "SW_1-1825027-1_THT"
			(at -2.4 9.6 90)
			(layer "F.Fab")
			(effects
				(font
					(size 0.7 0.7)
					(thickness 0.15)
				)
				(justify right bottom)
			)
		)
		(property "Datasheet" "https://www.te.com/commerce/DocumentDelivery/DDEController?Action=showdoc&DocId=Customer+Drawing%7F1825027%7FH1%7Fpdf%7FEnglish%7FENG_CD_1825027_H1.pdf%7F1-1825027-1"
			(at 0 0 270)
			(layer "F.Fab")
			(hide yes)
			(effects
				(font
					(size 1.27 1.27)
					(thickness 0.15)
				)
			)
		)
		(property "Author" "Antmicro"
			(at -21.312 218.108 0)
			(layer "F.Fab")
			(hide yes)
			(effects
				(font
					(size 1 1)
					(thickness 0.15)
				)
			)
		)
		(property "License" "Apache-2.0"
			(at -21.312 218.108 0)
			(layer "F.Fab")
			(hide yes)
			(effects
				(font
					(size 1 1)
					(thickness 0.15)
				)
			)
		)
		(property "MPN" "1-1825027-1"
			(at -21.312 218.108 0)
			(layer "F.Fab")
			(hide yes)
			(effects
				(font
					(size 1 1)
					(thickness 0.15)
				)
			)
		)
		(property "Manufacturer" "TE Connectivity"
			(at -21.312 218.108 0)
			(layer "F.Fab")
			(hide yes)
			(effects
				(font
					(size 1 1)
					(thickness 0.15)
				)
			)
		)
		(sheetname "Com Express 7 MGMT")
		(sheetfile "com_express_7_mgmt.kicad_sch")
		(attr through_hole)
		(fp_line
			(start 4.004 2.6)
			(end 0.494 2.6)
			(stroke
				(width 0.15)
				(type solid)
			)
			(layer "F.SilkS")
		)
		(fp_line
			(start -1.307 2.548)
			(end -1.307 -0.485)
			(stroke
				(width 0.15)
				(type solid)
			)
			(layer "F.SilkS")
		)
		(fp_line
			(start 5.804 -0.5)
			(end 5.799 2.6)
			(stroke
				(width 0.15)
				(type solid)
			)
			(layer "F.SilkS")
		)
		(fp_line
			(start -1.331 -4.01)
			(end 5.828 -4.01)
			(stroke
				(width 0.15)
				(type solid)
			)
			(layer "F.SilkS")
		)
		(fp_line
			(start 0.14 8.58)
			(end 4.24 8.58)
			(stroke
				(width 0.05)
				(type solid)
			)
			(layer "F.CrtYd")
		)
		(fp_line
			(start 4.24 8.58)
			(end 4.24 2.89)
			(stroke
				(width 0.05)
				(type solid)
			)
			(layer "F.CrtYd")
		)
		(fp_line
			(start -1.6 2.89)
			(end 0.14 2.89)
			(stroke
				(width 0.05)
				(type solid)
			)
			(layer "F.CrtYd")
		)
		(fp_line
			(start 0.14 2.89)
			(end 0.14 8.58)
			(stroke
				(width 0.05)
				(type solid)
			)
			(layer "F.CrtYd")
		)
		(fp_line
			(start 4.24 2.89)
			(end 6.1 2.89)
			(stroke
				(width 0.05)
				(type solid)
			)
			(layer "F.CrtYd")
		)
		(fp_line
			(start 6.1 2.89)
			(end 6.1 -4.21)
			(stroke
				(width 0.05)
				(type solid)
			)
			(layer "F.CrtYd")
		)
		(fp_line
			(start -1.6 -4.21)
			(end -1.6 2.89)
			(stroke
				(width 0.05)
				(type solid)
			)
			(layer "F.CrtYd")
		)
		(fp_line
			(start 6.1 -4.21)
			(end -1.6 -4.21)
			(stroke
				(width 0.05)
				(type solid)
			)
			(layer "F.CrtYd")
		)
		(fp_line
			(start 0.494 8.349)
			(end 4.004 8.349)
			(stroke
				(width 0.15)
				(type solid)
			)
			(layer "F.Fab")
		)
		(fp_line
			(start 4.004 8.349)
			(end 3.999 2.6)
			(stroke
				(width 0.15)
				(type solid)
			)
			(layer "F.Fab")
		)
		(fp_line
			(start -1.307 2.6)
			(end -1.307 -4.01)
			(stroke
				(width 0.15)
				(type solid)
			)
			(layer "F.Fab")
		)
		(fp_line
			(start 0.494 2.6)
			(end 0.494 8.349)
			(stroke
				(width 0.15)
				(type solid)
			)
			(layer "F.Fab")
		)
		(fp_line
			(start 0.494 2.6)
			(end -1.307 2.6)
			(stroke
				(width 0.15)
				(type solid)
			)
			(layer "F.Fab")
		)
		(fp_line
			(start 5.799 2.6)
			(end 3.999 2.6)
			(stroke
				(width 0.15)
				(type solid)
			)
			(layer "F.Fab")
		)
		(fp_line
			(start -1.307 -4.01)
			(end 5.804 -4.01)
			(stroke
				(width 0.15)
				(type solid)
			)
			(layer "F.Fab")
		)
		(fp_line
			(start 5.804 -4.01)
			(end 5.804 2.6)
			(stroke
				(width 0.15)
				(type solid)
			)
			(layer "F.Fab")
		)
		(pad "1" thru_hole circle
			(at 0 0 270)
			(size 1.498 1.498)
			(drill 0.99)
			(layers "*.Cu" "*.Mask")
			(remove_unused_layers no)
			(net 84 "/Com Express 7 MGMT/PWRBTN")
			(pinfunction "1")
			(pintype "passive")
			(teardrops
				(best_length_ratio 0.4)
				(max_length 1)
				(best_width_ratio 0.9)
				(max_width 2)
				(curved_edges yes)
				(filter_ratio 0.9)
				(enabled yes)
				(allow_two_segments yes)
				(prefer_zone_connections yes)
			)
		)
		(pad "2" thru_hole circle
			(at 4.498 0 270)
			(size 1.498 1.498)
			(drill 0.99)
			(layers "*.Cu" "*.Mask")
			(remove_unused_layers no)
			(net 1 "GND")
			(pinfunction "2")
			(pintype "passive")
			(teardrops
				(best_length_ratio 0.4)
				(max_length 1)
				(best_width_ratio 0.9)
				(max_width 2)
				(curved_edges yes)
				(filter_ratio 0.9)
				(enabled yes)
				(allow_two_segments yes)
				(prefer_zone_connections yes)
			)
		)
		(pad "SH" thru_hole circle
			(at -1.256 -2.492 270)
			(size 1.95 1.95)
			(drill 1.3)
			(layers "*.Cu" "*.Mask")
			(remove_unused_layers no)
			(net 1 "GND")
			(pinfunction "SH")
			(pintype "passive")
			(teardrops
				(best_length_ratio 0.4)
				(max_length 1)
				(best_width_ratio 0.9)
				(max_width 2)
				(curved_edges yes)
				(filter_ratio 0.9)
				(enabled yes)
				(allow_two_segments yes)
				(prefer_zone_connections yes)
			)
		)
		(pad "SH" thru_hole circle
			(at 5.754 -2.492 270)
			(size 1.95 1.95)
			(drill 1.3)
			(layers "*.Cu" "*.Mask")
			(remove_unused_layers no)
			(net 1 "GND")
			(pinfunction "SH")
			(pintype "passive")
			(teardrops
				(best_length_ratio 0.4)
				(max_length 1)
				(best_width_ratio 0.9)
				(max_width 2)
				(curved_edges yes)
				(filter_ratio 0.9)
				(enabled yes)
				(allow_two_segments yes)
				(prefer_zone_connections yes)
			)
		)
	)
	(footprint "antmicro-footprints:R_0402_1005Metric"
		(layer "F.Cu")
		(at 163.1 159.36 180)
		(descr "Resistor SMD 0402")
		(tags "resistor SMD 0402")
		(property "Reference" "R32"
			(at -0.8 -0.44 0)
			(layer "F.SilkS")
			(effects
				(font
					(size 0.7 0.7)
					(thickness 0.15)
				)
				(justify left bottom)
			)
		)
		(property "Value" "R_0R_0402"
			(at -1.011843 1.772047 0)
			(layer "F.Fab")
			(effects
				(font
					(size 0.7 0.7)
					(thickness 0.15)
				)
				(justify right bottom)
			)
		)
		(property "Datasheet" "https://industrial.panasonic.com/cdbs/www-data/pdf/RDA0000/AOA0000C301.pdf"
			(at 0 0 180)
			(layer "F.Fab")
			(hide yes)
			(effects
				(font
					(size 1.27 1.27)
					(thickness 0.15)
				)
			)
		)
		(property "Author" "Antmicro"
			(at 326.2 318.72 0)
			(layer "F.Fab")
			(hide yes)
			(effects
				(font
					(size 1 1)
					(thickness 0.15)
				)
			)
		)
		(property "Current" "1A"
			(at 326.2 318.72 0)
			(layer "F.Fab")
			(hide yes)
			(effects
				(font
					(size 1 1)
					(thickness 0.15)
				)
			)
		)
		(property "License" "Apache-2.0"
			(at 326.2 318.72 0)
			(layer "F.Fab")
			(hide yes)
			(effects
				(font
					(size 1 1)
					(thickness 0.15)
				)
			)
		)
		(property "MPN" "ERJ2GE0R00X"
			(at 326.2 318.72 0)
			(layer "F.Fab")
			(hide yes)
			(effects
				(font
					(size 1 1)
					(thickness 0.15)
				)
			)
		)
		(property "Manufacturer" "Panasonic"
			(at 326.2 318.72 0)
			(layer "F.Fab")
			(hide yes)
			(effects
				(font
					(size 1 1)
					(thickness 0.15)
				)
			)
		)
		(property "Public" "False"
			(at 326.2 318.72 0)
			(layer "F.Fab")
			(hide yes)
			(effects
				(font
					(size 1 1)
					(thickness 0.15)
				)
			)
		)
		(property "Tolerance" ""
			(at 326.2 318.72 0)
			(layer "F.Fab")
			(hide yes)
			(effects
				(font
					(size 1 1)
					(thickness 0.15)
				)
			)
		)
		(property "Val" "0R"
			(at 326.2 318.72 0)
			(layer "F.Fab")
			(hide yes)
			(effects
				(font
					(size 1 1)
					(thickness 0.15)
				)
			)
		)
		(sheetname "2xSFP+")
		(sheetfile "2xSFP+.kicad_sch")
		(attr smd dnp)
		(fp_rect
			(start -0.925 -0.47)
			(end 0.925 0.47)
			(stroke
				(width 0.05)
				(type default)
			)
			(fill no)
			(layer "F.CrtYd")
		)
		(fp_rect
			(start -0.5 -0.25)
			(end 0.5 0.25)
			(stroke
				(width 0.15)
				(type solid)
			)
			(fill no)
			(layer "F.Fab")
		)
		(pad "1" smd roundrect
			(at -0.48 0 180)
			(size 0.59 0.64)
			(layers "F.Cu" "F.Mask" "F.Paste")
			(roundrect_rratio 0.25)
			(net 1 "GND")
			(pintype "passive")
			(teardrops
				(best_length_ratio 0.2)
				(max_length 1)
				(best_width_ratio 0.9)
				(max_width 2)
				(curved_edges yes)
				(filter_ratio 0.9)
				(enabled yes)
				(allow_two_segments yes)
				(prefer_zone_connections yes)
			)
		)
		(pad "2" smd roundrect
			(at 0.48 0 180)
			(size 0.59 0.64)
			(layers "F.Cu" "F.Mask" "F.Paste")
			(roundrect_rratio 0.25)
			(net 557 "Net-(U5-A0)")
			(pintype "passive")
			(teardrops
				(best_length_ratio 0.2)
				(max_length 1)
				(best_width_ratio 0.9)
				(max_width 2)
				(curved_edges yes)
				(filter_ratio 0.9)
				(enabled yes)
				(allow_two_segments yes)
				(prefer_zone_connections yes)
			)
		)
	)
	(footprint "antmicro-footprints:Oscillator_SMD_Epson_SG3225EEN_3.2x2.5x1.2mm"
		(layer "F.Cu")
		(at 141.95 138.01 -90)
		(property "Reference" "Y2"
			(at 2.4 -0.55 0)
			(unlocked yes)
			(layer "F.SilkS")
			(effects
				(font
					(size 0.7 0.7)
					(thickness 0.15)
				)
				(justify left bottom)
			)
		)
		(property "Value" "Oscillator_156.25MHz_SG3225EEN"
			(at 0 3 270)
			(unlocked yes)
			(layer "F.Fab")
			(effects
				(font
					(size 0.7 0.7)
					(thickness 0.15)
				)
				(justify left bottom)
			)
		)
		(property "Datasheet" "https://support.epson.biz/td/api/doc_check.php?dl=brief_SG3225EEN&lang=en"
			(at 0 0 270)
			(layer "F.Fab")
			(hide yes)
			(effects
				(font
					(size 1.27 1.27)
					(thickness 0.15)
				)
			)
		)
		(property "Author" "Antmicro"
			(at 3.94 279.96 0)
			(layer "F.Fab")
			(hide yes)
			(effects
				(font
					(size 1 1)
					(thickness 0.15)
				)
			)
		)
		(property "License" "Apache-2.0"
			(at 3.94 279.96 0)
			(layer "F.Fab")
			(hide yes)
			(effects
				(font
					(size 1 1)
					(thickness 0.15)
				)
			)
		)
		(property "MPN" "SG3225EEN_156.250000M-CDGA3"
			(at 3.94 279.96 0)
			(layer "F.Fab")
			(hide yes)
			(effects
				(font
					(size 1 1)
					(thickness 0.15)
				)
			)
		)
		(property "Manufacturer" "Epson"
			(at 3.94 279.96 0)
			(layer "F.Fab")
			(hide yes)
			(effects
				(font
					(size 1 1)
					(thickness 0.15)
				)
			)
		)
		(property "Public" "False"
			(at 3.94 279.96 0)
			(layer "F.Fab")
			(hide yes)
			(effects
				(font
					(size 1 1)
					(thickness 0.15)
				)
			)
		)
		(property "Val" "156.25MHz"
			(at 3.94 279.96 0)
			(layer "F.Fab")
			(hide yes)
			(effects
				(font
					(size 1 1)
					(thickness 0.15)
				)
			)
		)
		(sheetname "KR to SFI #1")
		(sheetfile "kr_sfi.kicad_sch")
		(attr smd)
		(fp_line
			(start 1.25 1.925)
			(end -1.25 1.925)
			(stroke
				(width 0.15)
				(type solid)
			)
			(layer "F.SilkS")
		)
		(fp_line
			(start 1.25 -1.825)
			(end -1.25 -1.825)
			(stroke
				(width 0.15)
				(type solid)
			)
			(layer "F.SilkS")
		)
		(fp_circle
			(center -1.57 -1.87)
			(end -1.57 -1.82)
			(stroke
				(width 0.15)
				(type solid)
			)
			(fill yes)
			(layer "F.SilkS")
		)
		(fp_rect
			(start 1.58 -1.85)
			(end -1.6 1.96)
			(stroke
				(width 0.05)
				(type solid)
			)
			(fill no)
			(layer "F.CrtYd")
		)
		(pad "1" smd rect
			(at -0.925 -1.24 180)
			(size 0.92 1.05)
			(layers "F.Cu" "F.Mask" "F.Paste")
			(net 647 "Net-(Y2-EN)")
			(pinfunction "EN")
			(pintype "input")
			(solder_mask_margin 0.05)
			(teardrops
				(best_length_ratio 0.2)
				(max_length 1)
				(best_width_ratio 0.9)
				(max_width 2)
				(curved_edges yes)
				(filter_ratio 0.9)
				(enabled yes)
				(allow_two_segments yes)
				(prefer_zone_connections yes)
			)
		)
		(pad "2" smd rect
			(at -0.925 0.05 180)
			(size 0.8 1.05)
			(layers "F.Cu" "F.Mask" "F.Paste")
			(net 864 "unconnected-(Y2-NC-Pad2)")
			(pinfunction "NC")
			(pintype "no_connect")
			(solder_mask_margin 0.05)
			(teardrops
				(best_length_ratio 0.2)
				(max_length 1)
				(best_width_ratio 0.9)
				(max_width 2)
				(curved_edges yes)
				(filter_ratio 0.9)
				(enabled yes)
				(allow_two_segments yes)
				(prefer_zone_connections yes)
			)
		)
		(pad "3" smd rect
			(at -0.925 1.34 180)
			(size 0.92 1.05)
			(layers "F.Cu" "F.Mask" "F.Paste")
			(net 1 "GND")
			(pinfunction "GND")
			(pintype "power_in")
			(solder_mask_margin 0.05)
			(teardrops
				(best_length_ratio 0.2)
				(max_length 1)
				(best_width_ratio 0.9)
				(max_width 2)
				(curved_edges yes)
				(filter_ratio 0.9)
				(enabled yes)
				(allow_two_segments yes)
				(prefer_zone_connections yes)
			)
		)
		(pad "4" smd rect
			(at 0.925 1.34 180)
			(size 0.92 1.05)
			(layers "F.Cu" "F.Mask" "F.Paste")
			(net 107 "/2xSFP+/KR to SFI #1/CLK+")
			(pinfunction "OUT+")
			(pintype "output")
			(solder_mask_margin 0.05)
			(teardrops
				(best_length_ratio 0.2)
				(max_length 1)
				(best_width_ratio 0.9)
				(max_width 2)
				(curved_edges yes)
				(filter_ratio 0.9)
				(enabled yes)
				(allow_two_segments yes)
				(prefer_zone_connections yes)
			)
		)
		(pad "5" smd rect
			(at 0.925 0.05 180)
			(size 0.8 1.05)
			(layers "F.Cu" "F.Mask" "F.Paste")
			(net 109 "/2xSFP+/KR to SFI #1/CLK-")
			(pinfunction "OUT-")
			(pintype "output")
			(solder_mask_margin 0.05)
			(teardrops
				(best_length_ratio 0.2)
				(max_length 1)
				(best_width_ratio 0.9)
				(max_width 2)
				(curved_edges yes)
				(filter_ratio 0.9)
				(enabled yes)
				(allow_two_segments yes)
				(prefer_zone_connections yes)
			)
		)
		(pad "6" smd rect
			(at 0.925 -1.24 180)
			(size 0.92 1.05)
			(layers "F.Cu" "F.Mask" "F.Paste")
			(net 2 "+3V3")
			(pinfunction "VCC")
			(pintype "power_in")
			(solder_mask_margin 0.05)
			(teardrops
				(best_length_ratio 0.2)
				(max_length 1)
				(best_width_ratio 0.9)
				(max_width 2)
				(curved_edges yes)
				(filter_ratio 0.9)
				(enabled yes)
				(allow_two_segments yes)
				(prefer_zone_connections yes)
			)
		)
	)
	(footprint "antmicro-footprints:TP_SMD_0.75mm"
		(layer "F.Cu")
		(at 137.54 128.71)
		(property "Reference" "TP92"
			(at 0.51 -3.3 90)
			(layer "F.SilkS")
			(effects
				(font
					(size 0.7 0.7)
					(thickness 0.15)
				)
				(justify left bottom)
			)
		)
		(property "Value" "TP_0.75mm_SMD"
			(at 0 1.2 0)
			(layer "F.Fab")
			(effects
				(font
					(size 0.7 0.7)
					(thickness 0.15)
				)
				(justify left bottom)
			)
		)
		(property "Author" "Antmicro"
			(at 0 0 0)
			(layer "F.Fab")
			(hide yes)
			(effects
				(font
					(size 1 1)
					(thickness 0.15)
				)
			)
		)
		(property "License" "Apache-2.0"
			(at 0 0 0)
			(layer "F.Fab")
			(hide yes)
			(effects
				(font
					(size 1 1)
					(thickness 0.15)
				)
			)
		)
		(property "MPN" ""
			(at 0 0 0)
			(layer "F.Fab")
			(hide yes)
			(effects
				(font
					(size 1 1)
					(thickness 0.15)
				)
			)
		)
		(property "Manufacturer" ""
			(at 0 0 0)
			(layer "F.Fab")
			(hide yes)
			(effects
				(font
					(size 1 1)
					(thickness 0.15)
				)
			)
		)
		(property "Public" "False"
			(at 0 0 0)
			(layer "F.Fab")
			(hide yes)
			(effects
				(font
					(size 1 1)
					(thickness 0.15)
				)
			)
		)
		(sheetname "KR to SFI #2")
		(sheetfile "kr_sfi.kicad_sch")
		(attr exclude_from_pos_files exclude_from_bom)
		(fp_circle
			(center 0 0)
			(end 0.475 0)
			(stroke
				(width 0.05)
				(type default)
			)
			(fill no)
			(layer "F.CrtYd")
		)
		(pad "1" smd circle
			(at 0 0)
			(size 0.75 0.75)
			(layers "F.Cu" "F.Mask")
			(net 755 "Net-(U45A-LS_OK_{IN_A})")
			(pinfunction "1")
			(pintype "passive")
			(teardrops
				(best_length_ratio 0.4)
				(max_length 1)
				(best_width_ratio 0.9)
				(max_width 2)
				(curved_edges yes)
				(filter_ratio 0.9)
				(enabled yes)
				(allow_two_segments yes)
				(prefer_zone_connections yes)
			)
		)
	)
	(footprint "antmicro-footprints:R_0402_1005Metric"
		(layer "F.Cu")
		(at 113.4 144.36 90)
		(descr "Resistor SMD 0402")
		(tags "resistor SMD 0402")
		(property "Reference" "R213"
			(at 0.8 0.4 90)
			(layer "F.SilkS")
			(effects
				(font
					(size 0.7 0.7)
					(thickness 0.15)
				)
				(justify left bottom)
			)
		)
		(property "Value" "R_1k_0402"
			(at -1.011843 1.772047 90)
			(layer "F.Fab")
			(effects
				(font
					(size 0.7 0.7)
					(thickness 0.15)
				)
				(justify left bottom)
			)
		)
		(property "Datasheet" "https://www.bourns.com/docs/product-datasheets/cr.pdf"
			(at 0 0 90)
			(layer "F.Fab")
			(hide yes)
			(effects
				(font
					(size 1.27 1.27)
					(thickness 0.15)
				)
			)
		)
		(property "Author" "Antmicro"
			(at 257.76 30.96 0)
			(layer "F.Fab")
			(hide yes)
			(effects
				(font
					(size 1 1)
					(thickness 0.15)
				)
			)
		)
		(property "License" "Apache-2.0"
			(at 257.76 30.96 0)
			(layer "F.Fab")
			(hide yes)
			(effects
				(font
					(size 1 1)
					(thickness 0.15)
				)
			)
		)
		(property "MPN" "CR0402-FX-1001GLF"
			(at 257.76 30.96 0)
			(layer "F.Fab")
			(hide yes)
			(effects
				(font
					(size 1 1)
					(thickness 0.15)
				)
			)
		)
		(property "Manufacturer" "Bourns"
			(at 257.76 30.96 0)
			(layer "F.Fab")
			(hide yes)
			(effects
				(font
					(size 1 1)
					(thickness 0.15)
				)
			)
		)
		(property "Public" "False"
			(at 257.76 30.96 0)
			(layer "F.Fab")
			(hide yes)
			(effects
				(font
					(size 1 1)
					(thickness 0.15)
				)
			)
		)
		(property "Tolerance" "1%"
			(at 257.76 30.96 0)
			(layer "F.Fab")
			(hide yes)
			(effects
				(font
					(size 1 1)
					(thickness 0.15)
				)
			)
		)
		(property "Val" "1k"
			(at 257.76 30.96 0)
			(layer "F.Fab")
			(hide yes)
			(effects
				(font
					(size 1 1)
					(thickness 0.15)
				)
			)
		)
		(sheetname "PCIe redriver")
		(sheetfile "pcie_redriver.kicad_sch")
		(attr smd dnp)
		(fp_rect
			(start -0.925 -0.47)
			(end 0.925 0.47)
			(stroke
				(width 0.05)
				(type default)
			)
			(fill no)
			(layer "F.CrtYd")
		)
		(fp_rect
			(start -0.5 -0.25)
			(end 0.5 0.25)
			(stroke
				(width 0.15)
				(type solid)
			)
			(fill no)
			(layer "F.Fab")
		)
		(pad "1" smd roundrect
			(at -0.48 0 90)
			(size 0.59 0.64)
			(layers "F.Cu" "F.Mask" "F.Paste")
			(roundrect_rratio 0.25)
			(net 1 "GND")
			(pintype "passive")
			(teardrops
				(best_length_ratio 0.2)
				(max_length 1)
				(best_width_ratio 0.9)
				(max_width 2)
				(curved_edges yes)
				(filter_ratio 0.9)
				(enabled yes)
				(allow_two_segments yes)
				(prefer_zone_connections yes)
			)
		)
		(pad "2" smd roundrect
			(at 0.48 0 90)
			(size 0.59 0.64)
			(layers "F.Cu" "F.Mask" "F.Paste")
			(roundrect_rratio 0.25)
			(net 628 "/PCIe redriver/TX_SW")
			(pintype "passive")
			(teardrops
				(best_length_ratio 0.2)
				(max_length 1)
				(best_width_ratio 0.9)
				(max_width 2)
				(curved_edges yes)
				(filter_ratio 0.9)
				(enabled yes)
				(allow_two_segments yes)
				(prefer_zone_connections yes)
			)
		)
	)
	(footprint "antmicro-footprints:R_0201"
		(layer "F.Cu")
		(at 131.41 147.961 -90)
		(descr "Resistor SMD 0201")
		(tags "resistor SMD 0201")
		(property "Reference" "R311"
			(at 3.6 -0.29 90)
			(layer "F.SilkS")
			(effects
				(font
					(size 0.7 0.7)
					(thickness 0.15)
				)
				(justify right bottom)
			)
		)
		(property "Value" "R_0R_0201"
			(at 0 1.25 90)
			(layer "F.Fab")
			(effects
				(font
					(size 0.7 0.7)
					(thickness 0.15)
				)
				(justify right bottom)
			)
		)
		(property "Datasheet" "https://www.bourns.com/docs/product-datasheets/cr.pdf"
			(at 0 0 270)
			(layer "F.Fab")
			(hide yes)
			(effects
				(font
					(size 1.27 1.27)
					(thickness 0.15)
				)
			)
		)
		(property "Author" "Antmicro"
			(at -16.551 279.371 0)
			(layer "F.Fab")
			(hide yes)
			(effects
				(font
					(size 1 1)
					(thickness 0.15)
				)
			)
		)
		(property "License" "Apache-2.0"
			(at -16.551 279.371 0)
			(layer "F.Fab")
			(hide yes)
			(effects
				(font
					(size 1 1)
					(thickness 0.15)
				)
			)
		)
		(property "MPN" "CR0201-FX-0R00GLF"
			(at -16.551 279.371 0)
			(layer "F.Fab")
			(hide yes)
			(effects
				(font
					(size 1 1)
					(thickness 0.15)
				)
			)
		)
		(property "Manufacturer" "Bourns"
			(at -16.551 279.371 0)
			(layer "F.Fab")
			(hide yes)
			(effects
				(font
					(size 1 1)
					(thickness 0.15)
				)
			)
		)
		(property "Tolerance" "1%"
			(at -16.551 279.371 0)
			(layer "F.Fab")
			(hide yes)
			(effects
				(font
					(size 1 1)
					(thickness 0.15)
				)
			)
		)
		(property "Val" "0R"
			(at -16.551 279.371 0)
			(layer "F.Fab")
			(hide yes)
			(effects
				(font
					(size 1 1)
					(thickness 0.15)
				)
			)
		)
		(sheetname "KR to SFI #2")
		(sheetfile "kr_sfi.kicad_sch")
		(attr smd dnp)
		(fp_rect
			(start -0.7 -0.35)
			(end 0.7 0.35)
			(stroke
				(width 0.05)
				(type default)
			)
			(fill no)
			(layer "F.CrtYd")
		)
		(fp_rect
			(start -0.3 -0.15)
			(end 0.298 0.148)
			(stroke
				(width 0.15)
				(type solid)
			)
			(fill no)
			(layer "F.Fab")
		)
		(pad "" smd roundrect
			(at -0.346 0 270)
			(size 0.318 0.36)
			(layers "F.Paste")
			(roundrect_rratio 0.25)
			(teardrops
				(best_length_ratio 0.2)
				(max_length 1)
				(best_width_ratio 0.9)
				(max_width 2)
				(curved_edges yes)
				(filter_ratio 0.9)
				(enabled yes)
				(allow_two_segments yes)
				(prefer_zone_connections yes)
			)
		)
		(pad "" smd roundrect
			(at 0.344 0 270)
			(size 0.318 0.36)
			(layers "F.Paste")
			(roundrect_rratio 0.25)
			(teardrops
				(best_length_ratio 0.2)
				(max_length 1)
				(best_width_ratio 0.9)
				(max_width 2)
				(curved_edges yes)
				(filter_ratio 0.9)
				(enabled yes)
				(allow_two_segments yes)
				(prefer_zone_connections yes)
			)
		)
		(pad "1" smd roundrect
			(at -0.32 0 270)
			(size 0.46 0.4)
			(layers "F.Cu" "F.Mask")
			(roundrect_rratio 0.25)
			(net 878 "/2xSFP+/SFI1.RX+")
			(pintype "passive")
			(teardrops
				(best_length_ratio 0.2)
				(max_length 1)
				(best_width_ratio 0.9)
				(max_width 2)
				(curved_edges yes)
				(filter_ratio 0.9)
				(enabled yes)
				(allow_two_segments yes)
				(prefer_zone_connections yes)
			)
		)
		(pad "2" smd roundrect
			(at 0.32 0 270)
			(size 0.46 0.4)
			(layers "F.Cu" "F.Mask")
			(roundrect_rratio 0.25)
			(net 949 "/2xSFP+/KR to SFI #2/BYP_RX+")
			(pintype "passive")
			(teardrops
				(best_length_ratio 0.2)
				(max_length 1)
				(best_width_ratio 0.9)
				(max_width 2)
				(curved_edges yes)
				(filter_ratio 0.9)
				(enabled yes)
				(allow_two_segments yes)
				(prefer_zone_connections yes)
			)
		)
	)
	(footprint "antmicro-footprints:C_0402_1005Metric"
		(layer "F.Cu")
		(at 236.7 154.46 90)
		(descr "Capacitor SMD 0402")
		(tags "capacitor SMD 0402")
		(property "Reference" "C100"
			(at -1.4 -0.5 90)
			(layer "F.SilkS")
			(effects
				(font
					(size 0.7 0.7)
					(thickness 0.15)
				)
				(justify left bottom)
			)
		)
		(property "Value" "C_100n_0402"
			(at -1.022927 2.155213 90)
			(layer "F.Fab")
			(effects
				(font
					(size 0.7 0.7)
					(thickness 0.15)
				)
				(justify left bottom)
			)
		)
		(property "Datasheet" "https://www.murata.com/products/productdetail?partno=GRM155R61H104KE14%23"
			(at 0 0 90)
			(layer "F.Fab")
			(hide yes)
			(effects
				(font
					(size 1.27 1.27)
					(thickness 0.15)
				)
			)
		)
		(property "Author" "Antmicro"
			(at 391.16 -82.24 0)
			(layer "F.Fab")
			(hide yes)
			(effects
				(font
					(size 1 1)
					(thickness 0.15)
				)
			)
		)
		(property "Dielectric" "X5R"
			(at 391.16 -82.24 0)
			(layer "F.Fab")
			(hide yes)
			(effects
				(font
					(size 1 1)
					(thickness 0.15)
				)
			)
		)
		(property "License" "Apache-2.0"
			(at 391.16 -82.24 0)
			(layer "F.Fab")
			(hide yes)
			(effects
				(font
					(size 1 1)
					(thickness 0.15)
				)
			)
		)
		(property "MPN" "GRM155R61H104KE14D"
			(at 391.16 -82.24 0)
			(layer "F.Fab")
			(hide yes)
			(effects
				(font
					(size 1 1)
					(thickness 0.15)
				)
			)
		)
		(property "Manufacturer" "Murata"
			(at 391.16 -82.24 0)
			(layer "F.Fab")
			(hide yes)
			(effects
				(font
					(size 1 1)
					(thickness 0.15)
				)
			)
		)
		(property "Public" "False"
			(at 391.16 -82.24 0)
			(layer "F.Fab")
			(hide yes)
			(effects
				(font
					(size 1 1)
					(thickness 0.15)
				)
			)
		)
		(property "Val" "100n"
			(at 391.16 -82.24 0)
			(layer "F.Fab")
			(hide yes)
			(effects
				(font
					(size 1 1)
					(thickness 0.15)
				)
			)
		)
		(property "Voltage" "50V"
			(at 391.16 -82.24 0)
			(layer "F.Fab")
			(hide yes)
			(effects
				(font
					(size 1 1)
					(thickness 0.15)
				)
			)
		)
		(sheetname "Com Express 7 MGMT")
		(sheetfile "com_express_7_mgmt.kicad_sch")
		(attr smd)
		(fp_rect
			(start -0.925 -0.47)
			(end 0.925 0.47)
			(stroke
				(width 0.05)
				(type default)
			)
			(fill no)
			(layer "F.CrtYd")
		)
		(fp_line
			(start 0.504 -0.25)
			(end 0.504 0.248)
			(stroke
				(width 0.15)
				(type solid)
			)
			(layer "F.Fab")
		)
		(fp_line
			(start -0.494 -0.25)
			(end 0.504 -0.25)
			(stroke
				(width 0.15)
				(type solid)
			)
			(layer "F.Fab")
		)
		(fp_line
			(start 0.504 0.248)
			(end -0.494 0.248)
			(stroke
				(width 0.15)
				(type solid)
			)
			(layer "F.Fab")
		)
		(fp_line
			(start -0.494 0.248)
			(end -0.494 -0.25)
			(stroke
				(width 0.15)
				(type solid)
			)
			(layer "F.Fab")
		)
		(pad "1" smd roundrect
			(at -0.48 0 90)
			(size 0.59 0.64)
			(layers "F.Cu" "F.Mask" "F.Paste")
			(roundrect_rratio 0.25)
			(net 1 "GND")
			(pintype "passive")
			(teardrops
				(best_length_ratio 0.2)
				(max_length 1)
				(best_width_ratio 0.9)
				(max_width 2)
				(curved_edges yes)
				(filter_ratio 0.9)
				(enabled yes)
				(allow_two_segments yes)
				(prefer_zone_connections yes)
			)
		)
		(pad "2" smd roundrect
			(at 0.48 0 90)
			(size 0.59 0.64)
			(layers "F.Cu" "F.Mask" "F.Paste")
			(roundrect_rratio 0.25)
			(net 73 "+3V3_AON")
			(pintype "passive")
			(teardrops
				(best_length_ratio 0.2)
				(max_length 1)
				(best_width_ratio 0.9)
				(max_width 2)
				(curved_edges yes)
				(filter_ratio 0.9)
				(enabled yes)
				(allow_two_segments yes)
				(prefer_zone_connections yes)
			)
		)
	)
	(footprint "antmicro-footprints:R_0402_1005Metric"
		(layer "F.Cu")
		(at 134.425001 83.310001 180)
		(descr "Resistor SMD 0402")
		(tags "resistor SMD 0402")
		(property "Reference" "R232"
			(at -3.624999 -0.449999 0)
			(layer "F.SilkS")
			(effects
				(font
					(size 0.7 0.7)
					(thickness 0.15)
				)
				(justify right bottom)
			)
		)
		(property "Value" "R_0R_0402"
			(at -1.011843 1.772047 0)
			(layer "F.Fab")
			(effects
				(font
					(size 0.7 0.7)
					(thickness 0.15)
				)
				(justify right bottom)
			)
		)
		(property "Datasheet" "https://industrial.panasonic.com/cdbs/www-data/pdf/RDA0000/AOA0000C301.pdf"
			(at 0 0 180)
			(layer "F.Fab")
			(hide yes)
			(effects
				(font
					(size 1.27 1.27)
					(thickness 0.15)
				)
			)
		)
		(property "Author" "Antmicro"
			(at 268.850002 166.620002 0)
			(layer "F.Fab")
			(hide yes)
			(effects
				(font
					(size 1 1)
					(thickness 0.15)
				)
			)
		)
		(property "Current" "1A"
			(at 268.850002 166.620002 0)
			(layer "F.Fab")
			(hide yes)
			(effects
				(font
					(size 1 1)
					(thickness 0.15)
				)
			)
		)
		(property "License" "Apache-2.0"
			(at 268.850002 166.620002 0)
			(layer "F.Fab")
			(hide yes)
			(effects
				(font
					(size 1 1)
					(thickness 0.15)
				)
			)
		)
		(property "MPN" "ERJ2GE0R00X"
			(at 268.850002 166.620002 0)
			(layer "F.Fab")
			(hide yes)
			(effects
				(font
					(size 1 1)
					(thickness 0.15)
				)
			)
		)
		(property "Manufacturer" "Panasonic"
			(at 268.850002 166.620002 0)
			(layer "F.Fab")
			(hide yes)
			(effects
				(font
					(size 1 1)
					(thickness 0.15)
				)
			)
		)
		(property "Public" "False"
			(at 268.850002 166.620002 0)
			(layer "F.Fab")
			(hide yes)
			(effects
				(font
					(size 1 1)
					(thickness 0.15)
				)
			)
		)
		(property "Tolerance" ""
			(at 268.850002 166.620002 0)
			(layer "F.Fab")
			(hide yes)
			(effects
				(font
					(size 1 1)
					(thickness 0.15)
				)
			)
		)
		(property "Val" "0R"
			(at 268.850002 166.620002 0)
			(layer "F.Fab")
			(hide yes)
			(effects
				(font
					(size 1 1)
					(thickness 0.15)
				)
			)
		)
		(sheetname "GPIO expander")
		(sheetfile "gpio_exp.kicad_sch")
		(attr smd)
		(fp_rect
			(start -0.925 -0.47)
			(end 0.925 0.47)
			(stroke
				(width 0.05)
				(type default)
			)
			(fill no)
			(layer "F.CrtYd")
		)
		(fp_rect
			(start -0.5 -0.25)
			(end 0.5 0.25)
			(stroke
				(width 0.15)
				(type solid)
			)
			(fill no)
			(layer "F.Fab")
		)
		(pad "1" smd roundrect
			(at -0.48 0 180)
			(size 0.59 0.64)
			(layers "F.Cu" "F.Mask" "F.Paste")
			(roundrect_rratio 0.25)
			(net 1 "GND")
			(pintype "passive")
			(teardrops
				(best_length_ratio 0.2)
				(max_length 1)
				(best_width_ratio 0.9)
				(max_width 2)
				(curved_edges yes)
				(filter_ratio 0.9)
				(enabled yes)
				(allow_two_segments yes)
				(prefer_zone_connections yes)
			)
		)
		(pad "2" smd roundrect
			(at 0.48 0 180)
			(size 0.59 0.64)
			(layers "F.Cu" "F.Mask" "F.Paste")
			(roundrect_rratio 0.25)
			(net 633 "Net-(U41-A0)")
			(pintype "passive")
			(teardrops
				(best_length_ratio 0.2)
				(max_length 1)
				(best_width_ratio 0.9)
				(max_width 2)
				(curved_edges yes)
				(filter_ratio 0.9)
				(enabled yes)
				(allow_two_segments yes)
				(prefer_zone_connections yes)
			)
		)
	)
	(footprint "antmicro-footprints:R_0402_1005Metric"
		(layer "F.Cu")
		(at 126.425 88.06 180)
		(descr "Resistor SMD 0402")
		(tags "resistor SMD 0402")
		(property "Reference" "R243"
			(at -1.575 -6.4 0)
			(layer "F.SilkS")
			(effects
				(font
					(size 0.7 0.7)
					(thickness 0.15)
				)
				(justify right bottom)
			)
		)
		(property "Value" "R_0R_0402"
			(at -1.011843 1.772047 0)
			(layer "F.Fab")
			(effects
				(font
					(size 0.7 0.7)
					(thickness 0.15)
				)
				(justify right bottom)
			)
		)
		(property "Datasheet" "https://industrial.panasonic.com/cdbs/www-data/pdf/RDA0000/AOA0000C301.pdf"
			(at 0 0 180)
			(layer "F.Fab")
			(hide yes)
			(effects
				(font
					(size 1.27 1.27)
					(thickness 0.15)
				)
			)
		)
		(property "Author" "Antmicro"
			(at 252.85 176.12 0)
			(layer "F.Fab")
			(hide yes)
			(effects
				(font
					(size 1 1)
					(thickness 0.15)
				)
			)
		)
		(property "Current" "1A"
			(at 252.85 176.12 0)
			(layer "F.Fab")
			(hide yes)
			(effects
				(font
					(size 1 1)
					(thickness 0.15)
				)
			)
		)
		(property "License" "Apache-2.0"
			(at 252.85 176.12 0)
			(layer "F.Fab")
			(hide yes)
			(effects
				(font
					(size 1 1)
					(thickness 0.15)
				)
			)
		)
		(property "MPN" "ERJ2GE0R00X"
			(at 252.85 176.12 0)
			(layer "F.Fab")
			(hide yes)
			(effects
				(font
					(size 1 1)
					(thickness 0.15)
				)
			)
		)
		(property "Manufacturer" "Panasonic"
			(at 252.85 176.12 0)
			(layer "F.Fab")
			(hide yes)
			(effects
				(font
					(size 1 1)
					(thickness 0.15)
				)
			)
		)
		(property "Public" "False"
			(at 252.85 176.12 0)
			(layer "F.Fab")
			(hide yes)
			(effects
				(font
					(size 1 1)
					(thickness 0.15)
				)
			)
		)
		(property "Tolerance" ""
			(at 252.85 176.12 0)
			(layer "F.Fab")
			(hide yes)
			(effects
				(font
					(size 1 1)
					(thickness 0.15)
				)
			)
		)
		(property "Val" "0R"
			(at 252.85 176.12 0)
			(layer "F.Fab")
			(hide yes)
			(effects
				(font
					(size 1 1)
					(thickness 0.15)
				)
			)
		)
		(sheetname "GPIO expander")
		(sheetfile "gpio_exp.kicad_sch")
		(attr smd)
		(fp_rect
			(start -0.925 -0.47)
			(end 0.925 0.47)
			(stroke
				(width 0.05)
				(type default)
			)
			(fill no)
			(layer "F.CrtYd")
		)
		(fp_rect
			(start -0.5 -0.25)
			(end 0.5 0.25)
			(stroke
				(width 0.15)
				(type solid)
			)
			(fill no)
			(layer "F.Fab")
		)
		(pad "1" smd roundrect
			(at -0.48 0 180)
			(size 0.59 0.64)
			(layers "F.Cu" "F.Mask" "F.Paste")
			(roundrect_rratio 0.25)
			(net 644 "Net-(U41-IO0_5)")
			(pintype "passive")
			(teardrops
				(best_length_ratio 0.2)
				(max_length 1)
				(best_width_ratio 0.9)
				(max_width 2)
				(curved_edges yes)
				(filter_ratio 0.9)
				(enabled yes)
				(allow_two_segments yes)
				(prefer_zone_connections yes)
			)
		)
		(pad "2" smd roundrect
			(at 0.48 0 180)
			(size 0.59 0.64)
			(layers "F.Cu" "F.Mask" "F.Paste")
			(roundrect_rratio 0.25)
			(net 945 "/GPIO expander/GPIOEX5")
			(pintype "passive")
			(teardrops
				(best_length_ratio 0.2)
				(max_length 1)
				(best_width_ratio 0.9)
				(max_width 2)
				(curved_edges yes)
				(filter_ratio 0.9)
				(enabled yes)
				(allow_two_segments yes)
				(prefer_zone_connections yes)
			)
		)
	)
	(footprint "antmicro-footprints:R_0402_1005Metric"
		(layer "F.Cu")
		(at 122.05 89.96 180)
		(descr "Resistor SMD 0402")
		(tags "resistor SMD 0402")
		(property "Reference" "R29"
			(at -2.95 -0.44 0)
			(layer "F.SilkS")
			(effects
				(font
					(size 0.7 0.7)
					(thickness 0.15)
				)
				(justify right bottom)
			)
		)
		(property "Value" "R_0R_0402"
			(at -1.011843 1.772047 0)
			(layer "F.Fab")
			(effects
				(font
					(size 0.7 0.7)
					(thickness 0.15)
				)
				(justify right bottom)
			)
		)
		(property "Datasheet" "https://industrial.panasonic.com/cdbs/www-data/pdf/RDA0000/AOA0000C301.pdf"
			(at 0 0 180)
			(layer "F.Fab")
			(hide yes)
			(effects
				(font
					(size 1.27 1.27)
					(thickness 0.15)
				)
			)
		)
		(property "Author" "Antmicro"
			(at 244.1 179.92 0)
			(layer "F.Fab")
			(hide yes)
			(effects
				(font
					(size 1 1)
					(thickness 0.15)
				)
			)
		)
		(property "Current" "1A"
			(at 244.1 179.92 0)
			(layer "F.Fab")
			(hide yes)
			(effects
				(font
					(size 1 1)
					(thickness 0.15)
				)
			)
		)
		(property "License" "Apache-2.0"
			(at 244.1 179.92 0)
			(layer "F.Fab")
			(hide yes)
			(effects
				(font
					(size 1 1)
					(thickness 0.15)
				)
			)
		)
		(property "MPN" "ERJ2GE0R00X"
			(at 244.1 179.92 0)
			(layer "F.Fab")
			(hide yes)
			(effects
				(font
					(size 1 1)
					(thickness 0.15)
				)
			)
		)
		(property "Manufacturer" "Panasonic"
			(at 244.1 179.92 0)
			(layer "F.Fab")
			(hide yes)
			(effects
				(font
					(size 1 1)
					(thickness 0.15)
				)
			)
		)
		(property "Public" "False"
			(at 244.1 179.92 0)
			(layer "F.Fab")
			(hide yes)
			(effects
				(font
					(size 1 1)
					(thickness 0.15)
				)
			)
		)
		(property "Tolerance" ""
			(at 244.1 179.92 0)
			(layer "F.Fab")
			(hide yes)
			(effects
				(font
					(size 1 1)
					(thickness 0.15)
				)
			)
		)
		(property "Val" "0R"
			(at 244.1 179.92 0)
			(layer "F.Fab")
			(hide yes)
			(effects
				(font
					(size 1 1)
					(thickness 0.15)
				)
			)
		)
		(sheetname "2xUSB3.0+RJ45")
		(sheetfile "usb3+rj45.kicad_sch")
		(attr smd)
		(fp_rect
			(start -0.925 -0.47)
			(end 0.925 0.47)
			(stroke
				(width 0.05)
				(type default)
			)
			(fill no)
			(layer "F.CrtYd")
		)
		(fp_rect
			(start -0.5 -0.25)
			(end 0.5 0.25)
			(stroke
				(width 0.15)
				(type solid)
			)
			(fill no)
			(layer "F.Fab")
		)
		(pad "1" smd roundrect
			(at -0.48 0 180)
			(size 0.59 0.64)
			(layers "F.Cu" "F.Mask" "F.Paste")
			(roundrect_rratio 0.25)
			(net 942 "/2xUSB3.0+RJ45/EN_2")
			(pintype "passive")
			(teardrops
				(best_length_ratio 0.2)
				(max_length 1)
				(best_width_ratio 0.9)
				(max_width 2)
				(curved_edges yes)
				(filter_ratio 0.9)
				(enabled yes)
				(allow_two_segments yes)
				(prefer_zone_connections yes)
			)
		)
		(pad "2" smd roundrect
			(at 0.48 0 180)
			(size 0.59 0.64)
			(layers "F.Cu" "F.Mask" "F.Paste")
			(roundrect_rratio 0.25)
			(net 556 "/2xUSB3.0+RJ45/EN_2B")
			(pintype "passive")
			(teardrops
				(best_length_ratio 0.2)
				(max_length 1)
				(best_width_ratio 0.9)
				(max_width 2)
				(curved_edges yes)
				(filter_ratio 0.9)
				(enabled yes)
				(allow_two_segments yes)
				(prefer_zone_connections yes)
			)
		)
	)
	(footprint "antmicro-footprints:Spacer_Drill3.7mm_H2.5mm_9774025151R"
		(layer "F.Cu")
		(at 120.0745 80.3095 -90)
		(descr "Spacer M=3 h=2.5mm fi=5.1mm")
		(property "Reference" "H3"
			(at -0.1095 -4.1255 90)
			(layer "F.SilkS")
			(hide yes)
			(effects
				(font
					(size 0.7 0.7)
					(thickness 0.15)
				)
				(justify right bottom)
			)
		)
		(property "Value" "Spacer_Drill3.7mm_H2.5mm_9774025151R"
			(at 0 4 90)
			(layer "F.Fab")
			(effects
				(font
					(size 0.7 0.7)
					(thickness 0.15)
				)
				(justify right bottom)
			)
		)
		(property "Datasheet" "https://www.we-online.com/components/products/datasheet/9774025151R.pdf"
			(at 0 0 270)
			(layer "F.Fab")
			(hide yes)
			(effects
				(font
					(size 1.27 1.27)
					(thickness 0.15)
				)
			)
		)
		(property "Author" "Antmicro"
			(at 39.765 200.384 0)
			(layer "F.Fab")
			(hide yes)
			(effects
				(font
					(size 1 1)
					(thickness 0.15)
				)
			)
		)
		(property "License" "Apache-2.0"
			(at 39.765 200.384 0)
			(layer "F.Fab")
			(hide yes)
			(effects
				(font
					(size 1 1)
					(thickness 0.15)
				)
			)
		)
		(property "MPN" "9774025151R"
			(at 39.765 200.384 0)
			(layer "F.Fab")
			(hide yes)
			(effects
				(font
					(size 1 1)
					(thickness 0.15)
				)
			)
		)
		(property "Manufacturer" "Würth Elektronik"
			(at 39.765 200.384 0)
			(layer "F.Fab")
			(hide yes)
			(effects
				(font
					(size 1 1)
					(thickness 0.15)
				)
			)
		)
		(property "Public" "False"
			(at 39.765 200.384 0)
			(layer "F.Fab")
			(hide yes)
			(effects
				(font
					(size 1 1)
					(thickness 0.15)
				)
			)
		)
		(sheetname "M.2 key E")
		(sheetfile "m2keye.kicad_sch")
		(solder_paste_margin_ratio -1)
		(attr smd)
		(fp_circle
			(center 0 0)
			(end 3.05 0)
			(stroke
				(width 0.05)
				(type solid)
			)
			(fill no)
			(layer "F.CrtYd")
		)
		(fp_circle
			(center 0 0)
			(end 2.6 0)
			(stroke
				(width 0.15)
				(type solid)
			)
			(fill no)
			(layer "F.Fab")
		)
		(pad "" smd custom
			(at -1.7 -1.7 270)
			(size 0.62 0.62)
			(layers "F.Paste")
			(thermal_bridge_angle 90)
			(options
				(clearance outline)
				(anchor circle)
			)
			(primitives
				(gr_arc
					(start -0.250195 1.279127)
					(mid 0.285453 0.294389)
					(end 1.266786 -0.24747)
					(width 0.2)
				)
				(gr_arc
					(start -0.34334 1.279127)
					(mid 0.218448 0.232561)
					(end 1.259603 -0.339191)
					(width 0.2)
				)
				(gr_arc
					(start -0.436309 1.279127)
					(mid 0.152481 0.169693)
					(end 1.255279 -0.431435)
					(width 0.2)
				)
				(gr_arc
					(start -0.529126 1.279127)
					(mid 0.087542 0.105784)
					(end 1.253811 -0.524161)
					(width 0.2)
				)
				(gr_arc
					(start -0.621807 1.279127)
					(mid 0.0309 0.033527)
					(end 1.275473 -0.621136)
					(width 0.2)
				)
				(gr_arc
					(start -0.71437 1.279127)
					(mid -0.037758 -0.026651)
					(end 1.263664 -0.711602)
					(width 0.2)
				)
				(gr_arc
					(start -0.806826 1.279127)
					(mid -0.105837 -0.087395)
					(end 1.253435 -0.802342)
					(width 0.2)
				)
				(gr_arc
					(start -0.899187 1.279127)
					(mid -0.165236 -0.156885)
					(end 1.267475 -0.897258)
					(width 0.2)
				)
				(gr_arc
					(start -0.991463 1.279127)
					(mid -0.228522 -0.222449)
					(end 1.270645 -0.990112)
					(width 0.2)
				)
				(gr_arc
					(start -1.083663 1.279127)
					(mid -0.294507 -0.285313)
					(end 1.266278 -1.081674)
					(width 0.2)
				)
				(gr_line
					(start 1.279127 -0.250195)
					(end 1.279127 -1.083663)
					(width 0.2)
				)
				(gr_line
					(start -0.250195 1.279127)
					(end -1.083663 1.279127)
					(width 0.2)
				)
			)
			(teardrops
				(best_length_ratio 0.2)
				(max_length 1)
				(best_width_ratio 0.9)
				(max_width 2)
				(curved_edges yes)
				(filter_ratio 0.9)
				(enabled yes)
				(allow_two_segments yes)
				(prefer_zone_connections yes)
			)
		)
		(pad "" smd custom
			(at -1.7 1.7)
			(size 0.62 0.62)
			(layers "F.Paste")
			(thermal_bridge_angle 90)
			(options
				(clearance outline)
				(anchor circle)
			)
			(primitives
				(gr_arc
					(start -0.250195 1.279127)
					(mid 0.285453 0.294389)
					(end 1.266786 -0.24747)
					(width 0.2)
				)
				(gr_arc
					(start -0.34334 1.279127)
					(mid 0.218448 0.232561)
					(end 1.259603 -0.339191)
					(width 0.2)
				)
				(gr_arc
					(start -0.436309 1.279127)
					(mid 0.152481 0.169693)
					(end 1.255279 -0.431435)
					(width 0.2)
				)
				(gr_arc
					(start -0.529126 1.279127)
					(mid 0.087542 0.105784)
					(end 1.253811 -0.524161)
					(width 0.2)
				)
				(gr_arc
					(start -0.621807 1.279127)
					(mid 0.0309 0.033527)
					(end 1.275473 -0.621136)
					(width 0.2)
				)
				(gr_arc
					(start -0.71437 1.279127)
					(mid -0.037758 -0.026651)
					(end 1.263664 -0.711602)
					(width 0.2)
				)
				(gr_arc
					(start -0.806826 1.279127)
					(mid -0.105837 -0.087395)
					(end 1.253435 -0.802342)
					(width 0.2)
				)
				(gr_arc
					(start -0.899187 1.279127)
					(mid -0.165236 -0.156885)
					(end 1.267475 -0.897258)
					(width 0.2)
				)
				(gr_arc
					(start -0.991463 1.279127)
					(mid -0.228522 -0.222449)
					(end 1.270645 -0.990112)
					(width 0.2)
				)
				(gr_arc
					(start -1.083663 1.279127)
					(mid -0.294507 -0.285313)
					(end 1.266278 -1.081674)
					(width 0.2)
				)
				(gr_line
					(start 1.279127 -0.250195)
					(end 1.279127 -1.083663)
					(width 0.2)
				)
				(gr_line
					(start -0.250195 1.279127)
					(end -1.083663 1.279127)
					(width 0.2)
				)
			)
			(teardrops
				(best_length_ratio 0.2)
				(max_length 1)
				(best_width_ratio 0.9)
				(max_width 2)
				(curved_edges yes)
				(filter_ratio 0.9)
				(enabled yes)
				(allow_two_segments yes)
				(prefer_zone_connections yes)
			)
		)
		(pad "" smd custom
			(at 1.7 -1.7 180)
			(size 0.62 0.62)
			(layers "F.Paste")
			(thermal_bridge_angle 90)
			(options
				(clearance outline)
				(anchor circle)
			)
			(primitives
				(gr_arc
					(start -0.250195 1.279127)
					(mid 0.285453 0.294389)
					(end 1.266786 -0.24747)
					(width 0.2)
				)
				(gr_arc
					(start -0.34334 1.279127)
					(mid 0.218448 0.232561)
					(end 1.259603 -0.339191)
					(width 0.2)
				)
				(gr_arc
					(start -0.436309 1.279127)
					(mid 0.152481 0.169693)
					(end 1.255279 -0.431435)
					(width 0.2)
				)
				(gr_arc
					(start -0.529126 1.279127)
					(mid 0.087542 0.105784)
					(end 1.253811 -0.524161)
					(width 0.2)
				)
				(gr_arc
					(start -0.621807 1.279127)
					(mid 0.0309 0.033527)
					(end 1.275473 -0.621136)
					(width 0.2)
				)
				(gr_arc
					(start -0.71437 1.279127)
					(mid -0.037758 -0.026651)
					(end 1.263664 -0.711602)
					(width 0.2)
				)
				(gr_arc
					(start -0.806826 1.279127)
					(mid -0.105837 -0.087395)
					(end 1.253435 -0.802342)
					(width 0.2)
				)
				(gr_arc
					(start -0.899187 1.279127)
					(mid -0.165236 -0.156885)
					(end 1.267475 -0.897258)
					(width 0.2)
				)
				(gr_arc
					(start -0.991463 1.279127)
					(mid -0.228522 -0.222449)
					(end 1.270645 -0.990112)
					(width 0.2)
				)
				(gr_arc
					(start -1.083663 1.279127)
					(mid -0.294507 -0.285313)
					(end 1.266278 -1.081674)
					(width 0.2)
				)
				(gr_line
					(start 1.279127 -0.250195)
					(end 1.279127 -1.083663)
					(width 0.2)
				)
				(gr_line
					(start -0.250195 1.279127)
					(end -1.083663 1.279127)
					(width 0.2)
				)
			)
			(teardrops
				(best_length_ratio 0.2)
				(max_length 1)
				(best_width_ratio 0.9)
				(max_width 2)
				(curved_edges yes)
				(filter_ratio 0.9)
				(enabled yes)
				(allow_two_segments yes)
				(prefer_zone_connections yes)
			)
		)
		(pad "" smd custom
			(at 1.7 1.7 90)
			(size 0.62 0.62)
			(layers "F.Paste")
			(thermal_bridge_angle 90)
			(options
				(clearance outline)
				(anchor circle)
			)
			(primitives
				(gr_arc
					(start -0.250195 1.279127)
					(mid 0.285453 0.294389)
					(end 1.266786 -0.24747)
					(width 0.2)
				)
				(gr_arc
					(start -0.34334 1.279127)
					(mid 0.218448 0.232561)
					(end 1.259603 -0.339191)
					(width 0.2)
				)
				(gr_arc
					(start -0.436309 1.279127)
					(mid 0.152481 0.169693)
					(end 1.255279 -0.431435)
					(width 0.2)
				)
				(gr_arc
					(start -0.529126 1.279127)
					(mid 0.087542 0.105784)
					(end 1.253811 -0.524161)
					(width 0.2)
				)
				(gr_arc
					(start -0.621807 1.279127)
					(mid 0.0309 0.033527)
					(end 1.275473 -0.621136)
					(width 0.2)
				)
				(gr_arc
					(start -0.71437 1.279127)
					(mid -0.037758 -0.026651)
					(end 1.263664 -0.711602)
					(width 0.2)
				)
				(gr_arc
					(start -0.806826 1.279127)
					(mid -0.105837 -0.087395)
					(end 1.253435 -0.802342)
					(width 0.2)
				)
				(gr_arc
					(start -0.899187 1.279127)
					(mid -0.165236 -0.156885)
					(end 1.267475 -0.897258)
					(width 0.2)
				)
				(gr_arc
					(start -0.991463 1.279127)
					(mid -0.228522 -0.222449)
					(end 1.270645 -0.990112)
					(width 0.2)
				)
				(gr_arc
					(start -1.083663 1.279127)
					(mid -0.294507 -0.285313)
					(end 1.266278 -1.081674)
					(width 0.2)
				)
				(gr_line
					(start 1.279127 -0.250195)
					(end 1.279127 -1.083663)
					(width 0.2)
				)
				(gr_line
					(start -0.250195 1.279127)
					(end -1.083663 1.279127)
					(width 0.2)
				)
			)
			(teardrops
				(best_length_ratio 0.2)
				(max_length 1)
				(best_width_ratio 0.9)
				(max_width 2)
				(curved_edges yes)
				(filter_ratio 0.9)
				(enabled yes)
				(allow_two_segments yes)
				(prefer_zone_connections yes)
			)
		)
		(pad "1" thru_hole circle
			(at 0 0 270)
			(size 6 6)
			(drill 3.7)
			(layers "*.Cu" "*.Mask")
			(remove_unused_layers no)
			(net 1 "GND")
			(pintype "passive")
			(teardrops
				(best_length_ratio 0.4)
				(max_length 1)
				(best_width_ratio 0.9)
				(max_width 2)
				(curved_edges yes)
				(filter_ratio 0.9)
				(enabled yes)
				(allow_two_segments yes)
				(prefer_zone_connections yes)
			)
		)
	)
	(footprint "antmicro-footprints:R_0402_1005Metric"
		(layer "F.Cu")
		(at 218.43 133.1 -90)
		(descr "Resistor SMD 0402")
		(tags "resistor SMD 0402")
		(property "Reference" "R185"
			(at -1.54 -2.37 90)
			(layer "F.SilkS")
			(effects
				(font
					(size 0.7 0.7)
					(thickness 0.15)
				)
				(justify right bottom)
			)
		)
		(property "Value" "R_1k_0402"
			(at -1.011843 1.772047 90)
			(layer "F.Fab")
			(effects
				(font
					(size 0.7 0.7)
					(thickness 0.15)
				)
				(justify right bottom)
			)
		)
		(property "Datasheet" "https://www.bourns.com/docs/product-datasheets/cr.pdf"
			(at 0 0 270)
			(layer "F.Fab")
			(hide yes)
			(effects
				(font
					(size 1.27 1.27)
					(thickness 0.15)
				)
			)
		)
		(property "Author" "Antmicro"
			(at 85.33 351.53 0)
			(layer "F.Fab")
			(hide yes)
			(effects
				(font
					(size 1 1)
					(thickness 0.15)
				)
			)
		)
		(property "License" "Apache-2.0"
			(at 85.33 351.53 0)
			(layer "F.Fab")
			(hide yes)
			(effects
				(font
					(size 1 1)
					(thickness 0.15)
				)
			)
		)
		(property "MPN" "CR0402-FX-1001GLF"
			(at 85.33 351.53 0)
			(layer "F.Fab")
			(hide yes)
			(effects
				(font
					(size 1 1)
					(thickness 0.15)
				)
			)
		)
		(property "Manufacturer" "Bourns"
			(at 85.33 351.53 0)
			(layer "F.Fab")
			(hide yes)
			(effects
				(font
					(size 1 1)
					(thickness 0.15)
				)
			)
		)
		(property "Public" "False"
			(at 85.33 351.53 0)
			(layer "F.Fab")
			(hide yes)
			(effects
				(font
					(size 1 1)
					(thickness 0.15)
				)
			)
		)
		(property "Tolerance" "1%"
			(at 85.33 351.53 0)
			(layer "F.Fab")
			(hide yes)
			(effects
				(font
					(size 1 1)
					(thickness 0.15)
				)
			)
		)
		(property "Val" "1k"
			(at 85.33 351.53 0)
			(layer "F.Fab")
			(hide yes)
			(effects
				(font
					(size 1 1)
					(thickness 0.15)
				)
			)
		)
		(sheetname "PCIe misc")
		(sheetfile "pcie_misc.kicad_sch")
		(attr smd)
		(fp_rect
			(start -0.925 -0.47)
			(end 0.925 0.47)
			(stroke
				(width 0.05)
				(type default)
			)
			(fill no)
			(layer "F.CrtYd")
		)
		(fp_rect
			(start -0.5 -0.25)
			(end 0.5 0.25)
			(stroke
				(width 0.15)
				(type solid)
			)
			(fill no)
			(layer "F.Fab")
		)
		(pad "1" smd roundrect
			(at -0.48 0 270)
			(size 0.59 0.64)
			(layers "F.Cu" "F.Mask" "F.Paste")
			(roundrect_rratio 0.25)
			(net 605 "Net-(U37-~{OE3})")
			(pintype "passive")
			(teardrops
				(best_length_ratio 0.2)
				(max_length 1)
				(best_width_ratio 0.9)
				(max_width 2)
				(curved_edges yes)
				(filter_ratio 0.9)
				(enabled yes)
				(allow_two_segments yes)
				(prefer_zone_connections yes)
			)
		)
		(pad "2" smd roundrect
			(at 0.48 0 270)
			(size 0.59 0.64)
			(layers "F.Cu" "F.Mask" "F.Paste")
			(roundrect_rratio 0.25)
			(net 1 "GND")
			(pintype "passive")
			(teardrops
				(best_length_ratio 0.2)
				(max_length 1)
				(best_width_ratio 0.9)
				(max_width 2)
				(curved_edges yes)
				(filter_ratio 0.9)
				(enabled yes)
				(allow_two_segments yes)
				(prefer_zone_connections yes)
			)
		)
	)
	(footprint "antmicro-footprints:C_Pol_EIA-D"
		(layer "F.Cu")
		(at 317.324999 119.11 90)
		(property "Reference" "C41"
			(at -5.85 2.325001 90)
			(layer "F.SilkS")
			(effects
				(font
					(size 0.7 0.7)
					(thickness 0.15)
				)
				(justify left bottom)
			)
		)
		(property "Value" "C_Pol_68u_16V_Panasonic-TQC-D"
			(at 0 3.4 90)
			(layer "F.Fab")
			(effects
				(font
					(size 0.7 0.7)
					(thickness 0.15)
				)
				(justify left bottom)
			)
		)
		(property "Datasheet" "https://industrial.panasonic.com/sa/products/pt/aluminum-cap-smd/models/16TQC68MYF"
			(at 0 0 90)
			(layer "F.Fab")
			(hide yes)
			(effects
				(font
					(size 1.27 1.27)
					(thickness 0.15)
				)
			)
		)
		(property "Author" "Antmicro"
			(at 436.434999 -198.214999 0)
			(layer "F.Fab")
			(hide yes)
			(effects
				(font
					(size 1 1)
					(thickness 0.15)
				)
			)
		)
		(property "Dielectric" "template_dielectric"
			(at 436.434999 -198.214999 0)
			(layer "F.Fab")
			(hide yes)
			(effects
				(font
					(size 1 1)
					(thickness 0.15)
				)
			)
		)
		(property "License" "Apache-2.0"
			(at 436.434999 -198.214999 0)
			(layer "F.Fab")
			(hide yes)
			(effects
				(font
					(size 1 1)
					(thickness 0.15)
				)
			)
		)
		(property "MPN" "16TQC68MYF"
			(at 436.434999 -198.214999 0)
			(layer "F.Fab")
			(hide yes)
			(effects
				(font
					(size 1 1)
					(thickness 0.15)
				)
			)
		)
		(property "Manufacturer" "Panasonic"
			(at 436.434999 -198.214999 0)
			(layer "F.Fab")
			(hide yes)
			(effects
				(font
					(size 1 1)
					(thickness 0.15)
				)
			)
		)
		(property "Public" "False"
			(at 436.434999 -198.214999 0)
			(layer "F.Fab")
			(hide yes)
			(effects
				(font
					(size 1 1)
					(thickness 0.15)
				)
			)
		)
		(property "Val" "68u"
			(at 436.434999 -198.214999 0)
			(layer "F.Fab")
			(hide yes)
			(effects
				(font
					(size 1 1)
					(thickness 0.15)
				)
			)
		)
		(property "Voltage" "16V"
			(at 436.434999 -198.214999 0)
			(layer "F.Fab")
			(hide yes)
			(effects
				(font
					(size 1 1)
					(thickness 0.15)
				)
			)
		)
		(sheetname "Power")
		(sheetfile "power.kicad_sch")
		(attr smd)
		(fp_line
			(start 3.6 -2.2)
			(end 3.6 -1.6)
			(stroke
				(width 0.15)
				(type solid)
			)
			(layer "F.SilkS")
		)
		(fp_line
			(start -3.58 -2.2)
			(end 3.6 -2.2)
			(stroke
				(width 0.15)
				(type solid)
			)
			(layer "F.SilkS")
		)
		(fp_line
			(start -4.1 -2.025)
			(end -4.1 -1.625)
			(stroke
				(width 0.12)
				(type solid)
			)
			(layer "F.SilkS")
		)
		(fp_line
			(start -4.3 -1.825)
			(end -3.9 -1.825)
			(stroke
				(width 0.12)
				(type solid)
			)
			(layer "F.SilkS")
		)
		(fp_line
			(start -3.58 -1.6)
			(end -3.58 -2.2)
			(stroke
				(width 0.15)
				(type solid)
			)
			(layer "F.SilkS")
		)
		(fp_line
			(start 3.6 1.6)
			(end 3.6 2.2)
			(stroke
				(width 0.15)
				(type solid)
			)
			(layer "F.SilkS")
		)
		(fp_line
			(start 3.6 2.2)
			(end -3.58 2.2)
			(stroke
				(width 0.15)
				(type solid)
			)
			(layer "F.SilkS")
		)
		(fp_line
			(start -3.58 2.2)
			(end -3.58 1.6)
			(stroke
				(width 0.15)
				(type solid)
			)
			(layer "F.SilkS")
		)
		(fp_line
			(start 3.77 -2.4)
			(end 3.77 -1.51)
			(stroke
				(width 0.05)
				(type solid)
			)
			(layer "F.CrtYd")
		)
		(fp_line
			(start -3.775 -2.4)
			(end 3.77 -2.4)
			(stroke
				(width 0.05)
				(type solid)
			)
			(layer "F.CrtYd")
		)
		(fp_line
			(start -3.775 -2.4)
			(end -3.775 -1.5)
			(stroke
				(width 0.05)
				(type solid)
			)
			(layer "F.CrtYd")
		)
		(fp_line
			(start 4.505 -1.51)
			(end 4.505 1.5)
			(stroke
				(width 0.05)
				(type solid)
			)
			(layer "F.CrtYd")
		)
		(fp_line
			(start 3.77 -1.51)
			(end 4.505 -1.51)
			(stroke
				(width 0.05)
				(type solid)
			)
			(layer "F.CrtYd")
		)
		(fp_line
			(start -3.775 -1.5)
			(end -4.505 -1.5)
			(stroke
				(width 0.05)
				(type solid)
			)
			(layer "F.CrtYd")
		)
		(fp_line
			(start 4.505 1.51)
			(end 3.77 1.51)
			(stroke
				(width 0.05)
				(type solid)
			)
			(layer "F.CrtYd")
		)
		(fp_line
			(start 3.77 1.51)
			(end 3.77 2.4)
			(stroke
				(width 0.05)
				(type solid)
			)
			(layer "F.CrtYd")
		)
		(fp_line
			(start -3.77 1.51)
			(end -4.505 1.51)
			(stroke
				(width 0.05)
				(type solid)
			)
			(layer "F.CrtYd")
		)
		(fp_line
			(start -4.505 1.51)
			(end -4.505 -1.5)
			(stroke
				(width 0.05)
				(type solid)
			)
			(layer "F.CrtYd")
		)
		(fp_line
			(start 3.77 2.4)
			(end -3.77 2.4)
			(stroke
				(width 0.05)
				(type solid)
			)
			(layer "F.CrtYd")
		)
		(fp_line
			(start -3.77 2.4)
			(end -3.77 1.51)
			(stroke
				(width 0.05)
				(type solid)
			)
			(layer "F.CrtYd")
		)
		(fp_rect
			(start -3.65 -2.15)
			(end 3.65 2.15)
			(stroke
				(width 0.15)
				(type solid)
			)
			(fill no)
			(layer "F.Fab")
		)
		(pad "1" smd roundrect
			(at -3.1 0 90)
			(size 2.31 2.52)
			(layers "F.Cu" "F.Mask" "F.Paste")
			(roundrect_rratio 0.1)
			(net 62 "+12V_AON")
			(pintype "passive")
			(teardrops
				(best_length_ratio 0.2)
				(max_length 1)
				(best_width_ratio 0.9)
				(max_width 2)
				(curved_edges yes)
				(filter_ratio 0.9)
				(enabled yes)
				(allow_two_segments yes)
				(prefer_zone_connections yes)
			)
		)
		(pad "2" smd roundrect
			(at 3.1 0 90)
			(size 2.31 2.52)
			(layers "F.Cu" "F.Mask" "F.Paste")
			(roundrect_rratio 0.1)
			(net 1 "GND")
			(pintype "passive")
			(teardrops
				(best_length_ratio 0.2)
				(max_length 1)
				(best_width_ratio 0.9)
				(max_width 2)
				(curved_edges yes)
				(filter_ratio 0.9)
				(enabled yes)
				(allow_two_segments yes)
				(prefer_zone_connections yes)
			)
		)
	)
	(footprint "antmicro-footprints:R_0402_1005Metric"
		(layer "F.Cu")
		(at 120.2 86.36 -90)
		(descr "Resistor SMD 0402")
		(tags "resistor SMD 0402")
		(property "Reference" "R12"
			(at 0.8 -0.4 90)
			(layer "F.SilkS")
			(effects
				(font
					(size 0.7 0.7)
					(thickness 0.15)
				)
				(justify right bottom)
			)
		)
		(property "Value" "R_2k2_0402"
			(at -1.011843 1.772047 90)
			(layer "F.Fab")
			(effects
				(font
					(size 0.7 0.7)
					(thickness 0.15)
				)
				(justify right bottom)
			)
		)
		(property "Datasheet" "https://www.bourns.com/docs/product-datasheets/cr.pdf"
			(at 0 0 270)
			(layer "F.Fab")
			(hide yes)
			(effects
				(font
					(size 1.27 1.27)
					(thickness 0.15)
				)
			)
		)
		(property "Author" "Antmicro"
			(at 33.84 206.56 0)
			(layer "F.Fab")
			(hide yes)
			(effects
				(font
					(size 1 1)
					(thickness 0.15)
				)
			)
		)
		(property "License" "Apache-2.0"
			(at 33.84 206.56 0)
			(layer "F.Fab")
			(hide yes)
			(effects
				(font
					(size 1 1)
					(thickness 0.15)
				)
			)
		)
		(property "MPN" "CR0402-FX-2201GLF"
			(at 33.84 206.56 0)
			(layer "F.Fab")
			(hide yes)
			(effects
				(font
					(size 1 1)
					(thickness 0.15)
				)
			)
		)
		(property "Manufacturer" "Bourns"
			(at 33.84 206.56 0)
			(layer "F.Fab")
			(hide yes)
			(effects
				(font
					(size 1 1)
					(thickness 0.15)
				)
			)
		)
		(property "Public" "False"
			(at 33.84 206.56 0)
			(layer "F.Fab")
			(hide yes)
			(effects
				(font
					(size 1 1)
					(thickness 0.15)
				)
			)
		)
		(property "Tolerance" "1%"
			(at 33.84 206.56 0)
			(layer "F.Fab")
			(hide yes)
			(effects
				(font
					(size 1 1)
					(thickness 0.15)
				)
			)
		)
		(property "Val" "2k2"
			(at 33.84 206.56 0)
			(layer "F.Fab")
			(hide yes)
			(effects
				(font
					(size 1 1)
					(thickness 0.15)
				)
			)
		)
		(sheetname "2xUSB3.0+RJ45")
		(sheetfile "usb3+rj45.kicad_sch")
		(attr smd)
		(fp_rect
			(start -0.925 -0.47)
			(end 0.925 0.47)
			(stroke
				(width 0.05)
				(type default)
			)
			(fill no)
			(layer "F.CrtYd")
		)
		(fp_rect
			(start -0.5 -0.25)
			(end 0.5 0.25)
			(stroke
				(width 0.15)
				(type solid)
			)
			(fill no)
			(layer "F.Fab")
		)
		(pad "1" smd roundrect
			(at -0.48 0 270)
			(size 0.59 0.64)
			(layers "F.Cu" "F.Mask" "F.Paste")
			(roundrect_rratio 0.25)
			(net 1 "GND")
			(pintype "passive")
			(teardrops
				(best_length_ratio 0.2)
				(max_length 1)
				(best_width_ratio 0.9)
				(max_width 2)
				(curved_edges yes)
				(filter_ratio 0.9)
				(enabled yes)
				(allow_two_segments yes)
				(prefer_zone_connections yes)
			)
		)
		(pad "2" smd roundrect
			(at 0.48 0 270)
			(size 0.59 0.64)
			(layers "F.Cu" "F.Mask" "F.Paste")
			(roundrect_rratio 0.25)
			(net 547 "/2xUSB3.0+RJ45/P1_ISET")
			(pintype "passive")
			(teardrops
				(best_length_ratio 0.2)
				(max_length 1)
				(best_width_ratio 0.9)
				(max_width 2)
				(curved_edges yes)
				(filter_ratio 0.9)
				(enabled yes)
				(allow_two_segments yes)
				(prefer_zone_connections yes)
			)
		)
	)
	(footprint "antmicro-footprints:C_0402_1005Metric"
		(layer "F.Cu")
		(at 304.14 127.79)
		(descr "Capacitor SMD 0402")
		(tags "capacitor SMD 0402")
		(property "Reference" "C53"
			(at 0.86 0.42 0)
			(layer "F.SilkS")
			(effects
				(font
					(size 0.7 0.7)
					(thickness 0.15)
				)
				(justify left bottom)
			)
		)
		(property "Value" "C_100n_0402"
			(at -1.022927 2.155213 0)
			(layer "F.Fab")
			(effects
				(font
					(size 0.7 0.7)
					(thickness 0.15)
				)
				(justify left bottom)
			)
		)
		(property "Datasheet" "https://www.murata.com/products/productdetail?partno=GRM155R61H104KE14%23"
			(at 0 0 0)
			(layer "F.Fab")
			(hide yes)
			(effects
				(font
					(size 1.27 1.27)
					(thickness 0.15)
				)
			)
		)
		(property "Author" "Antmicro"
			(at 0 0 0)
			(layer "F.Fab")
			(hide yes)
			(effects
				(font
					(size 1 1)
					(thickness 0.15)
				)
			)
		)
		(property "Dielectric" "X5R"
			(at 0 0 0)
			(layer "F.Fab")
			(hide yes)
			(effects
				(font
					(size 1 1)
					(thickness 0.15)
				)
			)
		)
		(property "License" "Apache-2.0"
			(at 0 0 0)
			(layer "F.Fab")
			(hide yes)
			(effects
				(font
					(size 1 1)
					(thickness 0.15)
				)
			)
		)
		(property "MPN" "GRM155R61H104KE14D"
			(at 0 0 0)
			(layer "F.Fab")
			(hide yes)
			(effects
				(font
					(size 1 1)
					(thickness 0.15)
				)
			)
		)
		(property "Manufacturer" "Murata"
			(at 0 0 0)
			(layer "F.Fab")
			(hide yes)
			(effects
				(font
					(size 1 1)
					(thickness 0.15)
				)
			)
		)
		(property "Public" "False"
			(at 0 0 0)
			(layer "F.Fab")
			(hide yes)
			(effects
				(font
					(size 1 1)
					(thickness 0.15)
				)
			)
		)
		(property "Val" "100n"
			(at 0 0 0)
			(layer "F.Fab")
			(hide yes)
			(effects
				(font
					(size 1 1)
					(thickness 0.15)
				)
			)
		)
		(property "Voltage" "50V"
			(at 0 0 0)
			(layer "F.Fab")
			(hide yes)
			(effects
				(font
					(size 1 1)
					(thickness 0.15)
				)
			)
		)
		(sheetname "Power")
		(sheetfile "power.kicad_sch")
		(attr smd)
		(fp_rect
			(start -0.925 -0.47)
			(end 0.925 0.47)
			(stroke
				(width 0.05)
				(type default)
			)
			(fill no)
			(layer "F.CrtYd")
		)
		(fp_line
			(start -0.494 -0.25)
			(end 0.504 -0.25)
			(stroke
				(width 0.15)
				(type solid)
			)
			(layer "F.Fab")
		)
		(fp_line
			(start -0.494 0.248)
			(end -0.494 -0.25)
			(stroke
				(width 0.15)
				(type solid)
			)
			(layer "F.Fab")
		)
		(fp_line
			(start 0.504 -0.25)
			(end 0.504 0.248)
			(stroke
				(width 0.15)
				(type solid)
			)
			(layer "F.Fab")
		)
		(fp_line
			(start 0.504 0.248)
			(end -0.494 0.248)
			(stroke
				(width 0.15)
				(type solid)
			)
			(layer "F.Fab")
		)
		(pad "1" smd roundrect
			(at -0.48 0)
			(size 0.59 0.64)
			(layers "F.Cu" "F.Mask" "F.Paste")
			(roundrect_rratio 0.25)
			(net 1 "GND")
			(pintype "passive")
			(teardrops
				(best_length_ratio 0.2)
				(max_length 1)
				(best_width_ratio 0.9)
				(max_width 2)
				(curved_edges yes)
				(filter_ratio 0.9)
				(enabled yes)
				(allow_two_segments yes)
				(prefer_zone_connections yes)
			)
		)
		(pad "2" smd roundrect
			(at 0.48 0)
			(size 0.59 0.64)
			(layers "F.Cu" "F.Mask" "F.Paste")
			(roundrect_rratio 0.25)
			(net 72 "Net-(U20-CT)")
			(pintype "passive")
			(teardrops
				(best_length_ratio 0.2)
				(max_length 1)
				(best_width_ratio 0.9)
				(max_width 2)
				(curved_edges yes)
				(filter_ratio 0.9)
				(enabled yes)
				(allow_two_segments yes)
				(prefer_zone_connections yes)
			)
		)
	)
	(footprint "antmicro-footprints:USON-10_2.5x1mm_P0.5mm"
		(layer "F.Cu")
		(at 97.502 151.085 90)
		(descr "USON-10 2.5x1mm_ Pitch 0.5mm")
		(tags "USON-10 2.5x1mm Pitch 0.5mm")
		(property "Reference" "U8"
			(at -0.415 3.098 0)
			(layer "F.SilkS")
			(effects
				(font
					(size 0.7 0.7)
					(thickness 0.15)
				)
				(justify right bottom)
			)
		)
		(property "Value" "ESD204DQAR"
			(at 0.018 2.499 90)
			(layer "F.Fab")
			(effects
				(font
					(size 0.7 0.7)
					(thickness 0.15)
				)
				(justify left top)
			)
		)
		(property "Datasheet" "https://www.ti.com/lit/ds/symlink/esd204.pdf?ts=1706004844383&ref_url=https%253A%252F%252Fwww.ti.com%252Finterface%252Fdiodes%252Fesd-protection-diodes%252Fproducts.html"
			(at 0 0 90)
			(layer "F.Fab")
			(hide yes)
			(effects
				(font
					(size 1.27 1.27)
					(thickness 0.15)
				)
			)
		)
		(property "Author" "Antmicro"
			(at -42.04 261.9 0)
			(layer "F.Fab")
			(hide yes)
			(effects
				(font
					(size 1 1)
					(thickness 0.15)
				)
			)
		)
		(property "License" "Apache-2.0"
			(at -42.04 261.9 0)
			(layer "F.Fab")
			(hide yes)
			(effects
				(font
					(size 1 1)
					(thickness 0.15)
				)
			)
		)
		(property "MPN" "ESD204DQAR"
			(at -42.04 261.9 0)
			(layer "F.Fab")
			(hide yes)
			(effects
				(font
					(size 1 1)
					(thickness 0.15)
				)
			)
		)
		(property "Manufacturer" "Texas Instruments"
			(at -42.04 261.9 0)
			(layer "F.Fab")
			(hide yes)
			(effects
				(font
					(size 1 1)
					(thickness 0.15)
				)
			)
		)
		(sheetname "OCuLink")
		(sheetfile "oculink.kicad_sch")
		(attr smd)
		(fp_line
			(start 0.498 -1.401)
			(end -0.5 -1.401)
			(stroke
				(width 0.15)
				(type solid)
			)
			(layer "F.SilkS")
		)
		(fp_line
			(start 0.498 1.398)
			(end -0.5 1.398)
			(stroke
				(width 0.15)
				(type solid)
			)
			(layer "F.SilkS")
		)
		(fp_circle
			(center -0.68 -1.27)
			(end -0.63 -1.27)
			(stroke
				(width 0.15)
				(type solid)
			)
			(fill yes)
			(layer "F.SilkS")
		)
		(fp_rect
			(start -0.8 -1.5)
			(end 0.8 1.499)
			(stroke
				(width 0.05)
				(type solid)
			)
			(fill no)
			(layer "F.CrtYd")
		)
		(fp_line
			(start 0.498 -1.25)
			(end -0.25 -1.25)
			(stroke
				(width 0.15)
				(type solid)
			)
			(layer "F.Fab")
		)
		(fp_line
			(start 0.498 -1.25)
			(end 0.498 1.249)
			(stroke
				(width 0.15)
				(type solid)
			)
			(layer "F.Fab")
		)
		(fp_line
			(start -0.25 -1.25)
			(end -0.5 -1)
			(stroke
				(width 0.15)
				(type solid)
			)
			(layer "F.Fab")
		)
		(fp_line
			(start -0.5 -1)
			(end -0.5 1.249)
			(stroke
				(width 0.15)
				(type solid)
			)
			(layer "F.Fab")
		)
		(fp_line
			(start -0.5 1.249)
			(end 0.498 1.249)
			(stroke
				(width 0.15)
				(type solid)
			)
			(layer "F.Fab")
		)
		(pad "1" smd roundrect
			(at -0.387 -1)
			(size 0.25 0.55)
			(layers "F.Cu" "F.Mask" "F.Paste")
			(roundrect_rratio 0.25)
			(net 186 "/OCuLink/PCIe_{x4}.RX0+")
			(pintype "passive")
			(teardrops
				(best_length_ratio 0.2)
				(max_length 1)
				(best_width_ratio 0.9)
				(max_width 2)
				(curved_edges yes)
				(filter_ratio 0.9)
				(enabled yes)
				(allow_two_segments yes)
				(prefer_zone_connections yes)
			)
		)
		(pad "2" smd roundrect
			(at -0.387 -0.5)
			(size 0.25 0.55)
			(layers "F.Cu" "F.Mask" "F.Paste")
			(roundrect_rratio 0.25)
			(net 187 "/OCuLink/PCIe_{x4}.RX0-")
			(pintype "passive")
			(teardrops
				(best_length_ratio 0.2)
				(max_length 1)
				(best_width_ratio 0.9)
				(max_width 2)
				(curved_edges yes)
				(filter_ratio 0.9)
				(enabled yes)
				(allow_two_segments yes)
				(prefer_zone_connections yes)
			)
		)
		(pad "3" smd roundrect
			(at -0.387 0)
			(size 0.4 0.55)
			(layers "F.Cu" "F.Mask" "F.Paste")
			(roundrect_rratio 0.25)
			(net 1 "GND")
			(pintype "power_in")
			(teardrops
				(best_length_ratio 0.2)
				(max_length 1)
				(best_width_ratio 0.9)
				(max_width 2)
				(curved_edges yes)
				(filter_ratio 0.9)
				(enabled yes)
				(allow_two_segments yes)
				(prefer_zone_connections yes)
			)
		)
		(pad "4" smd roundrect
			(at -0.387 0.498)
			(size 0.25 0.55)
			(layers "F.Cu" "F.Mask" "F.Paste")
			(roundrect_rratio 0.25)
			(net 188 "/OCuLink/PCIe_{x4}.RX1+")
			(pintype "passive")
			(teardrops
				(best_length_ratio 0.2)
				(max_length 1)
				(best_width_ratio 0.9)
				(max_width 2)
				(curved_edges yes)
				(filter_ratio 0.9)
				(enabled yes)
				(allow_two_segments yes)
				(prefer_zone_connections yes)
			)
		)
		(pad "5" smd roundrect
			(at -0.387 0.998)
			(size 0.25 0.55)
			(layers "F.Cu" "F.Mask" "F.Paste")
			(roundrect_rratio 0.25)
			(net 189 "/OCuLink/PCIe_{x4}.RX1-")
			(pintype "passive")
			(teardrops
				(best_length_ratio 0.2)
				(max_length 1)
				(best_width_ratio 0.9)
				(max_width 2)
				(curved_edges yes)
				(filter_ratio 0.9)
				(enabled yes)
				(allow_two_segments yes)
				(prefer_zone_connections yes)
			)
		)
		(pad "6" smd roundrect
			(at 0.385 0.998)
			(size 0.25 0.55)
			(layers "F.Cu" "F.Mask" "F.Paste")
			(roundrect_rratio 0.25)
			(net 189 "/OCuLink/PCIe_{x4}.RX1-")
			(pintype "passive")
			(teardrops
				(best_length_ratio 0.2)
				(max_length 1)
				(best_width_ratio 0.9)
				(max_width 2)
				(curved_edges yes)
				(filter_ratio 0.9)
				(enabled yes)
				(allow_two_segments yes)
				(prefer_zone_connections yes)
			)
		)
		(pad "7" smd roundrect
			(at 0.385 0.498)
			(size 0.25 0.55)
			(layers "F.Cu" "F.Mask" "F.Paste")
			(roundrect_rratio 0.25)
			(net 188 "/OCuLink/PCIe_{x4}.RX1+")
			(pintype "passive")
			(teardrops
				(best_length_ratio 0.2)
				(max_length 1)
				(best_width_ratio 0.9)
				(max_width 2)
				(curved_edges yes)
				(filter_ratio 0.9)
				(enabled yes)
				(allow_two_segments yes)
				(prefer_zone_connections yes)
			)
		)
		(pad "8" smd roundrect
			(at 0.385 0)
			(size 0.4 0.55)
			(layers "F.Cu" "F.Mask" "F.Paste")
			(roundrect_rratio 0.25)
			(net 1 "GND")
			(pintype "passive")
			(teardrops
				(best_length_ratio 0.2)
				(max_length 1)
				(best_width_ratio 0.9)
				(max_width 2)
				(curved_edges yes)
				(filter_ratio 0.9)
				(enabled yes)
				(allow_two_segments yes)
				(prefer_zone_connections yes)
			)
		)
		(pad "9" smd roundrect
			(at 0.385 -0.5)
			(size 0.25 0.55)
			(layers "F.Cu" "F.Mask" "F.Paste")
			(roundrect_rratio 0.25)
			(net 187 "/OCuLink/PCIe_{x4}.RX0-")
			(pintype "passive")
			(teardrops
				(best_length_ratio 0.2)
				(max_length 1)
				(best_width_ratio 0.9)
				(max_width 2)
				(curved_edges yes)
				(filter_ratio 0.9)
				(enabled yes)
				(allow_two_segments yes)
				(prefer_zone_connections yes)
			)
		)
		(pad "10" smd roundrect
			(at 0.385 -1)
			(size 0.25 0.55)
			(layers "F.Cu" "F.Mask" "F.Paste")
			(roundrect_rratio 0.25)
			(net 186 "/OCuLink/PCIe_{x4}.RX0+")
			(pintype "passive")
			(teardrops
				(best_length_ratio 0.2)
				(max_length 1)
				(best_width_ratio 0.9)
				(max_width 2)
				(curved_edges yes)
				(filter_ratio 0.9)
				(enabled yes)
				(allow_two_segments yes)
				(prefer_zone_connections yes)
			)
		)
	)
	(footprint "antmicro-footprints:R_0402_1005Metric"
		(layer "F.Cu")
		(at 308.694999 121.61 180)
		(descr "Resistor SMD 0402")
		(tags "resistor SMD 0402")
		(property "Reference" "R97"
			(at -1.055001 -1.4 0)
			(layer "F.SilkS")
			(effects
				(font
					(size 0.7 0.7)
					(thickness 0.15)
				)
				(justify right bottom)
			)
		)
		(property "Value" "R_10k_0402"
			(at -1.011843 1.772047 0)
			(layer "F.Fab")
			(effects
				(font
					(size 0.7 0.7)
					(thickness 0.15)
				)
				(justify right bottom)
			)
		)
		(property "Datasheet" "https://www.bourns.com/docs/product-datasheets/cr.pdf"
			(at 0 0 180)
			(layer "F.Fab")
			(hide yes)
			(effects
				(font
					(size 1.27 1.27)
					(thickness 0.15)
				)
			)
		)
		(property "Author" "Antmicro"
			(at 617.389998 243.22 0)
			(layer "F.Fab")
			(hide yes)
			(effects
				(font
					(size 1 1)
					(thickness 0.15)
				)
			)
		)
		(property "License" "Apache-2.0"
			(at 617.389998 243.22 0)
			(layer "F.Fab")
			(hide yes)
			(effects
				(font
					(size 1 1)
					(thickness 0.15)
				)
			)
		)
		(property "MPN" "CR0402-FX-1002GLF"
			(at 617.389998 243.22 0)
			(layer "F.Fab")
			(hide yes)
			(effects
				(font
					(size 1 1)
					(thickness 0.15)
				)
			)
		)
		(property "Manufacturer" "Bourns"
			(at 617.389998 243.22 0)
			(layer "F.Fab")
			(hide yes)
			(effects
				(font
					(size 1 1)
					(thickness 0.15)
				)
			)
		)
		(property "Public" "False"
			(at 617.389998 243.22 0)
			(layer "F.Fab")
			(hide yes)
			(effects
				(font
					(size 1 1)
					(thickness 0.15)
				)
			)
		)
		(property "Tolerance" "1%"
			(at 617.389998 243.22 0)
			(layer "F.Fab")
			(hide yes)
			(effects
				(font
					(size 1 1)
					(thickness 0.15)
				)
			)
		)
		(property "Val" "10k"
			(at 617.389998 243.22 0)
			(layer "F.Fab")
			(hide yes)
			(effects
				(font
					(size 1 1)
					(thickness 0.15)
				)
			)
		)
		(sheetname "Power")
		(sheetfile "power.kicad_sch")
		(attr smd)
		(fp_rect
			(start -0.925 -0.47)
			(end 0.925 0.47)
			(stroke
				(width 0.05)
				(type default)
			)
			(fill no)
			(layer "F.CrtYd")
		)
		(fp_rect
			(start -0.5 -0.25)
			(end 0.5 0.25)
			(stroke
				(width 0.15)
				(type solid)
			)
			(fill no)
			(layer "F.Fab")
		)
		(pad "1" smd roundrect
			(at -0.48 0 180)
			(size 0.59 0.64)
			(layers "F.Cu" "F.Mask" "F.Paste")
			(roundrect_rratio 0.25)
			(net 580 "Net-(U18-FB)")
			(pintype "passive")
			(teardrops
				(best_length_ratio 0.2)
				(max_length 1)
				(best_width_ratio 0.9)
				(max_width 2)
				(curved_edges yes)
				(filter_ratio 0.9)
				(enabled yes)
				(allow_two_segments yes)
				(prefer_zone_connections yes)
			)
		)
		(pad "2" smd roundrect
			(at 0.48 0 180)
			(size 0.59 0.64)
			(layers "F.Cu" "F.Mask" "F.Paste")
			(roundrect_rratio 0.25)
			(net 70 "Net-(C49-Pad2)")
			(pintype "passive")
			(teardrops
				(best_length_ratio 0.2)
				(max_length 1)
				(best_width_ratio 0.9)
				(max_width 2)
				(curved_edges yes)
				(filter_ratio 0.9)
				(enabled yes)
				(allow_two_segments yes)
				(prefer_zone_connections yes)
			)
		)
	)
	(footprint "antmicro-footprints:R_0201"
		(layer "F.Cu")
		(at 128.41 147.31 -90)
		(descr "Resistor SMD 0201")
		(tags "resistor SMD 0201")
		(property "Reference" "R308"
			(at 4.099 -0.29 270)
			(layer "F.SilkS")
			(effects
				(font
					(size 0.7 0.7)
					(thickness 0.15)
				)
				(justify left bottom)
			)
		)
		(property "Value" "R_0R_0201"
			(at 0 1.25 270)
			(layer "F.Fab")
			(effects
				(font
					(size 0.7 0.7)
					(thickness 0.15)
				)
				(justify left bottom)
			)
		)
		(property "Datasheet" "https://www.bourns.com/docs/product-datasheets/cr.pdf"
			(at 0 0 270)
			(layer "F.Fab")
			(hide yes)
			(effects
				(font
					(size 1.27 1.27)
					(thickness 0.15)
				)
			)
		)
		(property "Author" "Antmicro"
			(at -18.9 275.72 0)
			(layer "F.Fab")
			(hide yes)
			(effects
				(font
					(size 1 1)
					(thickness 0.15)
				)
			)
		)
		(property "License" "Apache-2.0"
			(at -18.9 275.72 0)
			(layer "F.Fab")
			(hide yes)
			(effects
				(font
					(size 1 1)
					(thickness 0.15)
				)
			)
		)
		(property "MPN" "CR0201-FX-0R00GLF"
			(at -18.9 275.72 0)
			(layer "F.Fab")
			(hide yes)
			(effects
				(font
					(size 1 1)
					(thickness 0.15)
				)
			)
		)
		(property "Manufacturer" "Bourns"
			(at -18.9 275.72 0)
			(layer "F.Fab")
			(hide yes)
			(effects
				(font
					(size 1 1)
					(thickness 0.15)
				)
			)
		)
		(property "Tolerance" "1%"
			(at -18.9 275.72 0)
			(layer "F.Fab")
			(hide yes)
			(effects
				(font
					(size 1 1)
					(thickness 0.15)
				)
			)
		)
		(property "Val" "0R"
			(at -18.9 275.72 0)
			(layer "F.Fab")
			(hide yes)
			(effects
				(font
					(size 1 1)
					(thickness 0.15)
				)
			)
		)
		(sheetname "KR to SFI #2")
		(sheetfile "kr_sfi.kicad_sch")
		(attr smd)
		(fp_rect
			(start -0.7 -0.35)
			(end 0.7 0.35)
			(stroke
				(width 0.05)
				(type default)
			)
			(fill no)
			(layer "F.CrtYd")
		)
		(fp_rect
			(start -0.3 -0.15)
			(end 0.298 0.148)
			(stroke
				(width 0.15)
				(type solid)
			)
			(fill no)
			(layer "F.Fab")
		)
		(pad "" smd roundrect
			(at -0.346 0 270)
			(size 0.318 0.36)
			(layers "F.Paste")
			(roundrect_rratio 0.25)
			(teardrops
				(best_length_ratio 0.2)
				(max_length 1)
				(best_width_ratio 0.9)
				(max_width 2)
				(curved_edges yes)
				(filter_ratio 0.9)
				(enabled yes)
				(allow_two_segments yes)
				(prefer_zone_connections yes)
			)
		)
		(pad "" smd roundrect
			(at 0.344 0 270)
			(size 0.318 0.36)
			(layers "F.Paste")
			(roundrect_rratio 0.25)
			(teardrops
				(best_length_ratio 0.2)
				(max_length 1)
				(best_width_ratio 0.9)
				(max_width 2)
				(curved_edges yes)
				(filter_ratio 0.9)
				(enabled yes)
				(allow_two_segments yes)
				(prefer_zone_connections yes)
			)
		)
		(pad "1" smd roundrect
			(at -0.32 0 270)
			(size 0.46 0.4)
			(layers "F.Cu" "F.Mask")
			(roundrect_rratio 0.25)
			(net 952 "/2xSFP+/KR to SFI #2/SFI_R.TX-")
			(pintype "passive")
			(teardrops
				(best_length_ratio 0.2)
				(max_length 1)
				(best_width_ratio 0.9)
				(max_width 2)
				(curved_edges yes)
				(filter_ratio 0.9)
				(enabled yes)
				(allow_two_segments yes)
				(prefer_zone_connections yes)
			)
		)
		(pad "2" smd roundrect
			(at 0.32 0 270)
			(size 0.46 0.4)
			(layers "F.Cu" "F.Mask")
			(roundrect_rratio 0.25)
			(net 880 "/2xSFP+/SFI1.TX-")
			(pintype "passive")
			(teardrops
				(best_length_ratio 0.2)
				(max_length 1)
				(best_width_ratio 0.9)
				(max_width 2)
				(curved_edges yes)
				(filter_ratio 0.9)
				(enabled yes)
				(allow_two_segments yes)
				(prefer_zone_connections yes)
			)
		)
	)
	(footprint "antmicro-footprints:C_0603_1608Metric"
		(layer "F.Cu")
		(at 314.224999 118.96 -90)
		(descr "Capacitor SMD 0603")
		(tags "capacitor 0603")
		(property "Reference" "C42"
			(at -3.35 -0.425001 90)
			(layer "F.SilkS")
			(effects
				(font
					(size 0.7 0.7)
					(thickness 0.15)
				)
				(justify right bottom)
			)
		)
		(property "Value" "C_22u_16V_0603"
			(at -1.42757 1.770288 90)
			(layer "F.Fab")
			(effects
				(font
					(size 0.7 0.7)
					(thickness 0.15)
				)
				(justify right bottom)
			)
		)
		(property "Datasheet" "https://product.samsungsem.com/mlcc/CL10A226MO7JZN.do"
			(at 0 0 270)
			(layer "F.Fab")
			(hide yes)
			(effects
				(font
					(size 1.27 1.27)
					(thickness 0.15)
				)
			)
		)
		(property "Author" "Antmicro"
			(at 195.264999 433.184999 0)
			(layer "F.Fab")
			(hide yes)
			(effects
				(font
					(size 1 1)
					(thickness 0.15)
				)
			)
		)
		(property "Dielectric" ""
			(at 195.264999 433.184999 0)
			(layer "F.Fab")
			(hide yes)
			(effects
				(font
					(size 1 1)
					(thickness 0.15)
				)
			)
		)
		(property "License" "Apache-2.0"
			(at 195.264999 433.184999 0)
			(layer "F.Fab")
			(hide yes)
			(effects
				(font
					(size 1 1)
					(thickness 0.15)
				)
			)
		)
		(property "MPN" "CL10A226MO7JZNC"
			(at 195.264999 433.184999 0)
			(layer "F.Fab")
			(hide yes)
			(effects
				(font
					(size 1 1)
					(thickness 0.15)
				)
			)
		)
		(property "Manufacturer" "Samsung Electro-Mechanics"
			(at 195.264999 433.184999 0)
			(layer "F.Fab")
			(hide yes)
			(effects
				(font
					(size 1 1)
					(thickness 0.15)
				)
			)
		)
		(property "Public" "False"
			(at 195.264999 433.184999 0)
			(layer "F.Fab")
			(hide yes)
			(effects
				(font
					(size 1 1)
					(thickness 0.15)
				)
			)
		)
		(property "Val" "22u"
			(at 195.264999 433.184999 0)
			(layer "F.Fab")
			(hide yes)
			(effects
				(font
					(size 1 1)
					(thickness 0.15)
				)
			)
		)
		(property "Voltage" "16V"
			(at 195.264999 433.184999 0)
			(layer "F.Fab")
			(hide yes)
			(effects
				(font
					(size 1 1)
					(thickness 0.15)
				)
			)
		)
		(sheetname "Power")
		(sheetfile "power.kicad_sch")
		(attr smd)
		(fp_line
			(start -0.15 0.4)
			(end 0.15 0.4)
			(stroke
				(width 0.15)
				(type solid)
			)
			(layer "F.SilkS")
		)
		(fp_line
			(start -0.15 -0.4)
			(end 0.15 -0.4)
			(stroke
				(width 0.15)
				(type solid)
			)
			(layer "F.SilkS")
		)
		(fp_rect
			(start -1.25 -0.65)
			(end 1.25 0.65)
			(stroke
				(width 0.05)
				(type solid)
			)
			(fill no)
			(layer "F.CrtYd")
		)
		(fp_rect
			(start -0.8 -0.4)
			(end 0.8 0.4)
			(stroke
				(width 0.15)
				(type solid)
			)
			(fill no)
			(layer "F.Fab")
		)
		(pad "1" smd roundrect
			(at -0.7 0 270)
			(size 0.8 1)
			(layers "F.Cu" "F.Mask" "F.Paste")
			(roundrect_rratio 0.2)
			(net 1 "GND")
			(pintype "passive")
			(teardrops
				(best_length_ratio 0.2)
				(max_length 1)
				(best_width_ratio 0.9)
				(max_width 2)
				(curved_edges yes)
				(filter_ratio 0.9)
				(enabled yes)
				(allow_two_segments yes)
				(prefer_zone_connections yes)
			)
		)
		(pad "2" smd roundrect
			(at 0.7 0 270)
			(size 0.8 1)
			(layers "F.Cu" "F.Mask" "F.Paste")
			(roundrect_rratio 0.2)
			(net 62 "+12V_AON")
			(pintype "passive")
			(teardrops
				(best_length_ratio 0.2)
				(max_length 1)
				(best_width_ratio 0.9)
				(max_width 2)
				(curved_edges yes)
				(filter_ratio 0.9)
				(enabled yes)
				(allow_two_segments yes)
				(prefer_zone_connections yes)
			)
		)
	)
	(footprint "antmicro-footprints:R_0402_1005Metric"
		(layer "F.Cu")
		(at 136.6 101.41 180)
		(descr "Resistor SMD 0402")
		(tags "resistor SMD 0402")
		(property "Reference" "R17"
			(at -1.1 -1.4 0)
			(layer "F.SilkS")
			(effects
				(font
					(size 0.7 0.7)
					(thickness 0.15)
				)
				(justify right bottom)
			)
		)
		(property "Value" "R_75R_0402"
			(at -1.011843 1.772047 0)
			(layer "F.Fab")
			(effects
				(font
					(size 0.7 0.7)
					(thickness 0.15)
				)
				(justify right bottom)
			)
		)
		(property "Datasheet" "https://www.bourns.com/docs/product-datasheets/cr.pdf"
			(at 0 0 180)
			(layer "F.Fab")
			(hide yes)
			(effects
				(font
					(size 1.27 1.27)
					(thickness 0.15)
				)
			)
		)
		(property "Author" "Antmicro"
			(at 273.2 202.82 0)
			(layer "F.Fab")
			(hide yes)
			(effects
				(font
					(size 1 1)
					(thickness 0.15)
				)
			)
		)
		(property "License" "Apache-2.0"
			(at 273.2 202.82 0)
			(layer "F.Fab")
			(hide yes)
			(effects
				(font
					(size 1 1)
					(thickness 0.15)
				)
			)
		)
		(property "MPN" "CR0402-FX-75R0GLF"
			(at 273.2 202.82 0)
			(layer "F.Fab")
			(hide yes)
			(effects
				(font
					(size 1 1)
					(thickness 0.15)
				)
			)
		)
		(property "Manufacturer" "Bourns"
			(at 273.2 202.82 0)
			(layer "F.Fab")
			(hide yes)
			(effects
				(font
					(size 1 1)
					(thickness 0.15)
				)
			)
		)
		(property "Public" "False"
			(at 273.2 202.82 0)
			(layer "F.Fab")
			(hide yes)
			(effects
				(font
					(size 1 1)
					(thickness 0.15)
				)
			)
		)
		(property "Tolerance" "1%"
			(at 273.2 202.82 0)
			(layer "F.Fab")
			(hide yes)
			(effects
				(font
					(size 1 1)
					(thickness 0.15)
				)
			)
		)
		(property "Val" "75R"
			(at 273.2 202.82 0)
			(layer "F.Fab")
			(hide yes)
			(effects
				(font
					(size 1 1)
					(thickness 0.15)
				)
			)
		)
		(sheetname "2xUSB3.0+RJ45")
		(sheetfile "usb3+rj45.kicad_sch")
		(attr smd)
		(fp_rect
			(start -0.925 -0.47)
			(end 0.925 0.47)
			(stroke
				(width 0.05)
				(type default)
			)
			(fill no)
			(layer "F.CrtYd")
		)
		(fp_rect
			(start -0.5 -0.25)
			(end 0.5 0.25)
			(stroke
				(width 0.15)
				(type solid)
			)
			(fill no)
			(layer "F.Fab")
		)
		(pad "1" smd roundrect
			(at -0.48 0 180)
			(size 0.59 0.64)
			(layers "F.Cu" "F.Mask" "F.Paste")
			(roundrect_rratio 0.25)
			(net 50 "Net-(C12-Pad2)")
			(pintype "passive")
			(teardrops
				(best_length_ratio 0.2)
				(max_length 1)
				(best_width_ratio 0.9)
				(max_width 2)
				(curved_edges yes)
				(filter_ratio 0.9)
				(enabled yes)
				(allow_two_segments yes)
				(prefer_zone_connections yes)
			)
		)
		(pad "2" smd roundrect
			(at 0.48 0 180)
			(size 0.59 0.64)
			(layers "F.Cu" "F.Mask" "F.Paste")
			(roundrect_rratio 0.25)
			(net 552 "Net-(R17-Pad2)")
			(pintype "passive")
			(teardrops
				(best_length_ratio 0.2)
				(max_length 1)
				(best_width_ratio 0.9)
				(max_width 2)
				(curved_edges yes)
				(filter_ratio 0.9)
				(enabled yes)
				(allow_two_segments yes)
				(prefer_zone_connections yes)
			)
		)
	)
	(footprint "antmicro-footprints:R_0402_1005Metric"
		(layer "F.Cu")
		(at 114.4 150.36 -90)
		(descr "Resistor SMD 0402")
		(tags "resistor SMD 0402")
		(property "Reference" "R208"
			(at -0.46 -4.5 90)
			(layer "F.SilkS")
			(effects
				(font
					(size 0.7 0.7)
					(thickness 0.15)
				)
				(justify right bottom)
			)
		)
		(property "Value" "R_1k_0402"
			(at -1.011843 1.772047 90)
			(layer "F.Fab")
			(effects
				(font
					(size 0.7 0.7)
					(thickness 0.15)
				)
				(justify right bottom)
			)
		)
		(property "Datasheet" "https://www.bourns.com/docs/product-datasheets/cr.pdf"
			(at 0 0 270)
			(layer "F.Fab")
			(hide yes)
			(effects
				(font
					(size 1.27 1.27)
					(thickness 0.15)
				)
			)
		)
		(property "Author" "Antmicro"
			(at -35.96 264.76 0)
			(layer "F.Fab")
			(hide yes)
			(effects
				(font
					(size 1 1)
					(thickness 0.15)
				)
			)
		)
		(property "License" "Apache-2.0"
			(at -35.96 264.76 0)
			(layer "F.Fab")
			(hide yes)
			(effects
				(font
					(size 1 1)
					(thickness 0.15)
				)
			)
		)
		(property "MPN" "CR0402-FX-1001GLF"
			(at -35.96 264.76 0)
			(layer "F.Fab")
			(hide yes)
			(effects
				(font
					(size 1 1)
					(thickness 0.15)
				)
			)
		)
		(property "Manufacturer" "Bourns"
			(at -35.96 264.76 0)
			(layer "F.Fab")
			(hide yes)
			(effects
				(font
					(size 1 1)
					(thickness 0.15)
				)
			)
		)
		(property "Public" "False"
			(at -35.96 264.76 0)
			(layer "F.Fab")
			(hide yes)
			(effects
				(font
					(size 1 1)
					(thickness 0.15)
				)
			)
		)
		(property "Tolerance" "1%"
			(at -35.96 264.76 0)
			(layer "F.Fab")
			(hide yes)
			(effects
				(font
					(size 1 1)
					(thickness 0.15)
				)
			)
		)
		(property "Val" "1k"
			(at -35.96 264.76 0)
			(layer "F.Fab")
			(hide yes)
			(effects
				(font
					(size 1 1)
					(thickness 0.15)
				)
			)
		)
		(sheetname "PCIe redriver")
		(sheetfile "pcie_redriver.kicad_sch")
		(attr smd dnp)
		(fp_rect
			(start -0.925 -0.47)
			(end 0.925 0.47)
			(stroke
				(width 0.05)
				(type default)
			)
			(fill no)
			(layer "F.CrtYd")
		)
		(fp_rect
			(start -0.5 -0.25)
			(end 0.5 0.25)
			(stroke
				(width 0.15)
				(type solid)
			)
			(fill no)
			(layer "F.Fab")
		)
		(pad "1" smd roundrect
			(at -0.48 0 270)
			(size 0.59 0.64)
			(layers "F.Cu" "F.Mask" "F.Paste")
			(roundrect_rratio 0.25)
			(net 2 "+3V3")
			(pintype "passive")
			(teardrops
				(best_length_ratio 0.2)
				(max_length 1)
				(best_width_ratio 0.9)
				(max_width 2)
				(curved_edges yes)
				(filter_ratio 0.9)
				(enabled yes)
				(allow_two_segments yes)
				(prefer_zone_connections yes)
			)
		)
		(pad "2" smd roundrect
			(at 0.48 0 270)
			(size 0.59 0.64)
			(layers "F.Cu" "F.Mask" "F.Paste")
			(roundrect_rratio 0.25)
			(net 626 "/PCIe redriver/TX_FG0")
			(pintype "passive")
			(teardrops
				(best_length_ratio 0.2)
				(max_length 1)
				(best_width_ratio 0.9)
				(max_width 2)
				(curved_edges yes)
				(filter_ratio 0.9)
				(enabled yes)
				(allow_two_segments yes)
				(prefer_zone_connections yes)
			)
		)
	)
	(footprint "antmicro-footprints:TP_SMD_0.75mm"
		(layer "F.Cu")
		(at 156.35 129.56)
		(property "Reference" "TP69"
			(at 0.45 -1.25 90)
			(layer "F.SilkS")
			(effects
				(font
					(size 0.7 0.7)
					(thickness 0.15)
				)
				(justify left bottom)
			)
		)
		(property "Value" "TP_0.75mm_SMD"
			(at 0 1.2 0)
			(layer "F.Fab")
			(effects
				(font
					(size 0.7 0.7)
					(thickness 0.15)
				)
				(justify left bottom)
			)
		)
		(property "Author" "Antmicro"
			(at 0 0 0)
			(layer "F.Fab")
			(hide yes)
			(effects
				(font
					(size 1 1)
					(thickness 0.15)
				)
			)
		)
		(property "License" "Apache-2.0"
			(at 0 0 0)
			(layer "F.Fab")
			(hide yes)
			(effects
				(font
					(size 1 1)
					(thickness 0.15)
				)
			)
		)
		(property "MPN" ""
			(at 0 0 0)
			(layer "F.Fab")
			(hide yes)
			(effects
				(font
					(size 1 1)
					(thickness 0.15)
				)
			)
		)
		(property "Manufacturer" ""
			(at 0 0 0)
			(layer "F.Fab")
			(hide yes)
			(effects
				(font
					(size 1 1)
					(thickness 0.15)
				)
			)
		)
		(property "Public" "False"
			(at 0 0 0)
			(layer "F.Fab")
			(hide yes)
			(effects
				(font
					(size 1 1)
					(thickness 0.15)
				)
			)
		)
		(sheetname "KR to SFI #1")
		(sheetfile "kr_sfi.kicad_sch")
		(attr exclude_from_pos_files exclude_from_bom)
		(fp_circle
			(center 0 0)
			(end 0.475 0)
			(stroke
				(width 0.05)
				(type default)
			)
			(fill no)
			(layer "F.CrtYd")
		)
		(pad "1" smd circle
			(at 0 0)
			(size 0.75 0.75)
			(layers "F.Cu" "F.Mask")
			(net 732 "Net-(U43C-CLKOUTB+)")
			(pinfunction "1")
			(pintype "passive")
			(teardrops
				(best_length_ratio 0.4)
				(max_length 1)
				(best_width_ratio 0.9)
				(max_width 2)
				(curved_edges yes)
				(filter_ratio 0.9)
				(enabled yes)
				(allow_two_segments yes)
				(prefer_zone_connections yes)
			)
		)
	)
	(footprint "antmicro-footprints:TP_SMD_0.75mm"
		(layer "F.Cu")
		(at 153.75 129.56)
		(property "Reference" "TP61"
			(at 0.45 -1.25 90)
			(layer "F.SilkS")
			(effects
				(font
					(size 0.7 0.7)
					(thickness 0.15)
				)
				(justify left bottom)
			)
		)
		(property "Value" "TP_0.75mm_SMD"
			(at 0 1.2 0)
			(layer "F.Fab")
			(effects
				(font
					(size 0.7 0.7)
					(thickness 0.15)
				)
				(justify left bottom)
			)
		)
		(property "Author" "Antmicro"
			(at 0 0 0)
			(layer "F.Fab")
			(hide yes)
			(effects
				(font
					(size 1 1)
					(thickness 0.15)
				)
			)
		)
		(property "License" "Apache-2.0"
			(at 0 0 0)
			(layer "F.Fab")
			(hide yes)
			(effects
				(font
					(size 1 1)
					(thickness 0.15)
				)
			)
		)
		(property "MPN" ""
			(at 0 0 0)
			(layer "F.Fab")
			(hide yes)
			(effects
				(font
					(size 1 1)
					(thickness 0.15)
				)
			)
		)
		(property "Manufacturer" ""
			(at 0 0 0)
			(layer "F.Fab")
			(hide yes)
			(effects
				(font
					(size 1 1)
					(thickness 0.15)
				)
			)
		)
		(property "Public" "False"
			(at 0 0 0)
			(layer "F.Fab")
			(hide yes)
			(effects
				(font
					(size 1 1)
					(thickness 0.15)
				)
			)
		)
		(sheetname "KR to SFI #1")
		(sheetfile "kr_sfi.kicad_sch")
		(attr exclude_from_pos_files exclude_from_bom)
		(fp_circle
			(center 0 0)
			(end 0.475 0)
			(stroke
				(width 0.05)
				(type default)
			)
			(fill no)
			(layer "F.CrtYd")
		)
		(pad "1" smd circle
			(at 0 0)
			(size 0.75 0.75)
			(layers "F.Cu" "F.Mask")
			(net 724 "/2xSFP+/KR to SFI #1/TMS")
			(pinfunction "1")
			(pintype "passive")
			(teardrops
				(best_length_ratio 0.4)
				(max_length 1)
				(best_width_ratio 0.9)
				(max_width 2)
				(curved_edges yes)
				(filter_ratio 0.9)
				(enabled yes)
				(allow_two_segments yes)
				(prefer_zone_connections yes)
			)
		)
	)
	(footprint "antmicro-footprints:PinHeader_1x3_P2.54mm_Drill1.1mm"
		(layer "F.Cu")
		(at 216.42 70.61)
		(property "Reference" "J13"
			(at 7.67 1.36 90)
			(layer "F.SilkS")
			(effects
				(font
					(size 0.7 0.7)
					(thickness 0.15)
				)
				(justify left bottom)
			)
		)
		(property "Value" "PinHeader_1x3_P2.54mm_Drill1.1mm"
			(at -1.6 2.7 0)
			(layer "F.Fab")
			(effects
				(font
					(size 0.7 0.7)
					(thickness 0.15)
				)
				(justify left bottom)
			)
		)
		(property "Datasheet" "https://katalog.we-online.de/em/datasheet/6130xx11121.pdf"
			(at 0 0 0)
			(layer "F.Fab")
			(hide yes)
			(effects
				(font
					(size 1.27 1.27)
					(thickness 0.15)
				)
			)
		)
		(property "Author" "Antmicro"
			(at 0 0 0)
			(layer "F.Fab")
			(hide yes)
			(effects
				(font
					(size 1 1)
					(thickness 0.15)
				)
			)
		)
		(property "License" "Apache-2.0"
			(at 0 0 0)
			(layer "F.Fab")
			(hide yes)
			(effects
				(font
					(size 1 1)
					(thickness 0.15)
				)
			)
		)
		(property "MPN" "61300311121"
			(at 0 0 0)
			(layer "F.Fab")
			(hide yes)
			(effects
				(font
					(size 1 1)
					(thickness 0.15)
				)
			)
		)
		(property "Manufacturer" "Würth Elektronik"
			(at 0 0 0)
			(layer "F.Fab")
			(hide yes)
			(effects
				(font
					(size 1 1)
					(thickness 0.15)
				)
			)
		)
		(sheetname "Com Express 7 MGMT")
		(sheetfile "com_express_7_mgmt.kicad_sch")
		(attr through_hole)
		(fp_line
			(start -1.401 -1.401)
			(end -1.401 -0.902)
			(stroke
				(width 0.15)
				(type solid)
			)
			(layer "F.SilkS")
		)
		(fp_line
			(start -1.401 -1.401)
			(end -0.902 -1.401)
			(stroke
				(width 0.15)
				(type solid)
			)
			(layer "F.SilkS")
		)
		(fp_line
			(start -1.401 1.398)
			(end -1.401 0.9)
			(stroke
				(width 0.15)
				(type solid)
			)
			(layer "F.SilkS")
		)
		(fp_line
			(start -1.401 1.398)
			(end -0.902 1.398)
			(stroke
				(width 0.15)
				(type solid)
			)
			(layer "F.SilkS")
		)
		(fp_line
			(start 6.499 -1.401)
			(end 5.999 -1.401)
			(stroke
				(width 0.15)
				(type solid)
			)
			(layer "F.SilkS")
		)
		(fp_line
			(start 6.499 -1.401)
			(end 6.499 -0.902)
			(stroke
				(width 0.15)
				(type solid)
			)
			(layer "F.SilkS")
		)
		(fp_line
			(start 6.499 1.398)
			(end 5.999 1.398)
			(stroke
				(width 0.15)
				(type solid)
			)
			(layer "F.SilkS")
		)
		(fp_line
			(start 6.499 1.398)
			(end 6.499 0.9)
			(stroke
				(width 0.15)
				(type solid)
			)
			(layer "F.SilkS")
		)
		(fp_line
			(start -1.52 -1.52)
			(end -1.52 1.5)
			(stroke
				(width 0.05)
				(type solid)
			)
			(layer "F.CrtYd")
		)
		(fp_line
			(start -1.52 -1.52)
			(end 6.58 -1.52)
			(stroke
				(width 0.05)
				(type solid)
			)
			(layer "F.CrtYd")
		)
		(fp_line
			(start -1.52 1.5)
			(end 6.58 1.5)
			(stroke
				(width 0.05)
				(type solid)
			)
			(layer "F.CrtYd")
		)
		(fp_line
			(start 6.58 -1.52)
			(end 6.58 1.5)
			(stroke
				(width 0.05)
				(type solid)
			)
			(layer "F.CrtYd")
		)
		(fp_line
			(start -1.27 -1.27)
			(end -1.27 1.269)
			(stroke
				(width 0.15)
				(type solid)
			)
			(layer "F.Fab")
		)
		(fp_line
			(start -1.27 -1.27)
			(end 6.349 -1.27)
			(stroke
				(width 0.15)
				(type solid)
			)
			(layer "F.Fab")
		)
		(fp_line
			(start -1.27 1.269)
			(end 6.349 1.269)
			(stroke
				(width 0.15)
				(type solid)
			)
			(layer "F.Fab")
		)
		(fp_line
			(start 6.349 -1.27)
			(end 6.349 1.269)
			(stroke
				(width 0.15)
				(type solid)
			)
			(layer "F.Fab")
		)
		(pad "1" thru_hole rect
			(at 0 0)
			(size 1.7 1.7)
			(drill 1.1)
			(layers "*.Cu" "*.Mask")
			(remove_unused_layers no)
			(net 523 "Net-(J13-Pad1)")
			(pintype "passive")
			(teardrops
				(best_length_ratio 0.2)
				(max_length 1)
				(best_width_ratio 0.9)
				(max_width 2)
				(curved_edges yes)
				(filter_ratio 0.9)
				(enabled yes)
				(allow_two_segments yes)
				(prefer_zone_connections yes)
			)
		)
		(pad "2" thru_hole circle
			(at 2.539 0)
			(size 1.7 1.7)
			(drill 1.1)
			(layers "*.Cu" "*.Mask")
			(remove_unused_layers no)
			(net 315 "Net-(J12H-VCC_RTC)")
			(pintype "passive")
			(teardrops
				(best_length_ratio 0.4)
				(max_length 1)
				(best_width_ratio 0.9)
				(max_width 2)
				(curved_edges yes)
				(filter_ratio 0.9)
				(enabled yes)
				(allow_two_segments yes)
				(prefer_zone_connections yes)
			)
		)
		(pad "3" thru_hole circle
			(at 5.078 0)
			(size 1.7 1.7)
			(drill 1.1)
			(layers "*.Cu" "*.Mask")
			(remove_unused_layers no)
			(net 135 "Net-(D19-Pad3)")
			(pintype "passive")
			(teardrops
				(best_length_ratio 0.4)
				(max_length 1)
				(best_width_ratio 0.9)
				(max_width 2)
				(curved_edges yes)
				(filter_ratio 0.9)
				(enabled yes)
				(allow_two_segments yes)
				(prefer_zone_connections yes)
			)
		)
	)
	(footprint "antmicro-footprints:Spacer_Drill3.7mm_H5mm_9774050151R"
		(layer "F.Cu")
		(at 278.93 80.8 90)
		(descr "Spacer M=3 h=5mm fi=5.1mm")
		(property "Reference" "H9"
			(at 0 -3.2 90)
			(layer "F.SilkS")
			(hide yes)
			(effects
				(font
					(size 0.7 0.7)
					(thickness 0.15)
				)
				(justify left bottom)
			)
		)
		(property "Value" "Spacer_Drill3.7mm_H5mm_9774050151R"
			(at 0 4 90)
			(layer "F.Fab")
			(effects
				(font
					(size 0.7 0.7)
					(thickness 0.15)
				)
				(justify left bottom)
			)
		)
		(property "Datasheet" "https://www.we-online.com/catalog/datasheet/9774050151.pdf"
			(at 0 0 90)
			(layer "F.Fab")
			(hide yes)
			(effects
				(font
					(size 1.27 1.27)
					(thickness 0.15)
				)
			)
		)
		(property "Author" "Antmicro"
			(at 359.74 -198.12 0)
			(layer "F.Fab")
			(hide yes)
			(effects
				(font
					(size 1 1)
					(thickness 0.15)
				)
			)
		)
		(property "License" "Apache-2.0"
			(at 359.74 -198.12 0)
			(layer "F.Fab")
			(hide yes)
			(effects
				(font
					(size 1 1)
					(thickness 0.15)
				)
			)
		)
		(property "MPN" "9774050151R"
			(at 359.74 -198.12 0)
			(layer "F.Fab")
			(hide yes)
			(effects
				(font
					(size 1 1)
					(thickness 0.15)
				)
			)
		)
		(property "Manufacturer" "Würth Elektronik"
			(at 359.74 -198.12 0)
			(layer "F.Fab")
			(hide yes)
			(effects
				(font
					(size 1 1)
					(thickness 0.15)
				)
			)
		)
		(sheetname "Com Express 7 Interfaces")
		(sheetfile "com_express_7_interfaces.kicad_sch")
		(solder_paste_margin_ratio -1)
		(attr smd)
		(fp_circle
			(center 0 0)
			(end 3.05 0)
			(stroke
				(width 0.05)
				(type solid)
			)
			(fill no)
			(layer "F.CrtYd")
		)
		(fp_circle
			(center 0 0)
			(end 2.6 0)
			(stroke
				(width 0.15)
				(type solid)
			)
			(fill no)
			(layer "F.Fab")
		)
		(pad "" smd custom
			(at -1.7 -1.7 90)
			(size 0.62 0.62)
			(layers "F.Paste")
			(thermal_bridge_angle 90)
			(options
				(clearance outline)
				(anchor circle)
			)
			(primitives
				(gr_arc
					(start -0.250195 1.279127)
					(mid 0.285453 0.294389)
					(end 1.266786 -0.24747)
					(width 0.2)
				)
				(gr_arc
					(start -0.34334 1.279127)
					(mid 0.218448 0.232561)
					(end 1.259603 -0.339191)
					(width 0.2)
				)
				(gr_arc
					(start -0.436309 1.279127)
					(mid 0.152481 0.169693)
					(end 1.255279 -0.431435)
					(width 0.2)
				)
				(gr_arc
					(start -0.529126 1.279127)
					(mid 0.087542 0.105784)
					(end 1.253811 -0.524161)
					(width 0.2)
				)
				(gr_arc
					(start -0.621807 1.279127)
					(mid 0.0309 0.033527)
					(end 1.275473 -0.621136)
					(width 0.2)
				)
				(gr_arc
					(start -0.71437 1.279127)
					(mid -0.037758 -0.026651)
					(end 1.263664 -0.711602)
					(width 0.2)
				)
				(gr_arc
					(start -0.806826 1.279127)
					(mid -0.105837 -0.087395)
					(end 1.253435 -0.802342)
					(width 0.2)
				)
				(gr_arc
					(start -0.899187 1.279127)
					(mid -0.165236 -0.156885)
					(end 1.267475 -0.897258)
					(width 0.2)
				)
				(gr_arc
					(start -0.991463 1.279127)
					(mid -0.228522 -0.222449)
					(end 1.270645 -0.990112)
					(width 0.2)
				)
				(gr_arc
					(start -1.083663 1.279127)
					(mid -0.294507 -0.285313)
					(end 1.266278 -1.081674)
					(width 0.2)
				)
				(gr_line
					(start 1.279127 -0.250195)
					(end 1.279127 -1.083663)
					(width 0.2)
				)
				(gr_line
					(start -0.250195 1.279127)
					(end -1.083663 1.279127)
					(width 0.2)
				)
			)
			(teardrops
				(best_length_ratio 0.2)
				(max_length 1)
				(best_width_ratio 0.9)
				(max_width 2)
				(curved_edges yes)
				(filter_ratio 0.9)
				(enabled yes)
				(allow_two_segments yes)
				(prefer_zone_connections yes)
			)
		)
		(pad "" smd custom
			(at -1.7 1.7 180)
			(size 0.62 0.62)
			(layers "F.Paste")
			(thermal_bridge_angle 90)
			(options
				(clearance outline)
				(anchor circle)
			)
			(primitives
				(gr_arc
					(start -0.250195 1.279127)
					(mid 0.285453 0.294389)
					(end 1.266786 -0.24747)
					(width 0.2)
				)
				(gr_arc
					(start -0.34334 1.279127)
					(mid 0.218448 0.232561)
					(end 1.259603 -0.339191)
					(width 0.2)
				)
				(gr_arc
					(start -0.436309 1.279127)
					(mid 0.152481 0.169693)
					(end 1.255279 -0.431435)
					(width 0.2)
				)
				(gr_arc
					(start -0.529126 1.279127)
					(mid 0.087542 0.105784)
					(end 1.253811 -0.524161)
					(width 0.2)
				)
				(gr_arc
					(start -0.621807 1.279127)
					(mid 0.0309 0.033527)
					(end 1.275473 -0.621136)
					(width 0.2)
				)
				(gr_arc
					(start -0.71437 1.279127)
					(mid -0.037758 -0.026651)
					(end 1.263664 -0.711602)
					(width 0.2)
				)
				(gr_arc
					(start -0.806826 1.279127)
					(mid -0.105837 -0.087395)
					(end 1.253435 -0.802342)
					(width 0.2)
				)
				(gr_arc
					(start -0.899187 1.279127)
					(mid -0.165236 -0.156885)
					(end 1.267475 -0.897258)
					(width 0.2)
				)
				(gr_arc
					(start -0.991463 1.279127)
					(mid -0.228522 -0.222449)
					(end 1.270645 -0.990112)
					(width 0.2)
				)
				(gr_arc
					(start -1.083663 1.279127)
					(mid -0.294507 -0.285313)
					(end 1.266278 -1.081674)
					(width 0.2)
				)
				(gr_line
					(start 1.279127 -0.250195)
					(end 1.279127 -1.083663)
					(width 0.2)
				)
				(gr_line
					(start -0.250195 1.279127)
					(end -1.083663 1.279127)
					(width 0.2)
				)
			)
			(teardrops
				(best_length_ratio 0.2)
				(max_length 1)
				(best_width_ratio 0.9)
				(max_width 2)
				(curved_edges yes)
				(filter_ratio 0.9)
				(enabled yes)
				(allow_two_segments yes)
				(prefer_zone_connections yes)
			)
		)
		(pad "" smd custom
			(at 1.7 -1.7)
			(size 0.62 0.62)
			(layers "F.Paste")
			(thermal_bridge_angle 90)
			(options
				(clearance outline)
				(anchor circle)
			)
			(primitives
				(gr_arc
					(start -0.250195 1.279127)
					(mid 0.285453 0.294389)
					(end 1.266786 -0.24747)
					(width 0.2)
				)
				(gr_arc
					(start -0.34334 1.279127)
					(mid 0.218448 0.232561)
					(end 1.259603 -0.339191)
					(width 0.2)
				)
				(gr_arc
					(start -0.436309 1.279127)
					(mid 0.152481 0.169693)
					(end 1.255279 -0.431435)
					(width 0.2)
				)
				(gr_arc
					(start -0.529126 1.279127)
					(mid 0.087542 0.105784)
					(end 1.253811 -0.524161)
					(width 0.2)
				)
				(gr_arc
					(start -0.621807 1.279127)
					(mid 0.0309 0.033527)
					(end 1.275473 -0.621136)
					(width 0.2)
				)
				(gr_arc
					(start -0.71437 1.279127)
					(mid -0.037758 -0.026651)
					(end 1.263664 -0.711602)
					(width 0.2)
				)
				(gr_arc
					(start -0.806826 1.279127)
					(mid -0.105837 -0.087395)
					(end 1.253435 -0.802342)
					(width 0.2)
				)
				(gr_arc
					(start -0.899187 1.279127)
					(mid -0.165236 -0.156885)
					(end 1.267475 -0.897258)
					(width 0.2)
				)
				(gr_arc
					(start -0.991463 1.279127)
					(mid -0.228522 -0.222449)
					(end 1.270645 -0.990112)
					(width 0.2)
				)
				(gr_arc
					(start -1.083663 1.279127)
					(mid -0.294507 -0.285313)
					(end 1.266278 -1.081674)
					(width 0.2)
				)
				(gr_line
					(start 1.279127 -0.250195)
					(end 1.279127 -1.083663)
					(width 0.2)
				)
				(gr_line
					(start -0.250195 1.279127)
					(end -1.083663 1.279127)
					(width 0.2)
				)
			)
			(teardrops
				(best_length_ratio 0.2)
				(max_length 1)
				(best_width_ratio 0.9)
				(max_width 2)
				(curved_edges yes)
				(filter_ratio 0.9)
				(enabled yes)
				(allow_two_segments yes)
				(prefer_zone_connections yes)
			)
		)
		(pad "" smd custom
			(at 1.7 1.7 270)
			(size 0.62 0.62)
			(layers "F.Paste")
			(thermal_bridge_angle 90)
			(options
				(clearance outline)
				(anchor circle)
			)
			(primitives
				(gr_arc
					(start -0.250195 1.279127)
					(mid 0.285453 0.294389)
					(end 1.266786 -0.24747)
					(width 0.2)
				)
				(gr_arc
					(start -0.34334 1.279127)
					(mid 0.218448 0.232561)
					(end 1.259603 -0.339191)
					(width 0.2)
				)
				(gr_arc
					(start -0.436309 1.279127)
					(mid 0.152481 0.169693)
					(end 1.255279 -0.431435)
					(width 0.2)
				)
				(gr_arc
					(start -0.529126 1.279127)
					(mid 0.087542 0.105784)
					(end 1.253811 -0.524161)
					(width 0.2)
				)
				(gr_arc
					(start -0.621807 1.279127)
					(mid 0.0309 0.033527)
					(end 1.275473 -0.621136)
					(width 0.2)
				)
				(gr_arc
					(start -0.71437 1.279127)
					(mid -0.037758 -0.026651)
					(end 1.263664 -0.711602)
					(width 0.2)
				)
				(gr_arc
					(start -0.806826 1.279127)
					(mid -0.105837 -0.087395)
					(end 1.253435 -0.802342)
					(width 0.2)
				)
				(gr_arc
					(start -0.899187 1.279127)
					(mid -0.165236 -0.156885)
					(end 1.267475 -0.897258)
					(width 0.2)
				)
				(gr_arc
					(start -0.991463 1.279127)
					(mid -0.228522 -0.222449)
					(end 1.270645 -0.990112)
					(width 0.2)
				)
				(gr_arc
					(start -1.083663 1.279127)
					(mid -0.294507 -0.285313)
					(end 1.266278 -1.081674)
					(width 0.2)
				)
				(gr_line
					(start 1.279127 -0.250195)
					(end 1.279127 -1.083663)
					(width 0.2)
				)
				(gr_line
					(start -0.250195 1.279127)
					(end -1.083663 1.279127)
					(width 0.2)
				)
			)
			(teardrops
				(best_length_ratio 0.2)
				(max_length 1)
				(best_width_ratio 0.9)
				(max_width 2)
				(curved_edges yes)
				(filter_ratio 0.9)
				(enabled yes)
				(allow_two_segments yes)
				(prefer_zone_connections yes)
			)
		)
		(pad "1" thru_hole circle
			(at 0 0 90)
			(size 6 6)
			(drill 3.7)
			(layers "*.Cu" "*.Mask")
			(remove_unused_layers no)
			(net 1 "GND")
			(pintype "passive")
			(teardrops
				(best_length_ratio 0.4)
				(max_length 1)
				(best_width_ratio 0.9)
				(max_width 2)
				(curved_edges yes)
				(filter_ratio 0.9)
				(enabled yes)
				(allow_two_segments yes)
				(prefer_zone_connections yes)
			)
		)
	)
	(footprint "antmicro-footprints:R_0201"
		(layer "F.Cu")
		(at 146.57 147.935 -90)
		(descr "Resistor SMD 0201")
		(tags "resistor SMD 0201")
		(property "Reference" "R278"
			(at 3.625 -0.28 90)
			(layer "F.SilkS")
			(effects
				(font
					(size 0.7 0.7)
					(thickness 0.15)
				)
				(justify right bottom)
			)
		)
		(property "Value" "R_0R_0201"
			(at 0 1.25 90)
			(layer "F.Fab")
			(effects
				(font
					(size 0.7 0.7)
					(thickness 0.15)
				)
				(justify right bottom)
			)
		)
		(property "Datasheet" "https://www.bourns.com/docs/product-datasheets/cr.pdf"
			(at 0 0 270)
			(layer "F.Fab")
			(hide yes)
			(effects
				(font
					(size 1.27 1.27)
					(thickness 0.15)
				)
			)
		)
		(property "Author" "Antmicro"
			(at -1.365 294.505 0)
			(layer "F.Fab")
			(hide yes)
			(effects
				(font
					(size 1 1)
					(thickness 0.15)
				)
			)
		)
		(property "License" "Apache-2.0"
			(at -1.365 294.505 0)
			(layer "F.Fab")
			(hide yes)
			(effects
				(font
					(size 1 1)
					(thickness 0.15)
				)
			)
		)
		(property "MPN" "CR0201-FX-0R00GLF"
			(at -1.365 294.505 0)
			(layer "F.Fab")
			(hide yes)
			(effects
				(font
					(size 1 1)
					(thickness 0.15)
				)
			)
		)
		(property "Manufacturer" "Bourns"
			(at -1.365 294.505 0)
			(layer "F.Fab")
			(hide yes)
			(effects
				(font
					(size 1 1)
					(thickness 0.15)
				)
			)
		)
		(property "Tolerance" "1%"
			(at -1.365 294.505 0)
			(layer "F.Fab")
			(hide yes)
			(effects
				(font
					(size 1 1)
					(thickness 0.15)
				)
			)
		)
		(property "Val" "0R"
			(at -1.365 294.505 0)
			(layer "F.Fab")
			(hide yes)
			(effects
				(font
					(size 1 1)
					(thickness 0.15)
				)
			)
		)
		(sheetname "KR to SFI #1")
		(sheetfile "kr_sfi.kicad_sch")
		(attr smd dnp)
		(fp_rect
			(start -0.7 -0.35)
			(end 0.7 0.35)
			(stroke
				(width 0.05)
				(type default)
			)
			(fill no)
			(layer "F.CrtYd")
		)
		(fp_rect
			(start -0.3 -0.15)
			(end 0.298 0.148)
			(stroke
				(width 0.15)
				(type solid)
			)
			(fill no)
			(layer "F.Fab")
		)
		(pad "" smd roundrect
			(at -0.346 0 270)
			(size 0.318 0.36)
			(layers "F.Paste")
			(roundrect_rratio 0.25)
			(teardrops
				(best_length_ratio 0.2)
				(max_length 1)
				(best_width_ratio 0.9)
				(max_width 2)
				(curved_edges yes)
				(filter_ratio 0.9)
				(enabled yes)
				(allow_two_segments yes)
				(prefer_zone_connections yes)
			)
		)
		(pad "" smd roundrect
			(at 0.344 0 270)
			(size 0.318 0.36)
			(layers "F.Paste")
			(roundrect_rratio 0.25)
			(teardrops
				(best_length_ratio 0.2)
				(max_length 1)
				(best_width_ratio 0.9)
				(max_width 2)
				(curved_edges yes)
				(filter_ratio 0.9)
				(enabled yes)
				(allow_two_segments yes)
				(prefer_zone_connections yes)
			)
		)
		(pad "1" smd roundrect
			(at -0.32 0 270)
			(size 0.46 0.4)
			(layers "F.Cu" "F.Mask")
			(roundrect_rratio 0.25)
			(net 173 "/2xSFP+/SFI0.TX-")
			(pintype "passive")
			(teardrops
				(best_length_ratio 0.2)
				(max_length 1)
				(best_width_ratio 0.9)
				(max_width 2)
				(curved_edges yes)
				(filter_ratio 0.9)
				(enabled yes)
				(allow_two_segments yes)
				(prefer_zone_connections yes)
			)
		)
		(pad "2" smd roundrect
			(at 0.32 0 270)
			(size 0.46 0.4)
			(layers "F.Cu" "F.Mask")
			(roundrect_rratio 0.25)
			(net 948 "/2xSFP+/KR to SFI #1/BYP_TX-")
			(pintype "passive")
			(teardrops
				(best_length_ratio 0.2)
				(max_length 1)
				(best_width_ratio 0.9)
				(max_width 2)
				(curved_edges yes)
				(filter_ratio 0.9)
				(enabled yes)
				(allow_two_segments yes)
				(prefer_zone_connections yes)
			)
		)
	)
	(footprint "antmicro-footprints:R_0402_1005Metric"
		(layer "F.Cu")
		(at 252.67 90.449999 180)
		(descr "Resistor SMD 0402")
		(tags "resistor SMD 0402")
		(property "Reference" "R156"
			(at 0.87 -0.440001 0)
			(layer "F.SilkS")
			(effects
				(font
					(size 0.7 0.7)
					(thickness 0.15)
				)
				(justify right bottom)
			)
		)
		(property "Value" "R_10k_0402"
			(at -1.011843 1.772047 0)
			(layer "F.Fab")
			(effects
				(font
					(size 0.7 0.7)
					(thickness 0.15)
				)
				(justify right bottom)
			)
		)
		(property "Datasheet" "https://www.bourns.com/docs/product-datasheets/cr.pdf"
			(at 0 0 180)
			(layer "F.Fab")
			(hide yes)
			(effects
				(font
					(size 1.27 1.27)
					(thickness 0.15)
				)
			)
		)
		(property "Author" "Antmicro"
			(at 505.34 180.899998 0)
			(layer "F.Fab")
			(hide yes)
			(effects
				(font
					(size 1 1)
					(thickness 0.15)
				)
			)
		)
		(property "License" "Apache-2.0"
			(at 505.34 180.899998 0)
			(layer "F.Fab")
			(hide yes)
			(effects
				(font
					(size 1 1)
					(thickness 0.15)
				)
			)
		)
		(property "MPN" "CR0402-FX-1002GLF"
			(at 505.34 180.899998 0)
			(layer "F.Fab")
			(hide yes)
			(effects
				(font
					(size 1 1)
					(thickness 0.15)
				)
			)
		)
		(property "Manufacturer" "Bourns"
			(at 505.34 180.899998 0)
			(layer "F.Fab")
			(hide yes)
			(effects
				(font
					(size 1 1)
					(thickness 0.15)
				)
			)
		)
		(property "Public" "False"
			(at 505.34 180.899998 0)
			(layer "F.Fab")
			(hide yes)
			(effects
				(font
					(size 1 1)
					(thickness 0.15)
				)
			)
		)
		(property "Tolerance" "1%"
			(at 505.34 180.899998 0)
			(layer "F.Fab")
			(hide yes)
			(effects
				(font
					(size 1 1)
					(thickness 0.15)
				)
			)
		)
		(property "Val" "10k"
			(at 505.34 180.899998 0)
			(layer "F.Fab")
			(hide yes)
			(effects
				(font
					(size 1 1)
					(thickness 0.15)
				)
			)
		)
		(sheetname "Misc")
		(sheetfile "misc.kicad_sch")
		(attr smd)
		(fp_rect
			(start -0.925 -0.47)
			(end 0.925 0.47)
			(stroke
				(width 0.05)
				(type default)
			)
			(fill no)
			(layer "F.CrtYd")
		)
		(fp_rect
			(start -0.5 -0.25)
			(end 0.5 0.25)
			(stroke
				(width 0.15)
				(type solid)
			)
			(fill no)
			(layer "F.Fab")
		)
		(pad "1" smd roundrect
			(at -0.48 0 180)
			(size 0.59 0.64)
			(layers "F.Cu" "F.Mask" "F.Paste")
			(roundrect_rratio 0.25)
			(net 597 "/Misc/PWM1")
			(pintype "passive")
			(teardrops
				(best_length_ratio 0.2)
				(max_length 1)
				(best_width_ratio 0.9)
				(max_width 2)
				(curved_edges yes)
				(filter_ratio 0.9)
				(enabled yes)
				(allow_two_segments yes)
				(prefer_zone_connections yes)
			)
		)
		(pad "2" smd roundrect
			(at 0.48 0 180)
			(size 0.59 0.64)
			(layers "F.Cu" "F.Mask" "F.Paste")
			(roundrect_rratio 0.25)
			(net 2 "+3V3")
			(pintype "passive")
			(teardrops
				(best_length_ratio 0.2)
				(max_length 1)
				(best_width_ratio 0.9)
				(max_width 2)
				(curved_edges yes)
				(filter_ratio 0.9)
				(enabled yes)
				(allow_two_segments yes)
				(prefer_zone_connections yes)
			)
		)
	)
	(footprint "antmicro-footprints:TP_SMD_0.75mm"
		(layer "F.Cu")
		(at 138.2 129.56)
		(property "Reference" "TP89"
			(at 0.45 -1.25 90)
			(layer "F.SilkS")
			(effects
				(font
					(size 0.7 0.7)
					(thickness 0.15)
				)
				(justify left bottom)
			)
		)
		(property "Value" "TP_0.75mm_SMD"
			(at 0 1.2 0)
			(layer "F.Fab")
			(effects
				(font
					(size 0.7 0.7)
					(thickness 0.15)
				)
				(justify left bottom)
			)
		)
		(property "Author" "Antmicro"
			(at 0 0 0)
			(layer "F.Fab")
			(hide yes)
			(effects
				(font
					(size 1 1)
					(thickness 0.15)
				)
			)
		)
		(property "License" "Apache-2.0"
			(at 0 0 0)
			(layer "F.Fab")
			(hide yes)
			(effects
				(font
					(size 1 1)
					(thickness 0.15)
				)
			)
		)
		(property "MPN" ""
			(at 0 0 0)
			(layer "F.Fab")
			(hide yes)
			(effects
				(font
					(size 1 1)
					(thickness 0.15)
				)
			)
		)
		(property "Manufacturer" ""
			(at 0 0 0)
			(layer "F.Fab")
			(hide yes)
			(effects
				(font
					(size 1 1)
					(thickness 0.15)
				)
			)
		)
		(property "Public" "False"
			(at 0 0 0)
			(layer "F.Fab")
			(hide yes)
			(effects
				(font
					(size 1 1)
					(thickness 0.15)
				)
			)
		)
		(sheetname "KR to SFI #2")
		(sheetfile "kr_sfi.kicad_sch")
		(attr exclude_from_pos_files exclude_from_bom)
		(fp_circle
			(center 0 0)
			(end 0.475 0)
			(stroke
				(width 0.05)
				(type default)
			)
			(fill no)
			(layer "F.CrtYd")
		)
		(pad "1" smd circle
			(at 0 0)
			(size 0.75 0.75)
			(layers "F.Cu" "F.Mask")
			(net 752 "Net-(U45C-CLKOUTB+)")
			(pinfunction "1")
			(pintype "passive")
			(teardrops
				(best_length_ratio 0.4)
				(max_length 1)
				(best_width_ratio 0.9)
				(max_width 2)
				(curved_edges yes)
				(filter_ratio 0.9)
				(enabled yes)
				(allow_two_segments yes)
				(prefer_zone_connections yes)
			)
		)
	)
	(footprint "antmicro-footprints:R_0402_1005Metric"
		(layer "F.Cu")
		(at 251.625 130.41 90)
		(descr "Resistor SMD 0402")
		(tags "resistor SMD 0402")
		(property "Reference" "R172"
			(at -5.65 0.425 270)
			(layer "F.SilkS")
			(effects
				(font
					(size 0.7 0.7)
					(thickness 0.15)
				)
				(justify left bottom)
			)
		)
		(property "Value" "R_100k_0402"
			(at -1.011843 1.772047 90)
			(layer "F.Fab")
			(effects
				(font
					(size 0.7 0.7)
					(thickness 0.15)
				)
				(justify left bottom)
			)
		)
		(property "Datasheet" "https://www.bourns.com/docs/product-datasheets/cr.pdf"
			(at 0 0 90)
			(layer "F.Fab")
			(hide yes)
			(effects
				(font
					(size 1.27 1.27)
					(thickness 0.15)
				)
			)
		)
		(property "Author" "Antmicro"
			(at 382.035 -121.215 0)
			(layer "F.Fab")
			(hide yes)
			(effects
				(font
					(size 1 1)
					(thickness 0.15)
				)
			)
		)
		(property "License" "Apache-2.0"
			(at 382.035 -121.215 0)
			(layer "F.Fab")
			(hide yes)
			(effects
				(font
					(size 1 1)
					(thickness 0.15)
				)
			)
		)
		(property "MPN" "CR0402-FX-1003GLF"
			(at 382.035 -121.215 0)
			(layer "F.Fab")
			(hide yes)
			(effects
				(font
					(size 1 1)
					(thickness 0.15)
				)
			)
		)
		(property "Manufacturer" "Bourns"
			(at 382.035 -121.215 0)
			(layer "F.Fab")
			(hide yes)
			(effects
				(font
					(size 1 1)
					(thickness 0.15)
				)
			)
		)
		(property "Public" "False"
			(at 382.035 -121.215 0)
			(layer "F.Fab")
			(hide yes)
			(effects
				(font
					(size 1 1)
					(thickness 0.15)
				)
			)
		)
		(property "Tolerance" "1%"
			(at 382.035 -121.215 0)
			(layer "F.Fab")
			(hide yes)
			(effects
				(font
					(size 1 1)
					(thickness 0.15)
				)
			)
		)
		(property "Val" "100k"
			(at 382.035 -121.215 0)
			(layer "F.Fab")
			(hide yes)
			(effects
				(font
					(size 1 1)
					(thickness 0.15)
				)
			)
		)
		(sheetname "Com Express 7 MGMT")
		(sheetfile "com_express_7_mgmt.kicad_sch")
		(attr smd)
		(fp_rect
			(start -0.925 -0.47)
			(end 0.925 0.47)
			(stroke
				(width 0.05)
				(type default)
			)
			(fill no)
			(layer "F.CrtYd")
		)
		(fp_rect
			(start -0.5 -0.25)
			(end 0.5 0.25)
			(stroke
				(width 0.15)
				(type solid)
			)
			(fill no)
			(layer "F.Fab")
		)
		(pad "1" smd roundrect
			(at -0.48 0 90)
			(size 0.59 0.64)
			(layers "F.Cu" "F.Mask" "F.Paste")
			(roundrect_rratio 0.25)
			(net 1 "GND")
			(pintype "passive")
			(teardrops
				(best_length_ratio 0.2)
				(max_length 1)
				(best_width_ratio 0.9)
				(max_width 2)
				(curved_edges yes)
				(filter_ratio 0.9)
				(enabled yes)
				(allow_two_segments yes)
				(prefer_zone_connections yes)
			)
		)
		(pad "2" smd roundrect
			(at 0.48 0 90)
			(size 0.59 0.64)
			(layers "F.Cu" "F.Mask" "F.Paste")
			(roundrect_rratio 0.25)
			(net 138 "Net-(U33-1A)")
			(pintype "passive")
			(teardrops
				(best_length_ratio 0.2)
				(max_length 1)
				(best_width_ratio 0.9)
				(max_width 2)
				(curved_edges yes)
				(filter_ratio 0.9)
				(enabled yes)
				(allow_two_segments yes)
				(prefer_zone_connections yes)
			)
		)
	)
	(footprint "antmicro-footprints:C_0402_1005Metric"
		(layer "F.Cu")
		(at 129.5 107.3 -90)
		(descr "Capacitor SMD 0402")
		(tags "capacitor SMD 0402")
		(property "Reference" "C18"
			(at -0.98 0.5 90)
			(layer "F.SilkS")
			(effects
				(font
					(size 0.7 0.7)
					(thickness 0.15)
				)
				(justify right bottom)
			)
		)
		(property "Value" "C_100n_0402"
			(at -1.022927 2.155213 90)
			(layer "F.Fab")
			(effects
				(font
					(size 0.7 0.7)
					(thickness 0.15)
				)
				(justify right bottom)
			)
		)
		(property "Datasheet" "https://www.murata.com/products/productdetail?partno=GRM155R61H104KE14%23"
			(at 0 0 270)
			(layer "F.Fab")
			(hide yes)
			(effects
				(font
					(size 1.27 1.27)
					(thickness 0.15)
				)
			)
		)
		(property "Author" "Antmicro"
			(at 22.2 236.8 0)
			(layer "F.Fab")
			(hide yes)
			(effects
				(font
					(size 1 1)
					(thickness 0.15)
				)
			)
		)
		(property "Dielectric" "X5R"
			(at 22.2 236.8 0)
			(layer "F.Fab")
			(hide yes)
			(effects
				(font
					(size 1 1)
					(thickness 0.15)
				)
			)
		)
		(property "License" "Apache-2.0"
			(at 22.2 236.8 0)
			(layer "F.Fab")
			(hide yes)
			(effects
				(font
					(size 1 1)
					(thickness 0.15)
				)
			)
		)
		(property "MPN" "GRM155R61H104KE14D"
			(at 22.2 236.8 0)
			(layer "F.Fab")
			(hide yes)
			(effects
				(font
					(size 1 1)
					(thickness 0.15)
				)
			)
		)
		(property "Manufacturer" "Murata"
			(at 22.2 236.8 0)
			(layer "F.Fab")
			(hide yes)
			(effects
				(font
					(size 1 1)
					(thickness 0.15)
				)
			)
		)
		(property "Public" "False"
			(at 22.2 236.8 0)
			(layer "F.Fab")
			(hide yes)
			(effects
				(font
					(size 1 1)
					(thickness 0.15)
				)
			)
		)
		(property "Val" "100n"
			(at 22.2 236.8 0)
			(layer "F.Fab")
			(hide yes)
			(effects
				(font
					(size 1 1)
					(thickness 0.15)
				)
			)
		)
		(property "Voltage" "50V"
			(at 22.2 236.8 0)
			(layer "F.Fab")
			(hide yes)
			(effects
				(font
					(size 1 1)
					(thickness 0.15)
				)
			)
		)
		(sheetname "2xUSB3.0+RJ45")
		(sheetfile "usb3+rj45.kicad_sch")
		(attr smd)
		(fp_rect
			(start -0.925 -0.47)
			(end 0.925 0.47)
			(stroke
				(width 0.05)
				(type default)
			)
			(fill no)
			(layer "F.CrtYd")
		)
		(fp_line
			(start -0.494 0.248)
			(end -0.494 -0.25)
			(stroke
				(width 0.15)
				(type solid)
			)
			(layer "F.Fab")
		)
		(fp_line
			(start 0.504 0.248)
			(end -0.494 0.248)
			(stroke
				(width 0.15)
				(type solid)
			)
			(layer "F.Fab")
		)
		(fp_line
			(start -0.494 -0.25)
			(end 0.504 -0.25)
			(stroke
				(width 0.15)
				(type solid)
			)
			(layer "F.Fab")
		)
		(fp_line
			(start 0.504 -0.25)
			(end 0.504 0.248)
			(stroke
				(width 0.15)
				(type solid)
			)
			(layer "F.Fab")
		)
		(pad "1" smd roundrect
			(at -0.48 0 270)
			(size 0.59 0.64)
			(layers "F.Cu" "F.Mask" "F.Paste")
			(roundrect_rratio 0.25)
			(net 51 "Net-(C13-Pad1)")
			(pintype "passive")
			(teardrops
				(best_length_ratio 0.2)
				(max_length 1)
				(best_width_ratio 0.9)
				(max_width 2)
				(curved_edges yes)
				(filter_ratio 0.9)
				(enabled yes)
				(allow_two_segments yes)
				(prefer_zone_connections yes)
			)
		)
		(pad "2" smd roundrect
			(at 0.48 0 270)
			(size 0.59 0.64)
			(layers "F.Cu" "F.Mask" "F.Paste")
			(roundrect_rratio 0.25)
			(net 1 "GND")
			(pintype "passive")
			(teardrops
				(best_length_ratio 0.2)
				(max_length 1)
				(best_width_ratio 0.9)
				(max_width 2)
				(curved_edges yes)
				(filter_ratio 0.9)
				(enabled yes)
				(allow_two_segments yes)
				(prefer_zone_connections yes)
			)
		)
	)
	(footprint "antmicro-footprints:SOT-23-8"
		(layer "F.Cu")
		(at 303.15 106.11 -90)
		(descr "http://www.ti.com/lit/ds/symlink/ina219.pdf")
		(property "Reference" "U49"
			(at -1.1 -2.7 90)
			(layer "F.SilkS")
			(effects
				(font
					(size 0.7 0.7)
					(thickness 0.15)
				)
				(justify right bottom)
			)
		)
		(property "Value" "INA219AIDCNR"
			(at 0 2.8 90)
			(layer "F.Fab")
			(effects
				(font
					(size 0.7 0.7)
					(thickness 0.15)
				)
				(justify right bottom)
			)
		)
		(property "Datasheet" "https://www.ti.com/lit/ds/symlink/ina219.pdf?ts=1713856455637&ref_url=https%253A%252F%252Fwww.mouser.es%252F"
			(at 0 0 270)
			(layer "F.Fab")
			(hide yes)
			(effects
				(font
					(size 1.27 1.27)
					(thickness 0.15)
				)
			)
		)
		(property "Author" "Antmicro"
			(at 197.04 409.26 0)
			(layer "F.Fab")
			(hide yes)
			(effects
				(font
					(size 1 1)
					(thickness 0.15)
				)
			)
		)
		(property "License" "Apache-2.0"
			(at 197.04 409.26 0)
			(layer "F.Fab")
			(hide yes)
			(effects
				(font
					(size 1 1)
					(thickness 0.15)
				)
			)
		)
		(property "MPN" "INA219AIDCNR"
			(at 197.04 409.26 0)
			(layer "F.Fab")
			(hide yes)
			(effects
				(font
					(size 1 1)
					(thickness 0.15)
				)
			)
		)
		(property "Manufacturer" "Texas Instruments"
			(at 197.04 409.26 0)
			(layer "F.Fab")
			(hide yes)
			(effects
				(font
					(size 1 1)
					(thickness 0.15)
				)
			)
		)
		(sheetname "Power")
		(sheetfile "power.kicad_sch")
		(attr smd)
		(fp_line
			(start -0.987 1.6)
			(end -0.987 1.324)
			(stroke
				(width 0.15)
				(type solid)
			)
			(layer "F.SilkS")
		)
		(fp_line
			(start -0.613 1.6)
			(end -0.987 1.6)
			(stroke
				(width 0.15)
				(type solid)
			)
			(layer "F.SilkS")
		)
		(fp_line
			(start 1 1.6)
			(end 0.6 1.6)
			(stroke
				(width 0.15)
				(type solid)
			)
			(layer "F.SilkS")
		)
		(fp_line
			(start 1 1.3)
			(end 1 1.6)
			(stroke
				(width 0.15)
				(type solid)
			)
			(layer "F.SilkS")
		)
		(fp_line
			(start -1 -1.3)
			(end -1 -1.6)
			(stroke
				(width 0.15)
				(type solid)
			)
			(layer "F.SilkS")
		)
		(fp_line
			(start 1 -1.3)
			(end 1 -1.6)
			(stroke
				(width 0.15)
				(type solid)
			)
			(layer "F.SilkS")
		)
		(fp_line
			(start -1 -1.6)
			(end -0.6 -1.6)
			(stroke
				(width 0.15)
				(type solid)
			)
			(layer "F.SilkS")
		)
		(fp_line
			(start 1 -1.6)
			(end 0.625 -1.6)
			(stroke
				(width 0.15)
				(type solid)
			)
			(layer "F.SilkS")
		)
		(fp_circle
			(center -1.3 -1.4)
			(end -1.25 -1.4)
			(stroke
				(width 0.15)
				(type solid)
			)
			(fill yes)
			(layer "F.SilkS")
		)
		(fp_rect
			(start -1.9 -1.75)
			(end 1.898 1.75)
			(stroke
				(width 0.05)
				(type solid)
			)
			(fill no)
			(layer "F.CrtYd")
		)
		(fp_line
			(start -1.4 -1.25)
			(end -1.2 -1.45)
			(stroke
				(width 0.15)
				(type solid)
			)
			(layer "F.Fab")
		)
		(fp_rect
			(start -1.401 -1.45)
			(end 1.398 1.449)
			(stroke
				(width 0.15)
				(type solid)
			)
			(fill no)
			(layer "F.Fab")
		)
		(pad "1" smd roundrect
			(at -1.3 -0.975 180)
			(size 0.45 1.1)
			(layers "F.Cu" "F.Mask" "F.Paste")
			(roundrect_rratio 0.25)
			(net 71 "Net-(U49-IN+)")
			(pinfunction "IN+")
			(pintype "passive")
			(teardrops
				(best_length_ratio 0.2)
				(max_length 1)
				(best_width_ratio 0.9)
				(max_width 2)
				(curved_edges yes)
				(filter_ratio 0.9)
				(enabled yes)
				(allow_two_segments yes)
				(prefer_zone_connections yes)
			)
		)
		(pad "2" smd roundrect
			(at -1.3 -0.325 180)
			(size 0.45 1.1)
			(layers "F.Cu" "F.Mask" "F.Paste")
			(roundrect_rratio 0.25)
			(net 2 "+3V3")
			(pinfunction "IN-")
			(pintype "passive")
			(teardrops
				(best_length_ratio 0.2)
				(max_length 1)
				(best_width_ratio 0.9)
				(max_width 2)
				(curved_edges yes)
				(filter_ratio 0.9)
				(enabled yes)
				(allow_two_segments yes)
				(prefer_zone_connections yes)
			)
		)
		(pad "3" smd roundrect
			(at -1.3 0.325 180)
			(size 0.45 1.1)
			(layers "F.Cu" "F.Mask" "F.Paste")
			(roundrect_rratio 0.25)
			(net 1 "GND")
			(pinfunction "GND")
			(pintype "power_in")
			(teardrops
				(best_length_ratio 0.2)
				(max_length 1)
				(best_width_ratio 0.9)
				(max_width 2)
				(curved_edges yes)
				(filter_ratio 0.9)
				(enabled yes)
				(allow_two_segments yes)
				(prefer_zone_connections yes)
			)
		)
		(pad "4" smd roundrect
			(at -1.3 0.975 180)
			(size 0.45 1.1)
			(layers "F.Cu" "F.Mask" "F.Paste")
			(roundrect_rratio 0.25)
			(net 73 "+3V3_AON")
			(pinfunction "V_{S}")
			(pintype "power_in")
			(teardrops
				(best_length_ratio 0.2)
				(max_length 1)
				(best_width_ratio 0.9)
				(max_width 2)
				(curved_edges yes)
				(filter_ratio 0.9)
				(enabled yes)
				(allow_two_segments yes)
				(prefer_zone_connections yes)
			)
		)
		(pad "5" smd roundrect
			(at 1.3 0.975 180)
			(size 0.45 1.1)
			(layers "F.Cu" "F.Mask" "F.Paste")
			(roundrect_rratio 0.25)
			(net 371 "/Com Express 7 MGMT/I2C.SCL")
			(pinfunction "SCL")
			(pintype "open_collector")
			(teardrops
				(best_length_ratio 0.2)
				(max_length 1)
				(best_width_ratio 0.9)
				(max_width 2)
				(curved_edges yes)
				(filter_ratio 0.9)
				(enabled yes)
				(allow_two_segments yes)
				(prefer_zone_connections yes)
			)
		)
		(pad "6" smd roundrect
			(at 1.3 0.325 180)
			(size 0.45 1.1)
			(layers "F.Cu" "F.Mask" "F.Paste")
			(roundrect_rratio 0.25)
			(net 372 "/Com Express 7 MGMT/I2C.SDA")
			(pinfunction "SDA")
			(pintype "open_collector")
			(teardrops
				(best_length_ratio 0.2)
				(max_length 1)
				(best_width_ratio 0.9)
				(max_width 2)
				(curved_edges yes)
				(filter_ratio 0.9)
				(enabled yes)
				(allow_two_segments yes)
				(prefer_zone_connections yes)
			)
		)
		(pad "7" smd roundrect
			(at 1.3 -0.325 180)
			(size 0.45 1.1)
			(layers "F.Cu" "F.Mask" "F.Paste")
			(roundrect_rratio 0.25)
			(net 73 "+3V3_AON")
			(pinfunction "A0")
			(pintype "passive")
			(teardrops
				(best_length_ratio 0.2)
				(max_length 1)
				(best_width_ratio 0.9)
				(max_width 2)
				(curved_edges yes)
				(filter_ratio 0.9)
				(enabled yes)
				(allow_two_segments yes)
				(prefer_zone_connections yes)
			)
		)
		(pad "8" smd roundrect
			(at 1.3 -0.975 180)
			(size 0.45 1.1)
			(layers "F.Cu" "F.Mask" "F.Paste")
			(roundrect_rratio 0.25)
			(net 1 "GND")
			(pinfunction "A1")
			(pintype "passive")
			(teardrops
				(best_length_ratio 0.2)
				(max_length 1)
				(best_width_ratio 0.9)
				(max_width 2)
				(curved_edges yes)
				(filter_ratio 0.9)
				(enabled yes)
				(allow_two_segments yes)
				(prefer_zone_connections yes)
			)
		)
	)
	(footprint "antmicro-footprints:R_0402_1005Metric"
		(layer "F.Cu")
		(at 252.614999 81.174999)
		(descr "Resistor SMD 0402")
		(tags "resistor SMD 0402")
		(property "Reference" "R143"
			(at -0.825 0.435001 0)
			(layer "F.SilkS")
			(effects
				(font
					(size 0.7 0.7)
					(thickness 0.15)
				)
				(justify right bottom)
			)
		)
		(property "Value" "R_0R_0402"
			(at -1.011843 1.772047 0)
			(layer "F.Fab")
			(effects
				(font
					(size 0.7 0.7)
					(thickness 0.15)
				)
				(justify left bottom)
			)
		)
		(property "Datasheet" "https://industrial.panasonic.com/cdbs/www-data/pdf/RDA0000/AOA0000C301.pdf"
			(at 0 0 0)
			(layer "F.Fab")
			(hide yes)
			(effects
				(font
					(size 1.27 1.27)
					(thickness 0.15)
				)
			)
		)
		(property "Author" "Antmicro"
			(at 0 0 0)
			(layer "F.Fab")
			(hide yes)
			(effects
				(font
					(size 1 1)
					(thickness 0.15)
				)
			)
		)
		(property "Current" "1A"
			(at 0 0 0)
			(layer "F.Fab")
			(hide yes)
			(effects
				(font
					(size 1 1)
					(thickness 0.15)
				)
			)
		)
		(property "License" "Apache-2.0"
			(at 0 0 0)
			(layer "F.Fab")
			(hide yes)
			(effects
				(font
					(size 1 1)
					(thickness 0.15)
				)
			)
		)
		(property "MPN" "ERJ2GE0R00X"
			(at 0 0 0)
			(layer "F.Fab")
			(hide yes)
			(effects
				(font
					(size 1 1)
					(thickness 0.15)
				)
			)
		)
		(property "Manufacturer" "Panasonic"
			(at 0 0 0)
			(layer "F.Fab")
			(hide yes)
			(effects
				(font
					(size 1 1)
					(thickness 0.15)
				)
			)
		)
		(property "Public" "False"
			(at 0 0 0)
			(layer "F.Fab")
			(hide yes)
			(effects
				(font
					(size 1 1)
					(thickness 0.15)
				)
			)
		)
		(property "Tolerance" ""
			(at 0 0 0)
			(layer "F.Fab")
			(hide yes)
			(effects
				(font
					(size 1 1)
					(thickness 0.15)
				)
			)
		)
		(property "Val" "0R"
			(at 0 0 0)
			(layer "F.Fab")
			(hide yes)
			(effects
				(font
					(size 1 1)
					(thickness 0.15)
				)
			)
		)
		(sheetname "Misc")
		(sheetfile "misc.kicad_sch")
		(attr smd)
		(fp_rect
			(start -0.925 -0.47)
			(end 0.925 0.47)
			(stroke
				(width 0.05)
				(type default)
			)
			(fill no)
			(layer "F.CrtYd")
		)
		(fp_rect
			(start -0.5 -0.25)
			(end 0.5 0.25)
			(stroke
				(width 0.15)
				(type solid)
			)
			(fill no)
			(layer "F.Fab")
		)
		(pad "1" smd roundrect
			(at -0.48 0)
			(size 0.59 0.64)
			(layers "F.Cu" "F.Mask" "F.Paste")
			(roundrect_rratio 0.25)
			(net 1 "GND")
			(pintype "passive")
			(teardrops
				(best_length_ratio 0.2)
				(max_length 1)
				(best_width_ratio 0.9)
				(max_width 2)
				(curved_edges yes)
				(filter_ratio 0.9)
				(enabled yes)
				(allow_two_segments yes)
				(prefer_zone_connections yes)
			)
		)
		(pad "2" smd roundrect
			(at 0.48 0)
			(size 0.59 0.64)
			(layers "F.Cu" "F.Mask" "F.Paste")
			(roundrect_rratio 0.25)
			(net 588 "/Misc/~{ADDREN}")
			(pintype "passive")
			(teardrops
				(best_length_ratio 0.2)
				(max_length 1)
				(best_width_ratio 0.9)
				(max_width 2)
				(curved_edges yes)
				(filter_ratio 0.9)
				(enabled yes)
				(allow_two_segments yes)
				(prefer_zone_connections yes)
			)
		)
	)
	(footprint "antmicro-footprints:TP_SMD_0.75mm"
		(layer "F.Cu")
		(at 195.70861 72.802163 -90)
		(property "Reference" "TP104"
			(at 0 -0.6 90)
			(layer "F.SilkS")
			(hide yes)
			(effects
				(font
					(size 0.7 0.7)
					(thickness 0.15)
				)
				(justify right bottom)
			)
		)
		(property "Value" "TP_0.75mm_SMD"
			(at 0 1.2 90)
			(layer "F.Fab")
			(effects
				(font
					(size 0.7 0.7)
					(thickness 0.15)
				)
				(justify right bottom)
			)
		)
		(property "Author" "Antmicro"
			(at 122.906447 268.510773 0)
			(layer "F.Fab")
			(hide yes)
			(effects
				(font
					(size 1 1)
					(thickness 0.15)
				)
			)
		)
		(property "License" "Apache-2.0"
			(at 122.906447 268.510773 0)
			(layer "F.Fab")
			(hide yes)
			(effects
				(font
					(size 1 1)
					(thickness 0.15)
				)
			)
		)
		(property "MPN" ""
			(at 122.906447 268.510773 0)
			(layer "F.Fab")
			(hide yes)
			(effects
				(font
					(size 1 1)
					(thickness 0.15)
				)
			)
		)
		(property "Manufacturer" ""
			(at 122.906447 268.510773 0)
			(layer "F.Fab")
			(hide yes)
			(effects
				(font
					(size 1 1)
					(thickness 0.15)
				)
			)
		)
		(property "Public" "False"
			(at 122.906447 268.510773 0)
			(layer "F.Fab")
			(hide yes)
			(effects
				(font
					(size 1 1)
					(thickness 0.15)
				)
			)
		)
		(sheetname "Power")
		(sheetfile "power.kicad_sch")
		(attr exclude_from_pos_files exclude_from_bom)
		(fp_circle
			(center 0 0)
			(end 0.475 0)
			(stroke
				(width 0.05)
				(type default)
			)
			(fill no)
			(layer "F.CrtYd")
		)
		(pad "1" smd circle
			(at 0 0 270)
			(size 0.75 0.75)
			(layers "F.Cu" "F.Mask")
			(net 52 "+5V")
			(pinfunction "1")
			(pintype "passive")
			(teardrops
				(best_length_ratio 0.4)
				(max_length 1)
				(best_width_ratio 0.9)
				(max_width 2)
				(curved_edges yes)
				(filter_ratio 0.9)
				(enabled yes)
				(allow_two_segments yes)
				(prefer_zone_connections yes)
			)
		)
	)
	(footprint "antmicro-footprints:C_0402_1005Metric"
		(layer "F.Cu")
		(at 244.05 126.71)
		(descr "Capacitor SMD 0402")
		(tags "capacitor SMD 0402")
		(property "Reference" "C102"
			(at -1.4 -0.45 0)
			(layer "F.SilkS")
			(effects
				(font
					(size 0.7 0.7)
					(thickness 0.15)
				)
				(justify left bottom)
			)
		)
		(property "Value" "C_100n_0402"
			(at -1.022927 2.155213 0)
			(layer "F.Fab")
			(effects
				(font
					(size 0.7 0.7)
					(thickness 0.15)
				)
				(justify left bottom)
			)
		)
		(property "Datasheet" "https://www.murata.com/products/productdetail?partno=GRM155R61H104KE14%23"
			(at 0 0 0)
			(layer "F.Fab")
			(hide yes)
			(effects
				(font
					(size 1.27 1.27)
					(thickness 0.15)
				)
			)
		)
		(property "Author" "Antmicro"
			(at 0 0 0)
			(layer "F.Fab")
			(hide yes)
			(effects
				(font
					(size 1 1)
					(thickness 0.15)
				)
			)
		)
		(property "Dielectric" "X5R"
			(at 0 0 0)
			(layer "F.Fab")
			(hide yes)
			(effects
				(font
					(size 1 1)
					(thickness 0.15)
				)
			)
		)
		(property "License" "Apache-2.0"
			(at 0 0 0)
			(layer "F.Fab")
			(hide yes)
			(effects
				(font
					(size 1 1)
					(thickness 0.15)
				)
			)
		)
		(property "MPN" "GRM155R61H104KE14D"
			(at 0 0 0)
			(layer "F.Fab")
			(hide yes)
			(effects
				(font
					(size 1 1)
					(thickness 0.15)
				)
			)
		)
		(property "Manufacturer" "Murata"
			(at 0 0 0)
			(layer "F.Fab")
			(hide yes)
			(effects
				(font
					(size 1 1)
					(thickness 0.15)
				)
			)
		)
		(property "Public" "False"
			(at 0 0 0)
			(layer "F.Fab")
			(hide yes)
			(effects
				(font
					(size 1 1)
					(thickness 0.15)
				)
			)
		)
		(property "Val" "100n"
			(at 0 0 0)
			(layer "F.Fab")
			(hide yes)
			(effects
				(font
					(size 1 1)
					(thickness 0.15)
				)
			)
		)
		(property "Voltage" "50V"
			(at 0 0 0)
			(layer "F.Fab")
			(hide yes)
			(effects
				(font
					(size 1 1)
					(thickness 0.15)
				)
			)
		)
		(sheetname "Com Express 7 MGMT")
		(sheetfile "com_express_7_mgmt.kicad_sch")
		(attr smd)
		(fp_rect
			(start -0.925 -0.47)
			(end 0.925 0.47)
			(stroke
				(width 0.05)
				(type default)
			)
			(fill no)
			(layer "F.CrtYd")
		)
		(fp_line
			(start -0.494 -0.25)
			(end 0.504 -0.25)
			(stroke
				(width 0.15)
				(type solid)
			)
			(layer "F.Fab")
		)
		(fp_line
			(start -0.494 0.248)
			(end -0.494 -0.25)
			(stroke
				(width 0.15)
				(type solid)
			)
			(layer "F.Fab")
		)
		(fp_line
			(start 0.504 -0.25)
			(end 0.504 0.248)
			(stroke
				(width 0.15)
				(type solid)
			)
			(layer "F.Fab")
		)
		(fp_line
			(start 0.504 0.248)
			(end -0.494 0.248)
			(stroke
				(width 0.15)
				(type solid)
			)
			(layer "F.Fab")
		)
		(pad "1" smd roundrect
			(at -0.48 0)
			(size 0.59 0.64)
			(layers "F.Cu" "F.Mask" "F.Paste")
			(roundrect_rratio 0.25)
			(net 1 "GND")
			(pintype "passive")
			(teardrops
				(best_length_ratio 0.2)
				(max_length 1)
				(best_width_ratio 0.9)
				(max_width 2)
				(curved_edges yes)
				(filter_ratio 0.9)
				(enabled yes)
				(allow_two_segments yes)
				(prefer_zone_connections yes)
			)
		)
		(pad "2" smd roundrect
			(at 0.48 0)
			(size 0.59 0.64)
			(layers "F.Cu" "F.Mask" "F.Paste")
			(roundrect_rratio 0.25)
			(net 73 "+3V3_AON")
			(pintype "passive")
			(teardrops
				(best_length_ratio 0.2)
				(max_length 1)
				(best_width_ratio 0.9)
				(max_width 2)
				(curved_edges yes)
				(filter_ratio 0.9)
				(enabled yes)
				(allow_two_segments yes)
				(prefer_zone_connections yes)
			)
		)
	)
	(footprint "antmicro-footprints:R_0402_1005Metric"
		(layer "F.Cu")
		(at 126.425 85.060001 180)
		(descr "Resistor SMD 0402")
		(tags "resistor SMD 0402")
		(property "Reference" "R240"
			(at -1.575 -6.4 0)
			(layer "F.SilkS")
			(effects
				(font
					(size 0.7 0.7)
					(thickness 0.15)
				)
				(justify right bottom)
			)
		)
		(property "Value" "R_0R_0402"
			(at -1.011843 1.772047 0)
			(layer "F.Fab")
			(effects
				(font
					(size 0.7 0.7)
					(thickness 0.15)
				)
				(justify right bottom)
			)
		)
		(property "Datasheet" "https://industrial.panasonic.com/cdbs/www-data/pdf/RDA0000/AOA0000C301.pdf"
			(at 0 0 180)
			(layer "F.Fab")
			(hide yes)
			(effects
				(font
					(size 1.27 1.27)
					(thickness 0.15)
				)
			)
		)
		(property "Author" "Antmicro"
			(at 252.85 170.120002 0)
			(layer "F.Fab")
			(hide yes)
			(effects
				(font
					(size 1 1)
					(thickness 0.15)
				)
			)
		)
		(property "Current" "1A"
			(at 252.85 170.120002 0)
			(layer "F.Fab")
			(hide yes)
			(effects
				(font
					(size 1 1)
					(thickness 0.15)
				)
			)
		)
		(property "License" "Apache-2.0"
			(at 252.85 170.120002 0)
			(layer "F.Fab")
			(hide yes)
			(effects
				(font
					(size 1 1)
					(thickness 0.15)
				)
			)
		)
		(property "MPN" "ERJ2GE0R00X"
			(at 252.85 170.120002 0)
			(layer "F.Fab")
			(hide yes)
			(effects
				(font
					(size 1 1)
					(thickness 0.15)
				)
			)
		)
		(property "Manufacturer" "Panasonic"
			(at 252.85 170.120002 0)
			(layer "F.Fab")
			(hide yes)
			(effects
				(font
					(size 1 1)
					(thickness 0.15)
				)
			)
		)
		(property "Public" "False"
			(at 252.85 170.120002 0)
			(layer "F.Fab")
			(hide yes)
			(effects
				(font
					(size 1 1)
					(thickness 0.15)
				)
			)
		)
		(property "Tolerance" ""
			(at 252.85 170.120002 0)
			(layer "F.Fab")
			(hide yes)
			(effects
				(font
					(size 1 1)
					(thickness 0.15)
				)
			)
		)
		(property "Val" "0R"
			(at 252.85 170.120002 0)
			(layer "F.Fab")
			(hide yes)
			(effects
				(font
					(size 1 1)
					(thickness 0.15)
				)
			)
		)
		(sheetname "GPIO expander")
		(sheetfile "gpio_exp.kicad_sch")
		(attr smd)
		(fp_rect
			(start -0.925 -0.47)
			(end 0.925 0.47)
			(stroke
				(width 0.05)
				(type default)
			)
			(fill no)
			(layer "F.CrtYd")
		)
		(fp_rect
			(start -0.5 -0.25)
			(end 0.5 0.25)
			(stroke
				(width 0.15)
				(type solid)
			)
			(fill no)
			(layer "F.Fab")
		)
		(pad "1" smd roundrect
			(at -0.48 0 180)
			(size 0.59 0.64)
			(layers "F.Cu" "F.Mask" "F.Paste")
			(roundrect_rratio 0.25)
			(net 641 "Net-(U41-IO0_2)")
			(pintype "passive")
			(teardrops
				(best_length_ratio 0.2)
				(max_length 1)
				(best_width_ratio 0.9)
				(max_width 2)
				(curved_edges yes)
				(filter_ratio 0.9)
				(enabled yes)
				(allow_two_segments yes)
				(prefer_zone_connections yes)
			)
		)
		(pad "2" smd roundrect
			(at 0.48 0 180)
			(size 0.59 0.64)
			(layers "F.Cu" "F.Mask" "F.Paste")
			(roundrect_rratio 0.25)
			(net 944 "/GPIO expander/GPIOEX2")
			(pintype "passive")
			(teardrops
				(best_length_ratio 0.2)
				(max_length 1)
				(best_width_ratio 0.9)
				(max_width 2)
				(curved_edges yes)
				(filter_ratio 0.9)
				(enabled yes)
				(allow_two_segments yes)
				(prefer_zone_connections yes)
			)
		)
	)
	(footprint "antmicro-footprints:R_0402_1005Metric"
		(layer "F.Cu")
		(at 115.4 144.36 90)
		(descr "Resistor SMD 0402")
		(tags "resistor SMD 0402")
		(property "Reference" "R206"
			(at 0.8 0.4 90)
			(layer "F.SilkS")
			(effects
				(font
					(size 0.7 0.7)
					(thickness 0.15)
				)
				(justify left bottom)
			)
		)
		(property "Value" "R_1k_0402"
			(at -1.011843 1.772047 90)
			(layer "F.Fab")
			(effects
				(font
					(size 0.7 0.7)
					(thickness 0.15)
				)
				(justify left bottom)
			)
		)
		(property "Datasheet" "https://www.bourns.com/docs/product-datasheets/cr.pdf"
			(at 0 0 90)
			(layer "F.Fab")
			(hide yes)
			(effects
				(font
					(size 1.27 1.27)
					(thickness 0.15)
				)
			)
		)
		(property "Author" "Antmicro"
			(at 259.76 28.96 0)
			(layer "F.Fab")
			(hide yes)
			(effects
				(font
					(size 1 1)
					(thickness 0.15)
				)
			)
		)
		(property "License" "Apache-2.0"
			(at 259.76 28.96 0)
			(layer "F.Fab")
			(hide yes)
			(effects
				(font
					(size 1 1)
					(thickness 0.15)
				)
			)
		)
		(property "MPN" "CR0402-FX-1001GLF"
			(at 259.76 28.96 0)
			(layer "F.Fab")
			(hide yes)
			(effects
				(font
					(size 1 1)
					(thickness 0.15)
				)
			)
		)
		(property "Manufacturer" "Bourns"
			(at 259.76 28.96 0)
			(layer "F.Fab")
			(hide yes)
			(effects
				(font
					(size 1 1)
					(thickness 0.15)
				)
			)
		)
		(property "Public" "False"
			(at 259.76 28.96 0)
			(layer "F.Fab")
			(hide yes)
			(effects
				(font
					(size 1 1)
					(thickness 0.15)
				)
			)
		)
		(property "Tolerance" "1%"
			(at 259.76 28.96 0)
			(layer "F.Fab")
			(hide yes)
			(effects
				(font
					(size 1 1)
					(thickness 0.15)
				)
			)
		)
		(property "Val" "1k"
			(at 259.76 28.96 0)
			(layer "F.Fab")
			(hide yes)
			(effects
				(font
					(size 1 1)
					(thickness 0.15)
				)
			)
		)
		(sheetname "PCIe redriver")
		(sheetfile "pcie_redriver.kicad_sch")
		(attr smd)
		(fp_rect
			(start -0.925 -0.47)
			(end 0.925 0.47)
			(stroke
				(width 0.05)
				(type default)
			)
			(fill no)
			(layer "F.CrtYd")
		)
		(fp_rect
			(start -0.5 -0.25)
			(end 0.5 0.25)
			(stroke
				(width 0.15)
				(type solid)
			)
			(fill no)
			(layer "F.Fab")
		)
		(pad "1" smd roundrect
			(at -0.48 0 90)
			(size 0.59 0.64)
			(layers "F.Cu" "F.Mask" "F.Paste")
			(roundrect_rratio 0.25)
			(net 2 "+3V3")
			(pintype "passive")
			(teardrops
				(best_length_ratio 0.2)
				(max_length 1)
				(best_width_ratio 0.9)
				(max_width 2)
				(curved_edges yes)
				(filter_ratio 0.9)
				(enabled yes)
				(allow_two_segments yes)
				(prefer_zone_connections yes)
			)
		)
		(pad "2" smd roundrect
			(at 0.48 0 90)
			(size 0.59 0.64)
			(layers "F.Cu" "F.Mask" "F.Paste")
			(roundrect_rratio 0.25)
			(net 625 "/PCIe redriver/TX_EQ2")
			(pintype "passive")
			(teardrops
				(best_length_ratio 0.2)
				(max_length 1)
				(best_width_ratio 0.9)
				(max_width 2)
				(curved_edges yes)
				(filter_ratio 0.9)
				(enabled yes)
				(allow_two_segments yes)
				(prefer_zone_connections yes)
			)
		)
	)
	(footprint "antmicro-footprints:R_0402_1005Metric"
		(layer "F.Cu")
		(at 124.21 144.05)
		(descr "Resistor SMD 0402")
		(tags "resistor SMD 0402")
		(property "Reference" "R281"
			(at -3.61 0.46 0)
			(layer "F.SilkS")
			(effects
				(font
					(size 0.7 0.7)
					(thickness 0.15)
				)
				(justify left bottom)
			)
		)
		(property "Value" "R_0R_0402"
			(at -1.011843 1.772047 0)
			(layer "F.Fab")
			(effects
				(font
					(size 0.7 0.7)
					(thickness 0.15)
				)
				(justify left bottom)
			)
		)
		(property "Datasheet" "https://industrial.panasonic.com/cdbs/www-data/pdf/RDA0000/AOA0000C301.pdf"
			(at 0 0 0)
			(layer "F.Fab")
			(hide yes)
			(effects
				(font
					(size 1.27 1.27)
					(thickness 0.15)
				)
			)
		)
		(property "Author" "Antmicro"
			(at 0 0 0)
			(layer "F.Fab")
			(hide yes)
			(effects
				(font
					(size 1 1)
					(thickness 0.15)
				)
			)
		)
		(property "Current" "1A"
			(at 0 0 0)
			(layer "F.Fab")
			(hide yes)
			(effects
				(font
					(size 1 1)
					(thickness 0.15)
				)
			)
		)
		(property "License" "Apache-2.0"
			(at 0 0 0)
			(layer "F.Fab")
			(hide yes)
			(effects
				(font
					(size 1 1)
					(thickness 0.15)
				)
			)
		)
		(property "MPN" "ERJ2GE0R00X"
			(at 0 0 0)
			(layer "F.Fab")
			(hide yes)
			(effects
				(font
					(size 1 1)
					(thickness 0.15)
				)
			)
		)
		(property "Manufacturer" "Panasonic"
			(at 0 0 0)
			(layer "F.Fab")
			(hide yes)
			(effects
				(font
					(size 1 1)
					(thickness 0.15)
				)
			)
		)
		(property "Public" "False"
			(at 0 0 0)
			(layer "F.Fab")
			(hide yes)
			(effects
				(font
					(size 1 1)
					(thickness 0.15)
				)
			)
		)
		(property "Tolerance" ""
			(at 0 0 0)
			(layer "F.Fab")
			(hide yes)
			(effects
				(font
					(size 1 1)
					(thickness 0.15)
				)
			)
		)
		(property "Val" "0R"
			(at 0 0 0)
			(layer "F.Fab")
			(hide yes)
			(effects
				(font
					(size 1 1)
					(thickness 0.15)
				)
			)
		)
		(sheetname "KR to SFI #2")
		(sheetfile "kr_sfi.kicad_sch")
		(attr smd)
		(fp_rect
			(start -0.925 -0.47)
			(end 0.925 0.47)
			(stroke
				(width 0.05)
				(type default)
			)
			(fill no)
			(layer "F.CrtYd")
		)
		(fp_rect
			(start -0.5 -0.25)
			(end 0.5 0.25)
			(stroke
				(width 0.15)
				(type solid)
			)
			(fill no)
			(layer "F.Fab")
		)
		(pad "1" smd roundrect
			(at -0.48 0)
			(size 0.59 0.64)
			(layers "F.Cu" "F.Mask" "F.Paste")
			(roundrect_rratio 0.25)
			(net 669 "/2xSFP+/KR to SFI #2/MDIO_R")
			(pintype "passive")
			(teardrops
				(best_length_ratio 0.2)
				(max_length 1)
				(best_width_ratio 0.9)
				(max_width 2)
				(curved_edges yes)
				(filter_ratio 0.9)
				(enabled yes)
				(allow_two_segments yes)
				(prefer_zone_connections yes)
			)
		)
		(pad "2" smd roundrect
			(at 0.48 0)
			(size 0.59 0.64)
			(layers "F.Cu" "F.Mask" "F.Paste")
			(roundrect_rratio 0.25)
			(net 670 "/2xSFP+/KR to SFI #2/MDIO")
			(pintype "passive")
			(teardrops
				(best_length_ratio 0.2)
				(max_length 1)
				(best_width_ratio 0.9)
				(max_width 2)
				(curved_edges yes)
				(filter_ratio 0.9)
				(enabled yes)
				(allow_two_segments yes)
				(prefer_zone_connections yes)
			)
		)
	)
	(footprint "antmicro-footprints:RJ45_RJE361882415"
		(layer "F.Cu")
		(at 118.15 109.81 -90)
		(property "Reference" "J1"
			(at 6.2 22.55 0)
			(unlocked yes)
			(layer "F.SilkS")
			(effects
				(font
					(size 0.7 0.7)
					(thickness 0.15)
				)
				(justify left bottom)
			)
		)
		(property "Value" "Amphenol_RJE361882415"
			(at 3.555 23.9 270)
			(unlocked yes)
			(layer "F.Fab")
			(effects
				(font
					(size 0.7 0.7)
					(thickness 0.15)
				)
				(justify left bottom)
			)
		)
		(property "Datasheet" "https://cdn.amphenol-cs.com/media/wysiwyg/files/drawing/p-rje36-188-2xx5.pdf"
			(at 0 0 270)
			(layer "F.Fab")
			(hide yes)
			(effects
				(font
					(size 1.27 1.27)
					(thickness 0.15)
				)
			)
		)
		(property "Description" "Modular Connectors / Ethernet Connectors MODULAR JACK"
			(at 0 0 270)
			(layer "F.Fab")
			(hide yes)
			(effects
				(font
					(size 1.27 1.27)
					(thickness 0.15)
				)
			)
		)
		(property "Author" "Antmicro"
			(at 8.34 227.96 0)
			(layer "F.Fab")
			(hide yes)
			(effects
				(font
					(size 1 1)
					(thickness 0.15)
				)
			)
		)
		(property "License" "Apache-2.0"
			(at 8.34 227.96 0)
			(layer "F.Fab")
			(hide yes)
			(effects
				(font
					(size 1 1)
					(thickness 0.15)
				)
			)
		)
		(property "MPN" "RJE361882415"
			(at 8.34 227.96 0)
			(layer "F.Fab")
			(hide yes)
			(effects
				(font
					(size 1 1)
					(thickness 0.15)
				)
			)
		)
		(property "Manufacturer" "Amphenol"
			(at 8.34 227.96 0)
			(layer "F.Fab")
			(hide yes)
			(effects
				(font
					(size 1 1)
					(thickness 0.15)
				)
			)
		)
		(sheetname "2xUSB3.0+RJ45")
		(sheetfile "usb3+rj45.kicad_sch")
		(attr through_hole)
		(fp_line
			(start 5 23.5)
			(end 5 17)
			(stroke
				(width 0.1)
				(type default)
			)
			(layer "F.SilkS")
		)
		(fp_line
			(start -14 17)
			(end -14 23.5)
			(stroke
				(width 0.1)
				(type default)
			)
			(layer "F.SilkS")
		)
		(fp_line
			(start -14 4.5)
			(end -14 13)
			(stroke
				(width 0.1)
				(type default)
			)
			(layer "F.SilkS")
		)
		(fp_line
			(start 5 4.5)
			(end 5 13.5)
			(stroke
				(width 0.1)
				(type default)
			)
			(layer "F.SilkS")
		)
		(fp_line
			(start -14 -4.5)
			(end -14 0.5)
			(stroke
				(width 0.1)
				(type default)
			)
			(layer "F.SilkS")
		)
		(fp_line
			(start -14 -4.5)
			(end 5 -4.5)
			(stroke
				(width 0.1)
				(type default)
			)
			(layer "F.SilkS")
		)
		(fp_line
			(start 5 -4.5)
			(end 5 0.5)
			(stroke
				(width 0.1)
				(type default)
			)
			(layer "F.SilkS")
		)
		(fp_circle
			(center 0 -5.55)
			(end 0.05 -5.55)
			(stroke
				(width 0.15)
				(type solid)
			)
			(fill yes)
			(layer "F.SilkS")
		)
		(fp_rect
			(start -15.5 -5)
			(end 6.5 24)
			(stroke
				(width 0.05)
				(type solid)
			)
			(fill no)
			(layer "F.CrtYd")
		)
		(pad "1" thru_hole circle
			(at 0 0)
			(size 1.35 1.35)
			(drill 1)
			(layers "*.Cu" "*.Mask")
			(remove_unused_layers no)
			(net 146 "/2xUSB3.0+RJ45/DA+")
			(pinfunction "1")
			(pintype "bidirectional")
			(teardrops
				(best_length_ratio 0.4)
				(max_length 1)
				(best_width_ratio 0.9)
				(max_width 2)
				(curved_edges yes)
				(filter_ratio 0.9)
				(enabled yes)
				(allow_two_segments yes)
				(prefer_zone_connections yes)
			)
		)
		(pad "2" thru_hole circle
			(at -1.27 2.54)
			(size 1.35 1.35)
			(drill 1)
			(layers "*.Cu" "*.Mask")
			(remove_unused_layers no)
			(net 147 "/2xUSB3.0+RJ45/DA-")
			(pinfunction "2")
			(pintype "bidirectional")
			(teardrops
				(best_length_ratio 0.4)
				(max_length 1)
				(best_width_ratio 0.9)
				(max_width 2)
				(curved_edges yes)
				(filter_ratio 0.9)
				(enabled yes)
				(allow_two_segments yes)
				(prefer_zone_connections yes)
			)
		)
		(pad "3" thru_hole circle
			(at -2.54 0)
			(size 1.35 1.35)
			(drill 1)
			(layers "*.Cu" "*.Mask")
			(remove_unused_layers no)
			(net 148 "/2xUSB3.0+RJ45/DB+")
			(pinfunction "3")
			(pintype "bidirectional")
			(teardrops
				(best_length_ratio 0.4)
				(max_length 1)
				(best_width_ratio 0.9)
				(max_width 2)
				(curved_edges yes)
				(filter_ratio 0.9)
				(enabled yes)
				(allow_two_segments yes)
				(prefer_zone_connections yes)
			)
		)
		(pad "4" thru_hole circle
			(at -3.81 2.54)
			(size 1.35 1.35)
			(drill 1)
			(layers "*.Cu" "*.Mask")
			(remove_unused_layers no)
			(net 149 "/2xUSB3.0+RJ45/DC+")
			(pinfunction "4")
			(pintype "bidirectional")
			(teardrops
				(best_length_ratio 0.4)
				(max_length 1)
				(best_width_ratio 0.9)
				(max_width 2)
				(curved_edges yes)
				(filter_ratio 0.9)
				(enabled yes)
				(allow_two_segments yes)
				(prefer_zone_connections yes)
			)
		)
		(pad "5" thru_hole circle
			(at -5.08 0)
			(size 1.35 1.35)
			(drill 1)
			(layers "*.Cu" "*.Mask")
			(remove_unused_layers no)
			(net 150 "/2xUSB3.0+RJ45/DC-")
			(pinfunction "5")
			(pintype "bidirectional")
			(teardrops
				(best_length_ratio 0.4)
				(max_length 1)
				(best_width_ratio 0.9)
				(max_width 2)
				(curved_edges yes)
				(filter_ratio 0.9)
				(enabled yes)
				(allow_two_segments yes)
				(prefer_zone_connections yes)
			)
		)
		(pad "6" thru_hole circle
			(at -6.35 2.54)
			(size 1.35 1.35)
			(drill 1)
			(layers "*.Cu" "*.Mask")
			(remove_unused_layers no)
			(net 151 "/2xUSB3.0+RJ45/DB-")
			(pinfunction "6")
			(pintype "bidirectional")
			(teardrops
				(best_length_ratio 0.4)
				(max_length 1)
				(best_width_ratio 0.9)
				(max_width 2)
				(curved_edges yes)
				(filter_ratio 0.9)
				(enabled yes)
				(allow_two_segments yes)
				(prefer_zone_connections yes)
			)
		)
		(pad "7" thru_hole circle
			(at -7.62 0)
			(size 1.35 1.35)
			(drill 1)
			(layers "*.Cu" "*.Mask")
			(remove_unused_layers no)
			(net 152 "/2xUSB3.0+RJ45/DD+")
			(pinfunction "7")
			(pintype "bidirectional")
			(teardrops
				(best_length_ratio 0.4)
				(max_length 1)
				(best_width_ratio 0.9)
				(max_width 2)
				(curved_edges yes)
				(filter_ratio 0.9)
				(enabled yes)
				(allow_two_segments yes)
				(prefer_zone_connections yes)
			)
		)
		(pad "8" thru_hole circle
			(at -8.89 2.54)
			(size 1.35 1.35)
			(drill 1)
			(layers "*.Cu" "*.Mask")
			(remove_unused_layers no)
			(net 153 "/2xUSB3.0+RJ45/DD-")
			(pinfunction "8")
			(pintype "bidirectional")
			(teardrops
				(best_length_ratio 0.4)
				(max_length 1)
				(best_width_ratio 0.9)
				(max_width 2)
				(curved_edges yes)
				(filter_ratio 0.9)
				(enabled yes)
				(allow_two_segments yes)
				(prefer_zone_connections yes)
			)
		)
		(pad "D1" thru_hole circle
			(at -11.645 -2.71)
			(size 1.35 1.35)
			(drill 1)
			(layers "*.Cu" "*.Mask")
			(remove_unused_layers no)
			(net 154 "Net-(J1A-LED_D1)")
			(pinfunction "LED_D1")
			(pintype "passive")
			(teardrops
				(best_length_ratio 0.4)
				(max_length 1)
				(best_width_ratio 0.9)
				(max_width 2)
				(curved_edges yes)
				(filter_ratio 0.9)
				(enabled yes)
				(allow_two_segments yes)
				(prefer_zone_connections yes)
			)
		)
		(pad "D2" thru_hole circle
			(at -9.11 -2.71)
			(size 1.35 1.35)
			(drill 1)
			(layers "*.Cu" "*.Mask")
			(remove_unused_layers no)
			(net 155 "Net-(J1A-LED_D2)")
			(pinfunction "LED_D2")
			(pintype "passive")
			(teardrops
				(best_length_ratio 0.4)
				(max_length 1)
				(best_width_ratio 0.9)
				(max_width 2)
				(curved_edges yes)
				(filter_ratio 0.9)
				(enabled yes)
				(allow_two_segments yes)
				(prefer_zone_connections yes)
			)
		)
		(pad "D3" thru_hole circle
			(at 0.22 -2.71)
			(size 1.35 1.35)
			(drill 1)
			(layers "*.Cu" "*.Mask")
			(remove_unused_layers no)
			(net 156 "Net-(J1A-LED_D3)")
			(pinfunction "LED_D3")
			(pintype "passive")
			(teardrops
				(best_length_ratio 0.4)
				(max_length 1)
				(best_width_ratio 0.9)
				(max_width 2)
				(curved_edges yes)
				(filter_ratio 0.9)
				(enabled yes)
				(allow_two_segments yes)
				(prefer_zone_connections yes)
			)
		)
		(pad "D4" thru_hole circle
			(at 2.755 -2.71)
			(size 1.35 1.35)
			(drill 1)
			(layers "*.Cu" "*.Mask")
			(remove_unused_layers no)
			(net 157 "Net-(J1A-LED_D4)")
			(pinfunction "LED_D4")
			(pintype "passive")
			(teardrops
				(best_length_ratio 0.4)
				(max_length 1)
				(best_width_ratio 0.9)
				(max_width 2)
				(curved_edges yes)
				(filter_ratio 0.9)
				(enabled yes)
				(allow_two_segments yes)
				(prefer_zone_connections yes)
			)
		)
		(pad "MP" thru_hole circle
			(at -13.77 2.49)
			(size 3 3)
			(drill 2.3)
			(layers "*.Cu" "*.Mask")
			(remove_unused_layers no)
			(net 579 "/2xUSB3.0+RJ45/SH")
			(pinfunction "MP")
			(pintype "bidirectional")
			(teardrops
				(best_length_ratio 0.4)
				(max_length 1)
				(best_width_ratio 0.9)
				(max_width 2)
				(curved_edges yes)
				(filter_ratio 0.9)
				(enabled yes)
				(allow_two_segments yes)
				(prefer_zone_connections yes)
			)
		)
		(pad "MP" thru_hole circle
			(at -13.77 15.09)
			(size 3 3)
			(drill 2.3)
			(layers "*.Cu" "*.Mask")
			(remove_unused_layers no)
			(net 579 "/2xUSB3.0+RJ45/SH")
			(pinfunction "MP")
			(pintype "bidirectional")
			(teardrops
				(best_length_ratio 0.4)
				(max_length 1)
				(best_width_ratio 0.9)
				(max_width 2)
				(curved_edges yes)
				(filter_ratio 0.9)
				(enabled yes)
				(allow_two_segments yes)
				(prefer_zone_connections yes)
			)
		)
		(pad "MP" thru_hole circle
			(at -11.015 7.71)
			(size 3 3)
			(drill 2.3)
			(layers "*.Cu" "*.Mask")
			(remove_unused_layers no)
			(net 579 "/2xUSB3.0+RJ45/SH")
			(pinfunction "MP")
			(pintype "bidirectional")
			(teardrops
				(best_length_ratio 0.4)
				(max_length 1)
				(best_width_ratio 0.9)
				(max_width 2)
				(curved_edges yes)
				(filter_ratio 0.9)
				(enabled yes)
				(allow_two_segments yes)
				(prefer_zone_connections yes)
			)
		)
		(pad "MP" thru_hole circle
			(at -11.015 13.39)
			(size 3 3)
			(drill 2.3)
			(layers "*.Cu" "*.Mask")
			(remove_unused_layers no)
			(net 579 "/2xUSB3.0+RJ45/SH")
			(pinfunction "MP")
			(pintype "bidirectional")
			(teardrops
				(best_length_ratio 0.4)
				(max_length 1)
				(best_width_ratio 0.9)
				(max_width 2)
				(curved_edges yes)
				(filter_ratio 0.9)
				(enabled yes)
				(allow_two_segments yes)
				(prefer_zone_connections yes)
			)
		)
		(pad "MP" thru_hole circle
			(at 2.125 7.71)
			(size 3 3)
			(drill 2.3)
			(layers "*.Cu" "*.Mask")
			(remove_unused_layers no)
			(net 579 "/2xUSB3.0+RJ45/SH")
			(pinfunction "MP")
			(pintype "bidirectional")
			(teardrops
				(best_length_ratio 0.4)
				(max_length 1)
				(best_width_ratio 0.9)
				(max_width 2)
				(curved_edges yes)
				(filter_ratio 0.9)
				(enabled yes)
				(allow_two_segments yes)
				(prefer_zone_connections yes)
			)
		)
		(pad "MP" thru_hole circle
			(at 2.125 13.39)
			(size 3 3)
			(drill 2.3)
			(layers "*.Cu" "*.Mask")
			(remove_unused_layers no)
			(net 579 "/2xUSB3.0+RJ45/SH")
			(pinfunction "MP")
			(pintype "bidirectional")
			(teardrops
				(best_length_ratio 0.4)
				(max_length 1)
				(best_width_ratio 0.9)
				(max_width 2)
				(curved_edges yes)
				(filter_ratio 0.9)
				(enabled yes)
				(allow_two_segments yes)
				(prefer_zone_connections yes)
			)
		)
		(pad "MP" thru_hole circle
			(at 4.88 2.49)
			(size 3 3)
			(drill 2.3)
			(layers "*.Cu" "*.Mask")
			(remove_unused_layers no)
			(net 579 "/2xUSB3.0+RJ45/SH")
			(pinfunction "MP")
			(pintype "bidirectional")
			(teardrops
				(best_length_ratio 0.4)
				(max_length 1)
				(best_width_ratio 0.9)
				(max_width 2)
				(curved_edges yes)
				(filter_ratio 0.9)
				(enabled yes)
				(allow_two_segments yes)
				(prefer_zone_connections yes)
			)
		)
		(pad "MP" thru_hole circle
			(at 4.88 15.09)
			(size 3 3)
			(drill 2.3)
			(layers "*.Cu" "*.Mask")
			(remove_unused_layers no)
			(net 579 "/2xUSB3.0+RJ45/SH")
			(pinfunction "MP")
			(pintype "bidirectional")
			(teardrops
				(best_length_ratio 0.4)
				(max_length 1)
				(best_width_ratio 0.9)
				(max_width 2)
				(curved_edges yes)
				(filter_ratio 0.9)
				(enabled yes)
				(allow_two_segments yes)
				(prefer_zone_connections yes)
			)
		)
		(pad "U1" thru_hole circle
			(at -7.945 11.4 270)
			(size 1.35 1.35)
			(drill 1)
			(layers "*.Cu" "*.Mask")
			(remove_unused_layers no)
			(net 42 "/2xUSB3.0+RJ45/P1_VBUS")
			(pinfunction "VBUS")
			(pintype "passive")
			(teardrops
				(best_length_ratio 0.4)
				(max_length 1)
				(best_width_ratio 0.9)
				(max_width 2)
				(curved_edges yes)
				(filter_ratio 0.9)
				(enabled yes)
				(allow_two_segments yes)
				(prefer_zone_connections yes)
			)
		)
		(pad "U2" thru_hole circle
			(at -5.445 11.4 270)
			(size 1.35 1.35)
			(drill 1)
			(layers "*.Cu" "*.Mask")
			(remove_unused_layers no)
			(net 123 "/2xUSB3.0+RJ45/P1_D-")
			(pinfunction "D-")
			(pintype "bidirectional")
			(teardrops
				(best_length_ratio 0.4)
				(max_length 1)
				(best_width_ratio 0.9)
				(max_width 2)
				(curved_edges yes)
				(filter_ratio 0.9)
				(enabled yes)
				(allow_two_segments yes)
				(prefer_zone_connections yes)
			)
		)
		(pad "U3" thru_hole circle
			(at -3.445 11.4 270)
			(size 1.35 1.35)
			(drill 1)
			(layers "*.Cu" "*.Mask")
			(remove_unused_layers no)
			(net 124 "/2xUSB3.0+RJ45/P1_D+")
			(pinfunction "D+")
			(pintype "bidirectional")
			(teardrops
				(best_length_ratio 0.4)
				(max_length 1)
				(best_width_ratio 0.9)
				(max_width 2)
				(curved_edges yes)
				(filter_ratio 0.9)
				(enabled yes)
				(allow_two_segments yes)
				(prefer_zone_connections yes)
			)
		)
		(pad "U4" thru_hole circle
			(at -0.945 11.4 270)
			(size 1.35 1.35)
			(drill 1)
			(layers "*.Cu" "*.Mask")
			(remove_unused_layers no)
			(net 1 "GND")
			(pinfunction "GND")
			(pintype "power_in")
			(teardrops
				(best_length_ratio 0.4)
				(max_length 1)
				(best_width_ratio 0.9)
				(max_width 2)
				(curved_edges yes)
				(filter_ratio 0.9)
				(enabled yes)
				(allow_two_segments yes)
				(prefer_zone_connections yes)
			)
		)
		(pad "U5" thru_hole circle
			(at -8.445 9.9 270)
			(size 1.35 1.35)
			(drill 1)
			(layers "*.Cu" "*.Mask")
			(remove_unused_layers no)
			(net 44 "/2xUSB3.0+RJ45/USBSS_1.TX+")
			(pinfunction "SSTX+")
			(pintype "bidirectional")
			(teardrops
				(best_length_ratio 0.4)
				(max_length 1)
				(best_width_ratio 0.9)
				(max_width 2)
				(curved_edges yes)
				(filter_ratio 0.9)
				(enabled yes)
				(allow_two_segments yes)
				(prefer_zone_connections yes)
			)
		)
		(pad "U6" thru_hole circle
			(at -6.445 9.9 270)
			(size 1.35 1.35)
			(drill 1)
			(layers "*.Cu" "*.Mask")
			(remove_unused_layers no)
			(net 47 "/2xUSB3.0+RJ45/USBSS_1.TX-")
			(pinfunction "SSTX-")
			(pintype "bidirectional")
			(teardrops
				(best_length_ratio 0.4)
				(max_length 1)
				(best_width_ratio 0.9)
				(max_width 2)
				(curved_edges yes)
				(filter_ratio 0.9)
				(enabled yes)
				(allow_two_segments yes)
				(prefer_zone_connections yes)
			)
		)
		(pad "U7" thru_hole circle
			(at -4.445 9.9 270)
			(size 1.35 1.35)
			(drill 1)
			(layers "*.Cu" "*.Mask")
			(remove_unused_layers no)
			(net 1 "GND")
			(pinfunction "GND_DRAIN")
			(pintype "power_in")
			(teardrops
				(best_length_ratio 0.4)
				(max_length 1)
				(best_width_ratio 0.9)
				(max_width 2)
				(curved_edges yes)
				(filter_ratio 0.9)
				(enabled yes)
				(allow_two_segments yes)
				(prefer_zone_connections yes)
			)
		)
		(pad "U8" thru_hole circle
			(at -2.445 9.9 270)
			(size 1.35 1.35)
			(drill 1)
			(layers "*.Cu" "*.Mask")
			(remove_unused_layers no)
			(net 159 "/2xUSB3.0+RJ45/USBSS_1.RX+")
			(pinfunction "SSRX+")
			(pintype "bidirectional")
			(teardrops
				(best_length_ratio 0.4)
				(max_length 1)
				(best_width_ratio 0.9)
				(max_width 2)
				(curved_edges yes)
				(filter_ratio 0.9)
				(enabled yes)
				(allow_two_segments yes)
				(prefer_zone_connections yes)
			)
		)
		(pad "U9" thru_hole circle
			(at -0.445 9.9 270)
			(size 1.35 1.35)
			(drill 1)
			(layers "*.Cu" "*.Mask")
			(remove_unused_layers no)
			(net 158 "/2xUSB3.0+RJ45/USBSS_1.RX-")
			(pinfunction "SSRX-")
			(pintype "bidirectional")
			(teardrops
				(best_length_ratio 0.4)
				(max_length 1)
				(best_width_ratio 0.9)
				(max_width 2)
				(curved_edges yes)
				(filter_ratio 0.9)
				(enabled yes)
				(allow_two_segments yes)
				(prefer_zone_connections yes)
			)
		)
		(pad "U10" thru_hole circle
			(at -7.945 8.2 270)
			(size 1.35 1.35)
			(drill 1)
			(layers "*.Cu" "*.Mask")
			(remove_unused_layers no)
			(net 43 "/2xUSB3.0+RJ45/P2_VBUS")
			(pinfunction "VBUS")
			(pintype "passive")
			(teardrops
				(best_length_ratio 0.4)
				(max_length 1)
				(best_width_ratio 0.9)
				(max_width 2)
				(curved_edges yes)
				(filter_ratio 0.9)
				(enabled yes)
				(allow_two_segments yes)
				(prefer_zone_connections yes)
			)
		)
		(pad "U11" thru_hole circle
			(at -5.445 8.2 270)
			(size 1.35 1.35)
			(drill 1)
			(layers "*.Cu" "*.Mask")
			(remove_unused_layers no)
			(net 125 "/2xUSB3.0+RJ45/P2_D-")
			(pinfunction "D-")
			(pintype "bidirectional")
			(teardrops
				(best_length_ratio 0.4)
				(max_length 1)
				(best_width_ratio 0.9)
				(max_width 2)
				(curved_edges yes)
				(filter_ratio 0.9)
				(enabled yes)
				(allow_two_segments yes)
				(prefer_zone_connections yes)
			)
		)
		(pad "U12" thru_hole circle
			(at -3.445 8.2 270)
			(size 1.35 1.35)
			(drill 1)
			(layers "*.Cu" "*.Mask")
			(remove_unused_layers no)
			(net 126 "/2xUSB3.0+RJ45/P2_D+")
			(pinfunction "D+")
			(pintype "bidirectional")
			(teardrops
				(best_length_ratio 0.4)
				(max_length 1)
				(best_width_ratio 0.9)
				(max_width 2)
				(curved_edges yes)
				(filter_ratio 0.9)
				(enabled yes)
				(allow_two_segments yes)
				(prefer_zone_connections yes)
			)
		)
		(pad "U13" thru_hole circle
			(at -0.945 8.2 270)
			(size 1.35 1.35)
			(drill 1)
			(layers "*.Cu" "*.Mask")
			(remove_unused_layers no)
			(net 1 "GND")
			(pinfunction "GND")
			(pintype "power_in")
			(teardrops
				(best_length_ratio 0.4)
				(max_length 1)
				(best_width_ratio 0.9)
				(max_width 2)
				(curved_edges yes)
				(filter_ratio 0.9)
				(enabled yes)
				(allow_two_segments yes)
				(prefer_zone_connections yes)
			)
		)
		(pad "U14" thru_hole circle
			(at -8.445 6.7 270)
			(size 1.35 1.35)
			(drill 1)
			(layers "*.Cu" "*.Mask")
			(remove_unused_layers no)
			(net 45 "/2xUSB3.0+RJ45/USBSS_2.TX+")
			(pinfunction "SSTX+")
			(pintype "bidirectional")
			(teardrops
				(best_length_ratio 0.4)
				(max_length 1)
				(best_width_ratio 0.9)
				(max_width 2)
				(curved_edges yes)
				(filter_ratio 0.9)
				(enabled yes)
				(allow_two_segments yes)
				(prefer_zone_connections yes)
			)
		)
		(pad "U15" thru_hole circle
			(at -6.445 6.7 270)
			(size 1.35 1.35)
			(drill 1)
			(layers "*.Cu" "*.Mask")
			(remove_unused_layers no)
			(net 49 "/2xUSB3.0+RJ45/USBSS_2.TX-")
			(pinfunction "SSTX-")
			(pintype "bidirectional")
			(teardrops
				(best_length_ratio 0.4)
				(max_length 1)
				(best_width_ratio 0.9)
				(max_width 2)
				(curved_edges yes)
				(filter_ratio 0.9)
				(enabled yes)
				(allow_two_segments yes)
				(prefer_zone_connections yes)
			)
		)
		(pad "U16" thru_hole circle
			(at -4.445 6.7 270)
			(size 1.35 1.35)
			(drill 1)
			(layers "*.Cu" "*.Mask")
			(remove_unused_layers no)
			(net 1 "GND")
			(pinfunction "GND_DRAIN")
			(pintype "power_in")
			(teardrops
				(best_length_ratio 0.4)
				(max_length 1)
				(best_width_ratio 0.9)
				(max_width 2)
				(curved_edges yes)
				(filter_ratio 0.9)
				(enabled yes)
				(allow_two_segments yes)
				(prefer_zone_connections yes)
			)
		)
		(pad "U17" thru_hole circle
			(at -2.445 6.7 270)
			(size 1.35 1.35)
			(drill 1)
			(layers "*.Cu" "*.Mask")
			(remove_unused_layers no)
			(net 161 "/2xUSB3.0+RJ45/USBSS_2.RX+")
			(pinfunction "SSRX+")
			(pintype "bidirectional")
			(teardrops
				(best_length_ratio 0.4)
				(max_length 1)
				(best_width_ratio 0.9)
				(max_width 2)
				(curved_edges yes)
				(filter_ratio 0.9)
				(enabled yes)
				(allow_two_segments yes)
				(prefer_zone_connections yes)
			)
		)
		(pad "U18" thru_hole circle
			(at -0.445 6.7 270)
			(size 1.35 1.35)
			(drill 1)
			(layers "*.Cu" "*.Mask")
			(remove_unused_layers no)
			(net 160 "/2xUSB3.0+RJ45/USBSS_2.RX-")
			(pinfunction "SSRX-")
			(pintype "bidirectional")
			(teardrops
				(best_length_ratio 0.4)
				(max_length 1)
				(best_width_ratio 0.9)
				(max_width 2)
				(curved_edges yes)
				(filter_ratio 0.9)
				(enabled yes)
				(allow_two_segments yes)
				(prefer_zone_connections yes)
			)
		)
	)
	(footprint "antmicro-footprints:R_0402_1005Metric"
		(layer "F.Cu")
		(at 179.35 103.87 90)
		(descr "Resistor SMD 0402")
		(tags "resistor SMD 0402")
		(property "Reference" "R122"
			(at 0.81 0.45 90)
			(layer "F.SilkS")
			(effects
				(font
					(size 0.7 0.7)
					(thickness 0.15)
				)
				(justify left bottom)
			)
		)
		(property "Value" "R_10k_0402"
			(at -1.011843 1.772047 90)
			(layer "F.Fab")
			(effects
				(font
					(size 0.7 0.7)
					(thickness 0.15)
				)
				(justify left bottom)
			)
		)
		(property "Datasheet" "https://www.bourns.com/docs/product-datasheets/cr.pdf"
			(at 0 0 90)
			(layer "F.Fab")
			(hide yes)
			(effects
				(font
					(size 1.27 1.27)
					(thickness 0.15)
				)
			)
		)
		(property "Author" "Antmicro"
			(at 283.22 -75.48 0)
			(layer "F.Fab")
			(hide yes)
			(effects
				(font
					(size 1 1)
					(thickness 0.15)
				)
			)
		)
		(property "License" "Apache-2.0"
			(at 283.22 -75.48 0)
			(layer "F.Fab")
			(hide yes)
			(effects
				(font
					(size 1 1)
					(thickness 0.15)
				)
			)
		)
		(property "MPN" "CR0402-FX-1002GLF"
			(at 283.22 -75.48 0)
			(layer "F.Fab")
			(hide yes)
			(effects
				(font
					(size 1 1)
					(thickness 0.15)
				)
			)
		)
		(property "Manufacturer" "Bourns"
			(at 283.22 -75.48 0)
			(layer "F.Fab")
			(hide yes)
			(effects
				(font
					(size 1 1)
					(thickness 0.15)
				)
			)
		)
		(property "Public" "False"
			(at 283.22 -75.48 0)
			(layer "F.Fab")
			(hide yes)
			(effects
				(font
					(size 1 1)
					(thickness 0.15)
				)
			)
		)
		(property "Tolerance" "1%"
			(at 283.22 -75.48 0)
			(layer "F.Fab")
			(hide yes)
			(effects
				(font
					(size 1 1)
					(thickness 0.15)
				)
			)
		)
		(property "Val" "10k"
			(at 283.22 -75.48 0)
			(layer "F.Fab")
			(hide yes)
			(effects
				(font
					(size 1 1)
					(thickness 0.15)
				)
			)
		)
		(sheetname "M.2 key M #1")
		(sheetfile "m2keym_low.kicad_sch")
		(attr smd)
		(fp_rect
			(start -0.925 -0.47)
			(end 0.925 0.47)
			(stroke
				(width 0.05)
				(type default)
			)
			(fill no)
			(layer "F.CrtYd")
		)
		(fp_rect
			(start -0.5 -0.25)
			(end 0.5 0.25)
			(stroke
				(width 0.15)
				(type solid)
			)
			(fill no)
			(layer "F.Fab")
		)
		(pad "1" smd roundrect
			(at -0.48 0 90)
			(size 0.59 0.64)
			(layers "F.Cu" "F.Mask" "F.Paste")
			(roundrect_rratio 0.25)
			(net 529 "/M.2 key M #1/~{CLKREQ}")
			(pintype "passive")
			(teardrops
				(best_length_ratio 0.2)
				(max_length 1)
				(best_width_ratio 0.9)
				(max_width 2)
				(curved_edges yes)
				(filter_ratio 0.9)
				(enabled yes)
				(allow_two_segments yes)
				(prefer_zone_connections yes)
			)
		)
		(pad "2" smd roundrect
			(at 0.48 0 90)
			(size 0.59 0.64)
			(layers "F.Cu" "F.Mask" "F.Paste")
			(roundrect_rratio 0.25)
			(net 2 "+3V3")
			(pintype "passive")
			(teardrops
				(best_length_ratio 0.2)
				(max_length 1)
				(best_width_ratio 0.9)
				(max_width 2)
				(curved_edges yes)
				(filter_ratio 0.9)
				(enabled yes)
				(allow_two_segments yes)
				(prefer_zone_connections yes)
			)
		)
	)
	(footprint "antmicro-footprints:TSSOP-8_3x3mm_P0.65mm"
		(layer "F.Cu")
		(at 234.970707 78.085)
		(property "Reference" "U29"
			(at -0.999999 2.725 0)
			(layer "F.SilkS")
			(effects
				(font
					(size 0.7 0.7)
					(thickness 0.15)
				)
				(justify left bottom)
			)
		)
		(property "Value" "NTS0102_TSSOP"
			(at 0 2.8 0)
			(layer "F.Fab")
			(effects
				(font
					(size 0.7 0.7)
					(thickness 0.15)
				)
				(justify left bottom)
			)
		)
		(property "Datasheet" "https://www.mouser.com/datasheet/2/302/NTS0102-1127324.pdf"
			(at 0 0 0)
			(layer "F.Fab")
			(hide yes)
			(effects
				(font
					(size 1.27 1.27)
					(thickness 0.15)
				)
			)
		)
		(property "Author" "Antmicro"
			(at 0 0 0)
			(layer "F.Fab")
			(hide yes)
			(effects
				(font
					(size 1 1)
					(thickness 0.15)
				)
			)
		)
		(property "License" "Apache-2.0"
			(at 0 0 0)
			(layer "F.Fab")
			(hide yes)
			(effects
				(font
					(size 1 1)
					(thickness 0.15)
				)
			)
		)
		(property "MPN" "NTS0102DP"
			(at 0 0 0)
			(layer "F.Fab")
			(hide yes)
			(effects
				(font
					(size 1 1)
					(thickness 0.15)
				)
			)
		)
		(property "Manufacturer" "NXP"
			(at 0 0 0)
			(layer "F.Fab")
			(hide yes)
			(effects
				(font
					(size 1 1)
					(thickness 0.15)
				)
			)
		)
		(sheetname "Misc")
		(sheetfile "misc.kicad_sch")
		(attr smd)
		(fp_line
			(start -1.55 1.561)
			(end 1.552 1.561)
			(stroke
				(width 0.15)
				(type solid)
			)
			(layer "F.SilkS")
		)
		(fp_line
			(start -1.525 -1.537)
			(end 1.552 -1.539)
			(stroke
				(width 0.15)
				(type solid)
			)
			(layer "F.SilkS")
		)
		(fp_circle
			(center -1.87 -1.4)
			(end -1.82 -1.4)
			(stroke
				(width 0.15)
				(type solid)
			)
			(fill yes)
			(layer "F.SilkS")
		)
		(fp_rect
			(start -3.15 -1.789)
			(end 3.15 1.811)
			(stroke
				(width 0.05)
				(type solid)
			)
			(fill no)
			(layer "F.CrtYd")
		)
		(fp_line
			(start -1.55 -0.937)
			(end -1.55 1.561)
			(stroke
				(width 0.15)
				(type solid)
			)
			(layer "F.Fab")
		)
		(fp_line
			(start -1.55 -0.937)
			(end -0.949 -1.539)
			(stroke
				(width 0.15)
				(type solid)
			)
			(layer "F.Fab")
		)
		(fp_line
			(start -1.55 1.561)
			(end 1.552 1.561)
			(stroke
				(width 0.15)
				(type solid)
			)
			(layer "F.Fab")
		)
		(fp_line
			(start -0.949 -1.539)
			(end 1.552 -1.539)
			(stroke
				(width 0.15)
				(type solid)
			)
			(layer "F.Fab")
		)
		(fp_line
			(start 1.552 -1.539)
			(end 1.552 1.561)
			(stroke
				(width 0.15)
				(type solid)
			)
			(layer "F.Fab")
		)
		(pad "1" smd roundrect
			(at -2.148 -0.962)
			(size 1.47 0.4)
			(layers "F.Cu" "F.Mask" "F.Paste")
			(roundrect_rratio 0.25)
			(net 284 "/Misc/PWM_{C5V}")
			(pinfunction "B_{2}")
			(pintype "bidirectional")
			(teardrops
				(best_length_ratio 0.2)
				(max_length 1)
				(best_width_ratio 0.9)
				(max_width 2)
				(curved_edges yes)
				(filter_ratio 0.9)
				(enabled yes)
				(allow_two_segments yes)
				(prefer_zone_connections yes)
			)
		)
		(pad "2" smd roundrect
			(at -2.148 -0.313)
			(size 1.47 0.4)
			(layers "F.Cu" "F.Mask" "F.Paste")
			(roundrect_rratio 0.25)
			(net 1 "GND")
			(pinfunction "GND")
			(pintype "power_in")
			(teardrops
				(best_length_ratio 0.2)
				(max_length 1)
				(best_width_ratio 0.9)
				(max_width 2)
				(curved_edges yes)
				(filter_ratio 0.9)
				(enabled yes)
				(allow_two_segments yes)
				(prefer_zone_connections yes)
			)
		)
		(pad "3" smd roundrect
			(at -2.148 0.338)
			(size 1.47 0.4)
			(layers "F.Cu" "F.Mask" "F.Paste")
			(roundrect_rratio 0.25)
			(net 2 "+3V3")
			(pinfunction "VCC_{A}")
			(pintype "power_in")
			(teardrops
				(best_length_ratio 0.2)
				(max_length 1)
				(best_width_ratio 0.9)
				(max_width 2)
				(curved_edges yes)
				(filter_ratio 0.9)
				(enabled yes)
				(allow_two_segments yes)
				(prefer_zone_connections yes)
			)
		)
		(pad "4" smd roundrect
			(at -2.148 0.987)
			(size 1.47 0.4)
			(layers "F.Cu" "F.Mask" "F.Paste")
			(roundrect_rratio 0.25)
			(net 400 "/Com Express 7 MGMT/FAN_PWM")
			(pinfunction "A_{2}")
			(pintype "bidirectional")
			(teardrops
				(best_length_ratio 0.2)
				(max_length 1)
				(best_width_ratio 0.9)
				(max_width 2)
				(curved_edges yes)
				(filter_ratio 0.9)
				(enabled yes)
				(allow_two_segments yes)
				(prefer_zone_connections yes)
			)
		)
		(pad "5" smd roundrect
			(at 2.151 0.987)
			(size 1.47 0.4)
			(layers "F.Cu" "F.Mask" "F.Paste")
			(roundrect_rratio 0.25)
			(net 401 "/Com Express 7 MGMT/FAM_TACH")
			(pinfunction "A_{1}")
			(pintype "bidirectional")
			(teardrops
				(best_length_ratio 0.2)
				(max_length 1)
				(best_width_ratio 0.9)
				(max_width 2)
				(curved_edges yes)
				(filter_ratio 0.9)
				(enabled yes)
				(allow_two_segments yes)
				(prefer_zone_connections yes)
			)
		)
		(pad "6" smd roundrect
			(at 2.151 0.338)
			(size 1.47 0.4)
			(layers "F.Cu" "F.Mask" "F.Paste")
			(roundrect_rratio 0.25)
			(net 2 "+3V3")
			(pinfunction "OE")
			(pintype "input")
			(teardrops
				(best_length_ratio 0.2)
				(max_length 1)
				(best_width_ratio 0.9)
				(max_width 2)
				(curved_edges yes)
				(filter_ratio 0.9)
				(enabled yes)
				(allow_two_segments yes)
				(prefer_zone_connections yes)
			)
		)
		(pad "7" smd roundrect
			(at 2.151 -0.313)
			(size 1.47 0.4)
			(layers "F.Cu" "F.Mask" "F.Paste")
			(roundrect_rratio 0.25)
			(net 52 "+5V")
			(pinfunction "VCC_{B}")
			(pintype "power_in")
			(teardrops
				(best_length_ratio 0.2)
				(max_length 1)
				(best_width_ratio 0.9)
				(max_width 2)
				(curved_edges yes)
				(filter_ratio 0.9)
				(enabled yes)
				(allow_two_segments yes)
				(prefer_zone_connections yes)
			)
		)
		(pad "8" smd roundrect
			(at 2.151 -0.962)
			(size 1.47 0.4)
			(layers "F.Cu" "F.Mask" "F.Paste")
			(roundrect_rratio 0.25)
			(net 283 "/Misc/TACH_{C5V}")
			(pinfunction "B_{1}")
			(pintype "bidirectional")
			(teardrops
				(best_length_ratio 0.2)
				(max_length 1)
				(best_width_ratio 0.9)
				(max_width 2)
				(curved_edges yes)
				(filter_ratio 0.9)
				(enabled yes)
				(allow_two_segments yes)
				(prefer_zone_connections yes)
			)
		)
	)
	(footprint "antmicro-footprints:TP_SMD_0.75mm"
		(layer "F.Cu")
		(at 146.6 128.71)
		(property "Reference" "TP74"
			(at 0.4 -3.3 90)
			(layer "F.SilkS")
			(effects
				(font
					(size 0.7 0.7)
					(thickness 0.15)
				)
				(justify left bottom)
			)
		)
		(property "Value" "TP_0.75mm_SMD"
			(at 0 1.2 0)
			(layer "F.Fab")
			(effects
				(font
					(size 0.7 0.7)
					(thickness 0.15)
				)
				(justify left bottom)
			)
		)
		(property "Author" "Antmicro"
			(at 0 0 0)
			(layer "F.Fab")
			(hide yes)
			(effects
				(font
					(size 1 1)
					(thickness 0.15)
				)
			)
		)
		(property "License" "Apache-2.0"
			(at 0 0 0)
			(layer "F.Fab")
			(hide yes)
			(effects
				(font
					(size 1 1)
					(thickness 0.15)
				)
			)
		)
		(property "MPN" ""
			(at 0 0 0)
			(layer "F.Fab")
			(hide yes)
			(effects
				(font
					(size 1 1)
					(thickness 0.15)
				)
			)
		)
		(property "Manufacturer" ""
			(at 0 0 0)
			(layer "F.Fab")
			(hide yes)
			(effects
				(font
					(size 1 1)
					(thickness 0.15)
				)
			)
		)
		(property "Public" "False"
			(at 0 0 0)
			(layer "F.Fab")
			(hide yes)
			(effects
				(font
					(size 1 1)
					(thickness 0.15)
				)
			)
		)
		(sheetname "KR to SFI #1")
		(sheetfile "kr_sfi.kicad_sch")
		(attr exclude_from_pos_files exclude_from_bom)
		(fp_circle
			(center 0 0)
			(end 0.475 0)
			(stroke
				(width 0.05)
				(type default)
			)
			(fill no)
			(layer "F.CrtYd")
		)
		(pad "1" smd circle
			(at 0 0)
			(size 0.75 0.75)
			(layers "F.Cu" "F.Mask")
			(net 737 "Net-(U43B-LOSB)")
			(pinfunction "1")
			(pintype "passive")
			(teardrops
				(best_length_ratio 0.4)
				(max_length 1)
				(best_width_ratio 0.9)
				(max_width 2)
				(curved_edges yes)
				(filter_ratio 0.9)
				(enabled yes)
				(allow_two_segments yes)
				(prefer_zone_connections yes)
			)
		)
	)
	(footprint "antmicro-footprints:R_0201"
		(layer "F.Cu")
		(at 134.41 147.31 90)
		(descr "Resistor SMD 0201")
		(tags "resistor SMD 0201")
		(property "Reference" "R291"
			(at -4.099 0.29 90)
			(layer "F.SilkS")
			(effects
				(font
					(size 0.7 0.7)
					(thickness 0.15)
				)
				(justify left bottom)
			)
		)
		(property "Value" "R_0R_0201"
			(at 0 1.25 90)
			(layer "F.Fab")
			(effects
				(font
					(size 0.7 0.7)
					(thickness 0.15)
				)
				(justify left bottom)
			)
		)
		(property "Datasheet" "https://www.bourns.com/docs/product-datasheets/cr.pdf"
			(at 0 0 90)
			(layer "F.Fab")
			(hide yes)
			(effects
				(font
					(size 1.27 1.27)
					(thickness 0.15)
				)
			)
		)
		(property "Author" "Antmicro"
			(at 281.72 12.9 0)
			(layer "F.Fab")
			(hide yes)
			(effects
				(font
					(size 1 1)
					(thickness 0.15)
				)
			)
		)
		(property "License" "Apache-2.0"
			(at 281.72 12.9 0)
			(layer "F.Fab")
			(hide yes)
			(effects
				(font
					(size 1 1)
					(thickness 0.15)
				)
			)
		)
		(property "MPN" "CR0201-FX-0R00GLF"
			(at 281.72 12.9 0)
			(layer "F.Fab")
			(hide yes)
			(effects
				(font
					(size 1 1)
					(thickness 0.15)
				)
			)
		)
		(property "Manufacturer" "Bourns"
			(at 281.72 12.9 0)
			(layer "F.Fab")
			(hide yes)
			(effects
				(font
					(size 1 1)
					(thickness 0.15)
				)
			)
		)
		(property "Tolerance" "1%"
			(at 281.72 12.9 0)
			(layer "F.Fab")
			(hide yes)
			(effects
				(font
					(size 1 1)
					(thickness 0.15)
				)
			)
		)
		(property "Val" "0R"
			(at 281.72 12.9 0)
			(layer "F.Fab")
			(hide yes)
			(effects
				(font
					(size 1 1)
					(thickness 0.15)
				)
			)
		)
		(sheetname "KR to SFI #2")
		(sheetfile "kr_sfi.kicad_sch")
		(attr smd)
		(fp_rect
			(start -0.7 -0.35)
			(end 0.7 0.35)
			(stroke
				(width 0.05)
				(type default)
			)
			(fill no)
			(layer "F.CrtYd")
		)
		(fp_rect
			(start -0.3 -0.15)
			(end 0.298 0.148)
			(stroke
				(width 0.15)
				(type solid)
			)
			(fill no)
			(layer "F.Fab")
		)
		(pad "" smd roundrect
			(at -0.346 0 90)
			(size 0.318 0.36)
			(layers "F.Paste")
			(roundrect_rratio 0.25)
			(teardrops
				(best_length_ratio 0.2)
				(max_length 1)
				(best_width_ratio 0.9)
				(max_width 2)
				(curved_edges yes)
				(filter_ratio 0.9)
				(enabled yes)
				(allow_two_segments yes)
				(prefer_zone_connections yes)
			)
		)
		(pad "" smd roundrect
			(at 0.344 0 90)
			(size 0.318 0.36)
			(layers "F.Paste")
			(roundrect_rratio 0.25)
			(teardrops
				(best_length_ratio 0.2)
				(max_length 1)
				(best_width_ratio 0.9)
				(max_width 2)
				(curved_edges yes)
				(filter_ratio 0.9)
				(enabled yes)
				(allow_two_segments yes)
				(prefer_zone_connections yes)
			)
		)
		(pad "1" smd roundrect
			(at -0.32 0 90)
			(size 0.46 0.4)
			(layers "F.Cu" "F.Mask")
			(roundrect_rratio 0.25)
			(net 428 "/2xSFP+/10GKR_SFP1.RX-")
			(pintype "passive")
			(teardrops
				(best_length_ratio 0.2)
				(max_length 1)
				(best_width_ratio 0.9)
				(max_width 2)
				(curved_edges yes)
				(filter_ratio 0.9)
				(enabled yes)
				(allow_two_segments yes)
				(prefer_zone_connections yes)
			)
		)
		(pad "2" smd roundrect
			(at 0.32 0 90)
			(size 0.46 0.4)
			(layers "F.Cu" "F.Mask")
			(roundrect_rratio 0.25)
			(net 688 "/2xSFP+/KR to SFI #2/KR_R.RX-")
			(pintype "passive")
			(teardrops
				(best_length_ratio 0.2)
				(max_length 1)
				(best_width_ratio 0.9)
				(max_width 2)
				(curved_edges yes)
				(filter_ratio 0.9)
				(enabled yes)
				(allow_two_segments yes)
				(prefer_zone_connections yes)
			)
		)
	)
	(footprint "antmicro-footprints:R_0402_1005Metric"
		(layer "F.Cu")
		(at 221.16 130.65)
		(descr "Resistor SMD 0402")
		(tags "resistor SMD 0402")
		(property "Reference" "R200"
			(at 0.79 0.41 0)
			(layer "F.SilkS")
			(effects
				(font
					(size 0.7 0.7)
					(thickness 0.15)
				)
				(justify left bottom)
			)
		)
		(property "Value" "R_0R_0402"
			(at -1.011843 1.772047 0)
			(layer "F.Fab")
			(effects
				(font
					(size 0.7 0.7)
					(thickness 0.15)
				)
				(justify left bottom)
			)
		)
		(property "Datasheet" "https://industrial.panasonic.com/cdbs/www-data/pdf/RDA0000/AOA0000C301.pdf"
			(at 0 0 0)
			(layer "F.Fab")
			(hide yes)
			(effects
				(font
					(size 1.27 1.27)
					(thickness 0.15)
				)
			)
		)
		(property "Author" "Antmicro"
			(at 0 0 0)
			(layer "F.Fab")
			(hide yes)
			(effects
				(font
					(size 1 1)
					(thickness 0.15)
				)
			)
		)
		(property "Current" "1A"
			(at 0 0 0)
			(layer "F.Fab")
			(hide yes)
			(effects
				(font
					(size 1 1)
					(thickness 0.15)
				)
			)
		)
		(property "License" "Apache-2.0"
			(at 0 0 0)
			(layer "F.Fab")
			(hide yes)
			(effects
				(font
					(size 1 1)
					(thickness 0.15)
				)
			)
		)
		(property "MPN" "ERJ2GE0R00X"
			(at 0 0 0)
			(layer "F.Fab")
			(hide yes)
			(effects
				(font
					(size 1 1)
					(thickness 0.15)
				)
			)
		)
		(property "Manufacturer" "Panasonic"
			(at 0 0 0)
			(layer "F.Fab")
			(hide yes)
			(effects
				(font
					(size 1 1)
					(thickness 0.15)
				)
			)
		)
		(property "Public" "False"
			(at 0 0 0)
			(layer "F.Fab")
			(hide yes)
			(effects
				(font
					(size 1 1)
					(thickness 0.15)
				)
			)
		)
		(property "Tolerance" ""
			(at 0 0 0)
			(layer "F.Fab")
			(hide yes)
			(effects
				(font
					(size 1 1)
					(thickness 0.15)
				)
			)
		)
		(property "Val" "0R"
			(at 0 0 0)
			(layer "F.Fab")
			(hide yes)
			(effects
				(font
					(size 1 1)
					(thickness 0.15)
				)
			)
		)
		(sheetname "PCIe misc")
		(sheetfile "pcie_misc.kicad_sch")
		(attr smd)
		(fp_rect
			(start -0.925 -0.47)
			(end 0.925 0.47)
			(stroke
				(width 0.05)
				(type default)
			)
			(fill no)
			(layer "F.CrtYd")
		)
		(fp_rect
			(start -0.5 -0.25)
			(end 0.5 0.25)
			(stroke
				(width 0.15)
				(type solid)
			)
			(fill no)
			(layer "F.Fab")
		)
		(pad "1" smd roundrect
			(at -0.48 0)
			(size 0.59 0.64)
			(layers "F.Cu" "F.Mask" "F.Paste")
			(roundrect_rratio 0.25)
			(net 619 "/PCIe misc/DIF4+")
			(pintype "passive")
			(teardrops
				(best_length_ratio 0.2)
				(max_length 1)
				(best_width_ratio 0.9)
				(max_width 2)
				(curved_edges yes)
				(filter_ratio 0.9)
				(enabled yes)
				(allow_two_segments yes)
				(prefer_zone_connections yes)
			)
		)
		(pad "2" smd roundrect
			(at 0.48 0)
			(size 0.59 0.64)
			(layers "F.Cu" "F.Mask" "F.Paste")
			(roundrect_rratio 0.25)
			(net 273 "/M.2 key M #2/PCIE_{REF}.CK+")
			(pintype "passive")
			(teardrops
				(best_length_ratio 0.2)
				(max_length 1)
				(best_width_ratio 0.9)
				(max_width 2)
				(curved_edges yes)
				(filter_ratio 0.9)
				(enabled yes)
				(allow_two_segments yes)
				(prefer_zone_connections yes)
			)
		)
	)
	(footprint "antmicro-footprints:TP_SMD_0.75mm"
		(layer "F.Cu")
		(at 190.70861 72.802163 -90)
		(property "Reference" "TP97"
			(at 0 -0.6 90)
			(layer "F.SilkS")
			(hide yes)
			(effects
				(font
					(size 0.7 0.7)
					(thickness 0.15)
				)
				(justify right bottom)
			)
		)
		(property "Value" "TP_0.75mm_SMD"
			(at 0 1.2 90)
			(layer "F.Fab")
			(effects
				(font
					(size 0.7 0.7)
					(thickness 0.15)
				)
				(justify right bottom)
			)
		)
		(property "Author" "Antmicro"
			(at 117.906447 263.510773 0)
			(layer "F.Fab")
			(hide yes)
			(effects
				(font
					(size 1 1)
					(thickness 0.15)
				)
			)
		)
		(property "License" "Apache-2.0"
			(at 117.906447 263.510773 0)
			(layer "F.Fab")
			(hide yes)
			(effects
				(font
					(size 1 1)
					(thickness 0.15)
				)
			)
		)
		(property "MPN" ""
			(at 117.906447 263.510773 0)
			(layer "F.Fab")
			(hide yes)
			(effects
				(font
					(size 1 1)
					(thickness 0.15)
				)
			)
		)
		(property "Manufacturer" ""
			(at 117.906447 263.510773 0)
			(layer "F.Fab")
			(hide yes)
			(effects
				(font
					(size 1 1)
					(thickness 0.15)
				)
			)
		)
		(property "Public" "False"
			(at 117.906447 263.510773 0)
			(layer "F.Fab")
			(hide yes)
			(effects
				(font
					(size 1 1)
					(thickness 0.15)
				)
			)
		)
		(sheetname "Power")
		(sheetfile "power.kicad_sch")
		(attr exclude_from_pos_files exclude_from_bom)
		(fp_circle
			(center 0 0)
			(end 0.475 0)
			(stroke
				(width 0.05)
				(type default)
			)
			(fill no)
			(layer "F.CrtYd")
		)
		(pad "1" smd circle
			(at 0 0 270)
			(size 0.75 0.75)
			(layers "F.Cu" "F.Mask")
			(net 73 "+3V3_AON")
			(pinfunction "1")
			(pintype "passive")
			(teardrops
				(best_length_ratio 0.4)
				(max_length 1)
				(best_width_ratio 0.9)
				(max_width 2)
				(curved_edges yes)
				(filter_ratio 0.9)
				(enabled yes)
				(allow_two_segments yes)
				(prefer_zone_connections yes)
			)
		)
	)
	(footprint "antmicro-footprints:USON-10_2.5x1mm_P0.5mm"
		(layer "F.Cu")
		(at 107.6 152.2 -90)
		(descr "USON-10 2.5x1mm_ Pitch 0.5mm")
		(tags "USON-10 2.5x1mm Pitch 0.5mm")
		(property "Reference" "U9"
			(at -1.7 -0.78 0)
			(layer "F.SilkS")
			(effects
				(font
					(size 0.7 0.7)
					(thickness 0.15)
				)
				(justify right top)
			)
		)
		(property "Value" "ESD204DQAR"
			(at 0.018 2.499 90)
			(layer "F.Fab")
			(effects
				(font
					(size 0.7 0.7)
					(thickness 0.15)
				)
				(justify right top)
			)
		)
		(property "Datasheet" "https://www.ti.com/lit/ds/symlink/esd204.pdf?ts=1706004844383&ref_url=https%253A%252F%252Fwww.ti.com%252Finterface%252Fdiodes%252Fesd-protection-diodes%252Fproducts.html"
			(at 0 0 90)
			(layer "F.Fab")
			(hide yes)
			(effects
				(font
					(size 1.27 1.27)
					(thickness 0.15)
				)
			)
		)
		(property "Author" "Antmicro"
			(at 249.299 54.639 0)
			(layer "F.Fab")
			(hide yes)
			(effects
				(font
					(size 1 1)
					(thickness 0.15)
				)
			)
		)
		(property "License" "Apache-2.0"
			(at 249.299 54.639 0)
			(layer "F.Fab")
			(hide yes)
			(effects
				(font
					(size 1 1)
					(thickness 0.15)
				)
			)
		)
		(property "MPN" "ESD204DQAR"
			(at 249.299 54.639 0)
			(layer "F.Fab")
			(hide yes)
			(effects
				(font
					(size 1 1)
					(thickness 0.15)
				)
			)
		)
		(property "Manufacturer" "Texas Instruments"
			(at 249.299 54.639 0)
			(layer "F.Fab")
			(hide yes)
			(effects
				(font
					(size 1 1)
					(thickness 0.15)
				)
			)
		)
		(sheetname "OCuLink")
		(sheetfile "oculink.kicad_sch")
		(attr smd)
		(fp_line
			(start 0.498 1.398)
			(end -0.5 1.398)
			(stroke
				(width 0.15)
				(type solid)
			)
			(layer "F.SilkS")
		)
		(fp_line
			(start 0.498 -1.401)
			(end -0.5 -1.401)
			(stroke
				(width 0.15)
				(type solid)
			)
			(layer "F.SilkS")
		)
		(fp_circle
			(center -0.68 -1.27)
			(end -0.63 -1.27)
			(stroke
				(width 0.15)
				(type solid)
			)
			(fill yes)
			(layer "F.SilkS")
		)
		(fp_rect
			(start -0.8 -1.5)
			(end 0.8 1.499)
			(stroke
				(width 0.05)
				(type solid)
			)
			(fill no)
			(layer "F.CrtYd")
		)
		(fp_line
			(start -0.5 1.249)
			(end 0.498 1.249)
			(stroke
				(width 0.15)
				(type solid)
			)
			(layer "F.Fab")
		)
		(fp_line
			(start -0.5 -1)
			(end -0.5 1.249)
			(stroke
				(width 0.15)
				(type solid)
			)
			(layer "F.Fab")
		)
		(fp_line
			(start -0.25 -1.25)
			(end -0.5 -1)
			(stroke
				(width 0.15)
				(type solid)
			)
			(layer "F.Fab")
		)
		(fp_line
			(start 0.498 -1.25)
			(end 0.498 1.249)
			(stroke
				(width 0.15)
				(type solid)
			)
			(layer "F.Fab")
		)
		(fp_line
			(start 0.498 -1.25)
			(end -0.25 -1.25)
			(stroke
				(width 0.15)
				(type solid)
			)
			(layer "F.Fab")
		)
		(pad "1" smd roundrect
			(at -0.387 -1 180)
			(size 0.25 0.55)
			(layers "F.Cu" "F.Mask" "F.Paste")
			(roundrect_rratio 0.25)
			(net 194 "/OCuLink/PCIe_{x4}.RX2+")
			(pintype "passive")
			(teardrops
				(best_length_ratio 0.2)
				(max_length 1)
				(best_width_ratio 0.9)
				(max_width 2)
				(curved_edges yes)
				(filter_ratio 0.9)
				(enabled yes)
				(allow_two_segments yes)
				(prefer_zone_connections yes)
			)
		)
		(pad "2" smd roundrect
			(at -0.387 -0.5 180)
			(size 0.25 0.55)
			(layers "F.Cu" "F.Mask" "F.Paste")
			(roundrect_rratio 0.25)
			(net 195 "/OCuLink/PCIe_{x4}.RX2-")
			(pintype "passive")
			(teardrops
				(best_length_ratio 0.2)
				(max_length 1)
				(best_width_ratio 0.9)
				(max_width 2)
				(curved_edges yes)
				(filter_ratio 0.9)
				(enabled yes)
				(allow_two_segments yes)
				(prefer_zone_connections yes)
			)
		)
		(pad "3" smd roundrect
			(at -0.387 0 180)
			(size 0.4 0.55)
			(layers "F.Cu" "F.Mask" "F.Paste")
			(roundrect_rratio 0.25)
			(net 1 "GND")
			(pintype "power_in")
			(teardrops
				(best_length_ratio 0.2)
				(max_length 1)
				(best_width_ratio 0.9)
				(max_width 2)
				(curved_edges yes)
				(filter_ratio 0.9)
				(enabled yes)
				(allow_two_segments yes)
				(prefer_zone_connections yes)
			)
		)
		(pad "4" smd roundrect
			(at -0.387 0.498 180)
			(size 0.25 0.55)
			(layers "F.Cu" "F.Mask" "F.Paste")
			(roundrect_rratio 0.25)
			(net 196 "/OCuLink/PCIe_{x4}.RX3+")
			(pintype "passive")
			(teardrops
				(best_length_ratio 0.2)
				(max_length 1)
				(best_width_ratio 0.9)
				(max_width 2)
				(curved_edges yes)
				(filter_ratio 0.9)
				(enabled yes)
				(allow_two_segments yes)
				(prefer_zone_connections yes)
			)
		)
		(pad "5" smd roundrect
			(at -0.387 0.998 180)
			(size 0.25 0.55)
			(layers "F.Cu" "F.Mask" "F.Paste")
			(roundrect_rratio 0.25)
			(net 197 "/OCuLink/PCIe_{x4}.RX3-")
			(pintype "passive")
			(teardrops
				(best_length_ratio 0.2)
				(max_length 1)
				(best_width_ratio 0.9)
				(max_width 2)
				(curved_edges yes)
				(filter_ratio 0.9)
				(enabled yes)
				(allow_two_segments yes)
				(prefer_zone_connections yes)
			)
		)
		(pad "6" smd roundrect
			(at 0.385 0.998 180)
			(size 0.25 0.55)
			(layers "F.Cu" "F.Mask" "F.Paste")
			(roundrect_rratio 0.25)
			(net 197 "/OCuLink/PCIe_{x4}.RX3-")
			(pintype "passive")
			(teardrops
				(best_length_ratio 0.2)
				(max_length 1)
				(best_width_ratio 0.9)
				(max_width 2)
				(curved_edges yes)
				(filter_ratio 0.9)
				(enabled yes)
				(allow_two_segments yes)
				(prefer_zone_connections yes)
			)
		)
		(pad "7" smd roundrect
			(at 0.385 0.498 180)
			(size 0.25 0.55)
			(layers "F.Cu" "F.Mask" "F.Paste")
			(roundrect_rratio 0.25)
			(net 196 "/OCuLink/PCIe_{x4}.RX3+")
			(pintype "passive")
			(teardrops
				(best_length_ratio 0.2)
				(max_length 1)
				(best_width_ratio 0.9)
				(max_width 2)
				(curved_edges yes)
				(filter_ratio 0.9)
				(enabled yes)
				(allow_two_segments yes)
				(prefer_zone_connections yes)
			)
		)
		(pad "8" smd roundrect
			(at 0.385 0 180)
			(size 0.4 0.55)
			(layers "F.Cu" "F.Mask" "F.Paste")
			(roundrect_rratio 0.25)
			(net 1 "GND")
			(pintype "passive")
			(teardrops
				(best_length_ratio 0.2)
				(max_length 1)
				(best_width_ratio 0.9)
				(max_width 2)
				(curved_edges yes)
				(filter_ratio 0.9)
				(enabled yes)
				(allow_two_segments yes)
				(prefer_zone_connections yes)
			)
		)
		(pad "9" smd roundrect
			(at 0.385 -0.5 180)
			(size 0.25 0.55)
			(layers "F.Cu" "F.Mask" "F.Paste")
			(roundrect_rratio 0.25)
			(net 195 "/OCuLink/PCIe_{x4}.RX2-")
			(pintype "passive")
			(teardrops
				(best_length_ratio 0.2)
				(max_length 1)
				(best_width_ratio 0.9)
				(max_width 2)
				(curved_edges yes)
				(filter_ratio 0.9)
				(enabled yes)
				(allow_two_segments yes)
				(prefer_zone_connections yes)
			)
		)
		(pad "10" smd roundrect
			(at 0.385 -1 180)
			(size 0.25 0.55)
			(layers "F.Cu" "F.Mask" "F.Paste")
			(roundrect_rratio 0.25)
			(net 194 "/OCuLink/PCIe_{x4}.RX2+")
			(pintype "passive")
			(teardrops
				(best_length_ratio 0.2)
				(max_length 1)
				(best_width_ratio 0.9)
				(max_width 2)
				(curved_edges yes)
				(filter_ratio 0.9)
				(enabled yes)
				(allow_two_segments yes)
				(prefer_zone_connections yes)
			)
		)
	)
	(footprint "antmicro-footprints:R_0402_1005Metric"
		(layer "F.Cu")
		(at 308.275 76.362002)
		(descr "Resistor SMD 0402")
		(tags "resistor SMD 0402")
		(property "Reference" "R191"
			(at 0.775 0.397998 0)
			(layer "F.SilkS")
			(effects
				(font
					(size 0.7 0.7)
					(thickness 0.15)
				)
				(justify left bottom)
			)
		)
		(property "Value" "R_1k_0402"
			(at -1.011843 1.772047 0)
			(layer "F.Fab")
			(effects
				(font
					(size 0.7 0.7)
					(thickness 0.15)
				)
				(justify left bottom)
			)
		)
		(property "Datasheet" "https://www.bourns.com/docs/product-datasheets/cr.pdf"
			(at 0 0 0)
			(layer "F.Fab")
			(hide yes)
			(effects
				(font
					(size 1.27 1.27)
					(thickness 0.15)
				)
			)
		)
		(property "Author" "Antmicro"
			(at 0 0 0)
			(layer "F.Fab")
			(hide yes)
			(effects
				(font
					(size 1 1)
					(thickness 0.15)
				)
			)
		)
		(property "License" "Apache-2.0"
			(at 0 0 0)
			(layer "F.Fab")
			(hide yes)
			(effects
				(font
					(size 1 1)
					(thickness 0.15)
				)
			)
		)
		(property "MPN" "CR0402-FX-1001GLF"
			(at 0 0 0)
			(layer "F.Fab")
			(hide yes)
			(effects
				(font
					(size 1 1)
					(thickness 0.15)
				)
			)
		)
		(property "Manufacturer" "Bourns"
			(at 0 0 0)
			(layer "F.Fab")
			(hide yes)
			(effects
				(font
					(size 1 1)
					(thickness 0.15)
				)
			)
		)
		(property "Public" "False"
			(at 0 0 0)
			(layer "F.Fab")
			(hide yes)
			(effects
				(font
					(size 1 1)
					(thickness 0.15)
				)
			)
		)
		(property "Tolerance" "1%"
			(at 0 0 0)
			(layer "F.Fab")
			(hide yes)
			(effects
				(font
					(size 1 1)
					(thickness 0.15)
				)
			)
		)
		(property "Val" "1k"
			(at 0 0 0)
			(layer "F.Fab")
			(hide yes)
			(effects
				(font
					(size 1 1)
					(thickness 0.15)
				)
			)
		)
		(sheetname "PCIe misc")
		(sheetfile "pcie_misc.kicad_sch")
		(attr smd)
		(fp_rect
			(start -0.925 -0.47)
			(end 0.925 0.47)
			(stroke
				(width 0.05)
				(type default)
			)
			(fill no)
			(layer "F.CrtYd")
		)
		(fp_rect
			(start -0.5 -0.25)
			(end 0.5 0.25)
			(stroke
				(width 0.15)
				(type solid)
			)
			(fill no)
			(layer "F.Fab")
		)
		(pad "1" smd roundrect
			(at -0.48 0)
			(size 0.59 0.64)
			(layers "F.Cu" "F.Mask" "F.Paste")
			(roundrect_rratio 0.25)
			(net 610 "Net-(Y1-EN)")
			(pintype "passive")
			(teardrops
				(best_length_ratio 0.2)
				(max_length 1)
				(best_width_ratio 0.9)
				(max_width 2)
				(curved_edges yes)
				(filter_ratio 0.9)
				(enabled yes)
				(allow_two_segments yes)
				(prefer_zone_connections yes)
			)
		)
		(pad "2" smd roundrect
			(at 0.48 0)
			(size 0.59 0.64)
			(layers "F.Cu" "F.Mask" "F.Paste")
			(roundrect_rratio 0.25)
			(net 2 "+3V3")
			(pintype "passive")
			(teardrops
				(best_length_ratio 0.2)
				(max_length 1)
				(best_width_ratio 0.9)
				(max_width 2)
				(curved_edges yes)
				(filter_ratio 0.9)
				(enabled yes)
				(allow_two_segments yes)
				(prefer_zone_connections yes)
			)
		)
	)
	(footprint "antmicro-footprints:R_0402_1005Metric"
		(layer "F.Cu")
		(at 112.9 147.86 180)
		(descr "Resistor SMD 0402")
		(tags "resistor SMD 0402")
		(property "Reference" "R204"
			(at 0.85 -0.45 0)
			(layer "F.SilkS")
			(effects
				(font
					(size 0.7 0.7)
					(thickness 0.15)
				)
				(justify right bottom)
			)
		)
		(property "Value" "R_1k_0402"
			(at -1.011843 1.772047 0)
			(layer "F.Fab")
			(effects
				(font
					(size 0.7 0.7)
					(thickness 0.15)
				)
				(justify right bottom)
			)
		)
		(property "Datasheet" "https://www.bourns.com/docs/product-datasheets/cr.pdf"
			(at 0 0 180)
			(layer "F.Fab")
			(hide yes)
			(effects
				(font
					(size 1.27 1.27)
					(thickness 0.15)
				)
			)
		)
		(property "Author" "Antmicro"
			(at 225.8 295.72 0)
			(layer "F.Fab")
			(hide yes)
			(effects
				(font
					(size 1 1)
					(thickness 0.15)
				)
			)
		)
		(property "License" "Apache-2.0"
			(at 225.8 295.72 0)
			(layer "F.Fab")
			(hide yes)
			(effects
				(font
					(size 1 1)
					(thickness 0.15)
				)
			)
		)
		(property "MPN" "CR0402-FX-1001GLF"
			(at 225.8 295.72 0)
			(layer "F.Fab")
			(hide yes)
			(effects
				(font
					(size 1 1)
					(thickness 0.15)
				)
			)
		)
		(property "Manufacturer" "Bourns"
			(at 225.8 295.72 0)
			(layer "F.Fab")
			(hide yes)
			(effects
				(font
					(size 1 1)
					(thickness 0.15)
				)
			)
		)
		(property "Public" "False"
			(at 225.8 295.72 0)
			(layer "F.Fab")
			(hide yes)
			(effects
				(font
					(size 1 1)
					(thickness 0.15)
				)
			)
		)
		(property "Tolerance" "1%"
			(at 225.8 295.72 0)
			(layer "F.Fab")
			(hide yes)
			(effects
				(font
					(size 1 1)
					(thickness 0.15)
				)
			)
		)
		(property "Val" "1k"
			(at 225.8 295.72 0)
			(layer "F.Fab")
			(hide yes)
			(effects
				(font
					(size 1 1)
					(thickness 0.15)
				)
			)
		)
		(sheetname "PCIe redriver")
		(sheetfile "pcie_redriver.kicad_sch")
		(attr smd dnp)
		(fp_rect
			(start -0.925 -0.47)
			(end 0.925 0.47)
			(stroke
				(width 0.05)
				(type default)
			)
			(fill no)
			(layer "F.CrtYd")
		)
		(fp_rect
			(start -0.5 -0.25)
			(end 0.5 0.25)
			(stroke
				(width 0.15)
				(type solid)
			)
			(fill no)
			(layer "F.Fab")
		)
		(pad "1" smd roundrect
			(at -0.48 0 180)
			(size 0.59 0.64)
			(layers "F.Cu" "F.Mask" "F.Paste")
			(roundrect_rratio 0.25)
			(net 2 "+3V3")
			(pintype "passive")
			(teardrops
				(best_length_ratio 0.2)
				(max_length 1)
				(best_width_ratio 0.9)
				(max_width 2)
				(curved_edges yes)
				(filter_ratio 0.9)
				(enabled yes)
				(allow_two_segments yes)
				(prefer_zone_connections yes)
			)
		)
		(pad "2" smd roundrect
			(at 0.48 0 180)
			(size 0.59 0.64)
			(layers "F.Cu" "F.Mask" "F.Paste")
			(roundrect_rratio 0.25)
			(net 624 "/PCIe redriver/TX_EQ1")
			(pintype "passive")
			(teardrops
				(best_length_ratio 0.2)
				(max_length 1)
				(best_width_ratio 0.9)
				(max_width 2)
				(curved_edges yes)
				(filter_ratio 0.9)
				(enabled yes)
				(allow_two_segments yes)
				(prefer_zone_connections yes)
			)
		)
	)
	(footprint "antmicro-footprints:R_0402_1005Metric"
		(layer "F.Cu")
		(at 215.95 78.11)
		(descr "Resistor SMD 0402")
		(tags "resistor SMD 0402")
		(property "Reference" "R159"
			(at -1.35 1.35 0)
			(layer "F.SilkS")
			(effects
				(font
					(size 0.7 0.7)
					(thickness 0.15)
				)
				(justify left bottom)
			)
		)
		(property "Value" "R_2k2_0402"
			(at -1.011843 1.772047 0)
			(layer "F.Fab")
			(effects
				(font
					(size 0.7 0.7)
					(thickness 0.15)
				)
				(justify left bottom)
			)
		)
		(property "Datasheet" "https://www.bourns.com/docs/product-datasheets/cr.pdf"
			(at 0 0 0)
			(layer "F.Fab")
			(hide yes)
			(effects
				(font
					(size 1.27 1.27)
					(thickness 0.15)
				)
			)
		)
		(property "Author" "Antmicro"
			(at 0 0 0)
			(layer "F.Fab")
			(hide yes)
			(effects
				(font
					(size 1 1)
					(thickness 0.15)
				)
			)
		)
		(property "License" "Apache-2.0"
			(at 0 0 0)
			(layer "F.Fab")
			(hide yes)
			(effects
				(font
					(size 1 1)
					(thickness 0.15)
				)
			)
		)
		(property "MPN" "CR0402-FX-2201GLF"
			(at 0 0 0)
			(layer "F.Fab")
			(hide yes)
			(effects
				(font
					(size 1 1)
					(thickness 0.15)
				)
			)
		)
		(property "Manufacturer" "Bourns"
			(at 0 0 0)
			(layer "F.Fab")
			(hide yes)
			(effects
				(font
					(size 1 1)
					(thickness 0.15)
				)
			)
		)
		(property "Public" "False"
			(at 0 0 0)
			(layer "F.Fab")
			(hide yes)
			(effects
				(font
					(size 1 1)
					(thickness 0.15)
				)
			)
		)
		(property "Tolerance" "1%"
			(at 0 0 0)
			(layer "F.Fab")
			(hide yes)
			(effects
				(font
					(size 1 1)
					(thickness 0.15)
				)
			)
		)
		(property "Val" "2k2"
			(at 0 0 0)
			(layer "F.Fab")
			(hide yes)
			(effects
				(font
					(size 1 1)
					(thickness 0.15)
				)
			)
		)
		(sheetname "Com Express 7 MGMT")
		(sheetfile "com_express_7_mgmt.kicad_sch")
		(attr smd)
		(fp_rect
			(start -0.925 -0.47)
			(end 0.925 0.47)
			(stroke
				(width 0.05)
				(type default)
			)
			(fill no)
			(layer "F.CrtYd")
		)
		(fp_rect
			(start -0.5 -0.25)
			(end 0.5 0.25)
			(stroke
				(width 0.15)
				(type solid)
			)
			(fill no)
			(layer "F.Fab")
		)
		(pad "1" smd roundrect
			(at -0.48 0)
			(size 0.59 0.64)
			(layers "F.Cu" "F.Mask" "F.Paste")
			(roundrect_rratio 0.25)
			(net 1 "GND")
			(pintype "passive")
			(teardrops
				(best_length_ratio 0.2)
				(max_length 1)
				(best_width_ratio 0.9)
				(max_width 2)
				(curved_edges yes)
				(filter_ratio 0.9)
				(enabled yes)
				(allow_two_segments yes)
				(prefer_zone_connections yes)
			)
		)
		(pad "2" smd roundrect
			(at 0.48 0)
			(size 0.59 0.64)
			(layers "F.Cu" "F.Mask" "F.Paste")
			(roundrect_rratio 0.25)
			(net 523 "Net-(J13-Pad1)")
			(pintype "passive")
			(teardrops
				(best_length_ratio 0.2)
				(max_length 1)
				(best_width_ratio 0.9)
				(max_width 2)
				(curved_edges yes)
				(filter_ratio 0.9)
				(enabled yes)
				(allow_two_segments yes)
				(prefer_zone_connections yes)
			)
		)
	)
	(footprint "antmicro-footprints:TP_SMD_0.75mm"
		(layer "F.Cu")
		(at 128.44 128.71)
		(property "Reference" "TP94"
			(at 0.51 -3.3 90)
			(layer "F.SilkS")
			(effects
				(font
					(size 0.7 0.7)
					(thickness 0.15)
				)
				(justify left bottom)
			)
		)
		(property "Value" "TP_0.75mm_SMD"
			(at 0 1.2 0)
			(layer "F.Fab")
			(effects
				(font
					(size 0.7 0.7)
					(thickness 0.15)
				)
				(justify left bottom)
			)
		)
		(property "Author" "Antmicro"
			(at 0 0 0)
			(layer "F.Fab")
			(hide yes)
			(effects
				(font
					(size 1 1)
					(thickness 0.15)
				)
			)
		)
		(property "License" "Apache-2.0"
			(at 0 0 0)
			(layer "F.Fab")
			(hide yes)
			(effects
				(font
					(size 1 1)
					(thickness 0.15)
				)
			)
		)
		(property "MPN" ""
			(at 0 0 0)
			(layer "F.Fab")
			(hide yes)
			(effects
				(font
					(size 1 1)
					(thickness 0.15)
				)
			)
		)
		(property "Manufacturer" ""
			(at 0 0 0)
			(layer "F.Fab")
			(hide yes)
			(effects
				(font
					(size 1 1)
					(thickness 0.15)
				)
			)
		)
		(property "Public" "False"
			(at 0 0 0)
			(layer "F.Fab")
			(hide yes)
			(effects
				(font
					(size 1 1)
					(thickness 0.15)
				)
			)
		)
		(sheetname "KR to SFI #2")
		(sheetfile "kr_sfi.kicad_sch")
		(attr exclude_from_pos_files exclude_from_bom)
		(fp_circle
			(center 0 0)
			(end 0.475 0)
			(stroke
				(width 0.05)
				(type default)
			)
			(fill no)
			(layer "F.CrtYd")
		)
		(pad "1" smd circle
			(at 0 0)
			(size 0.75 0.75)
			(layers "F.Cu" "F.Mask")
			(net 757 "Net-(U45B-LOSB)")
			(pinfunction "1")
			(pintype "passive")
			(teardrops
				(best_length_ratio 0.4)
				(max_length 1)
				(best_width_ratio 0.9)
				(max_width 2)
				(curved_edges yes)
				(filter_ratio 0.9)
				(enabled yes)
				(allow_two_segments yes)
				(prefer_zone_connections yes)
			)
		)
	)
	(footprint "antmicro-footprints:SOT-23-3"
		(layer "F.Cu")
		(at 221.4985 79.51 90)
		(property "Reference" "D19"
			(at -2.7 -1.0895 180)
			(layer "F.SilkS")
			(effects
				(font
					(size 0.7 0.7)
					(thickness 0.15)
				)
				(justify left bottom)
			)
		)
		(property "Value" "BAT54C"
			(at -1.9 2.7 90)
			(layer "F.Fab")
			(effects
				(font
					(size 0.7 0.7)
					(thickness 0.15)
				)
				(justify left bottom)
			)
		)
		(property "Datasheet" "https://diotec.com/request/datasheet/bat54.pdf"
			(at 0 0 90)
			(layer "F.Fab")
			(hide yes)
			(effects
				(font
					(size 1.27 1.27)
					(thickness 0.15)
				)
			)
		)
		(property "Author" "Antmicro"
			(at 301.0085 -141.9885 0)
			(layer "F.Fab")
			(hide yes)
			(effects
				(font
					(size 1 1)
					(thickness 0.15)
				)
			)
		)
		(property "License" "Apache-2.0"
			(at 301.0085 -141.9885 0)
			(layer "F.Fab")
			(hide yes)
			(effects
				(font
					(size 1 1)
					(thickness 0.15)
				)
			)
		)
		(property "MPN" "BAT54C"
			(at 301.0085 -141.9885 0)
			(layer "F.Fab")
			(hide yes)
			(effects
				(font
					(size 1 1)
					(thickness 0.15)
				)
			)
		)
		(property "Manufacturer" "Diotec Semiconductor"
			(at 301.0085 -141.9885 0)
			(layer "F.Fab")
			(hide yes)
			(effects
				(font
					(size 1 1)
					(thickness 0.15)
				)
			)
		)
		(sheetname "Com Express 7 MGMT")
		(sheetfile "com_express_7_mgmt.kicad_sch")
		(attr smd)
		(fp_line
			(start 0.7 -1.5)
			(end -0.7 -1.5)
			(stroke
				(width 0.15)
				(type solid)
			)
			(layer "F.SilkS")
		)
		(fp_line
			(start -0.85 -1.35)
			(end -0.7 -1.5)
			(stroke
				(width 0.15)
				(type solid)
			)
			(layer "F.SilkS")
		)
		(fp_line
			(start -1.45 -1.35)
			(end -0.85 -1.35)
			(stroke
				(width 0.15)
				(type solid)
			)
			(layer "F.SilkS")
		)
		(fp_line
			(start 0.7 -0.4)
			(end 0.7 -1.5)
			(stroke
				(width 0.15)
				(type solid)
			)
			(layer "F.SilkS")
		)
		(fp_line
			(start 0.7 0.4)
			(end 0.7 1.5)
			(stroke
				(width 0.15)
				(type solid)
			)
			(layer "F.SilkS")
		)
		(fp_line
			(start 0.7 1.5)
			(end -0.7 1.5)
			(stroke
				(width 0.15)
				(type solid)
			)
			(layer "F.SilkS")
		)
		(fp_line
			(start -0.7 1.5)
			(end -0.7 1.35)
			(stroke
				(width 0.15)
				(type solid)
			)
			(layer "F.SilkS")
		)
		(fp_line
			(start 0.825 -1.6)
			(end 0.825 -0.45)
			(stroke
				(width 0.05)
				(type solid)
			)
			(layer "F.CrtYd")
		)
		(fp_line
			(start -0.9 -1.6)
			(end 0.825 -1.6)
			(stroke
				(width 0.05)
				(type solid)
			)
			(layer "F.CrtYd")
		)
		(fp_line
			(start -0.9 -1.6)
			(end -0.9 -1.4)
			(stroke
				(width 0.05)
				(type solid)
			)
			(layer "F.CrtYd")
		)
		(fp_line
			(start -0.9 -1.4)
			(end -1.75 -1.4)
			(stroke
				(width 0.05)
				(type solid)
			)
			(layer "F.CrtYd")
		)
		(fp_line
			(start -0.85 -0.5)
			(end -1.75 -0.5)
			(stroke
				(width 0.05)
				(type solid)
			)
			(layer "F.CrtYd")
		)
		(fp_line
			(start -1.75 -0.5)
			(end -1.75 -1.4)
			(stroke
				(width 0.05)
				(type solid)
			)
			(layer "F.CrtYd")
		)
		(fp_line
			(start 1.75 -0.45)
			(end 1.75 0.45)
			(stroke
				(width 0.05)
				(type solid)
			)
			(layer "F.CrtYd")
		)
		(fp_line
			(start 0.825 -0.45)
			(end 1.75 -0.45)
			(stroke
				(width 0.05)
				(type solid)
			)
			(layer "F.CrtYd")
		)
		(fp_line
			(start 1.75 0.45)
			(end 0.85 0.45)
			(stroke
				(width 0.05)
				(type solid)
			)
			(layer "F.CrtYd")
		)
		(fp_line
			(start 0.85 0.45)
			(end 0.85 1.65)
			(stroke
				(width 0.05)
				(type solid)
			)
			(layer "F.CrtYd")
		)
		(fp_line
			(start -0.85 0.5)
			(end -0.85 -0.5)
			(stroke
				(width 0.05)
				(type solid)
			)
			(layer "F.CrtYd")
		)
		(fp_line
			(start -1.75 0.5)
			(end -0.85 0.5)
			(stroke
				(width 0.05)
				(type solid)
			)
			(layer "F.CrtYd")
		)
		(fp_line
			(start -0.85 1.4)
			(end -1.75 1.4)
			(stroke
				(width 0.05)
				(type solid)
			)
			(layer "F.CrtYd")
		)
		(fp_line
			(start -1.75 1.4)
			(end -1.75 0.5)
			(stroke
				(width 0.05)
				(type solid)
			)
			(layer "F.CrtYd")
		)
		(fp_line
			(start 0.85 1.65)
			(end -0.85 1.65)
			(stroke
				(width 0.05)
				(type solid)
			)
			(layer "F.CrtYd")
		)
		(fp_line
			(start -0.85 1.65)
			(end -0.85 1.4)
			(stroke
				(width 0.05)
				(type solid)
			)
			(layer "F.CrtYd")
		)
		(fp_line
			(start -0.437 -1.526)
			(end 0.688 -1.526)
			(stroke
				(width 0.15)
				(type solid)
			)
			(layer "F.Fab")
		)
		(fp_line
			(start -0.437 -1.526)
			(end -0.712 -1.325)
			(stroke
				(width 0.15)
				(type solid)
			)
			(layer "F.Fab")
		)
		(fp_line
			(start -0.712 -1.325)
			(end -0.712 1.523)
			(stroke
				(width 0.15)
				(type solid)
			)
			(layer "F.Fab")
		)
		(fp_line
			(start 0.688 1.519)
			(end 0.688 -1.52)
			(stroke
				(width 0.15)
				(type solid)
			)
			(layer "F.Fab")
		)
		(fp_line
			(start -0.712 1.519)
			(end 0.688 1.519)
			(stroke
				(width 0.15)
				(type solid)
			)
			(layer "F.Fab")
		)
		(pad "1" smd roundrect
			(at -1.1 -0.951 90)
			(size 1 0.6)
			(layers "F.Cu" "F.Mask" "F.Paste")
			(roundrect_rratio 0.15)
			(net 73 "+3V3_AON")
			(pinfunction "1")
			(pintype "passive")
			(teardrops
				(best_length_ratio 0.2)
				(max_length 1)
				(best_width_ratio 0.9)
				(max_width 2)
				(curved_edges yes)
				(filter_ratio 0.9)
				(enabled yes)
				(allow_two_segments yes)
				(prefer_zone_connections yes)
			)
		)
		(pad "2" smd roundrect
			(at -1.1 0.949 90)
			(size 1 0.6)
			(layers "F.Cu" "F.Mask" "F.Paste")
			(roundrect_rratio 0.15)
			(net 73 "+3V3_AON")
			(pinfunction "2")
			(pintype "passive")
			(teardrops
				(best_length_ratio 0.2)
				(max_length 1)
				(best_width_ratio 0.9)
				(max_width 2)
				(curved_edges yes)
				(filter_ratio 0.9)
				(enabled yes)
				(allow_two_segments yes)
				(prefer_zone_connections yes)
			)
		)
		(pad "3" smd roundrect
			(at 1.1 -0.0005 90)
			(size 1 0.6)
			(layers "F.Cu" "F.Mask" "F.Paste")
			(roundrect_rratio 0.15)
			(net 135 "Net-(D19-Pad3)")
			(pinfunction "3")
			(pintype "passive")
			(teardrops
				(best_length_ratio 0.2)
				(max_length 1)
				(best_width_ratio 0.9)
				(max_width 2)
				(curved_edges yes)
				(filter_ratio 0.9)
				(enabled yes)
				(allow_two_segments yes)
				(prefer_zone_connections yes)
			)
		)
	)
	(footprint "antmicro-footprints:R_0402_1005Metric"
		(layer "F.Cu")
		(at 178.4 147 180)
		(descr "Resistor SMD 0402")
		(tags "resistor SMD 0402")
		(property "Reference" "R38"
			(at -2.95 -0.45 0)
			(layer "F.SilkS")
			(effects
				(font
					(size 0.7 0.7)
					(thickness 0.15)
				)
				(justify right bottom)
			)
		)
		(property "Value" "R_0R_0402"
			(at -1.011843 1.772046 0)
			(layer "F.Fab")
			(effects
				(font
					(size 0.7 0.7)
					(thickness 0.15)
				)
				(justify right bottom)
			)
		)
		(property "Datasheet" "https://industrial.panasonic.com/cdbs/www-data/pdf/RDA0000/AOA0000C301.pdf"
			(at 0 0 0)
			(layer "F.Fab")
			(hide yes)
			(effects
				(font
					(size 1.27 1.27)
					(thickness 0.15)
				)
			)
		)
		(property "Author" "Antmicro"
			(at 337.9 338.52 0)
			(layer "F.Fab")
			(hide yes)
			(effects
				(font
					(size 1 1)
					(thickness 0.15)
				)
			)
		)
		(property "Current" "1A"
			(at 337.9 338.52 0)
			(layer "F.Fab")
			(hide yes)
			(effects
				(font
					(size 1 1)
					(thickness 0.15)
				)
			)
		)
		(property "License" "Apache-2.0"
			(at 337.9 338.52 0)
			(layer "F.Fab")
			(hide yes)
			(effects
				(font
					(size 1 1)
					(thickness 0.15)
				)
			)
		)
		(property "MPN" "ERJ2GE0R00X"
			(at 337.9 338.52 0)
			(layer "F.Fab")
			(hide yes)
			(effects
				(font
					(size 1 1)
					(thickness 0.15)
				)
			)
		)
		(property "Manufacturer" "Panasonic"
			(at 337.9 338.52 0)
			(layer "F.Fab")
			(hide yes)
			(effects
				(font
					(size 1 1)
					(thickness 0.15)
				)
			)
		)
		(property "Public" "False"
			(at 337.9 338.52 0)
			(layer "F.Fab")
			(hide yes)
			(effects
				(font
					(size 1 1)
					(thickness 0.15)
				)
			)
		)
		(property "Tolerance" ""
			(at 337.9 338.52 0)
			(layer "F.Fab")
			(hide yes)
			(effects
				(font
					(size 1 1)
					(thickness 0.15)
				)
			)
		)
		(property "Val" "0R"
			(at 337.9 338.52 0)
			(layer "F.Fab")
			(hide yes)
			(effects
				(font
					(size 1 1)
					(thickness 0.15)
				)
			)
		)
		(sheetname "2xSFP+")
		(sheetfile "2xSFP+.kicad_sch")
		(attr smd)
		(fp_rect
			(start -0.925 -0.47)
			(end 0.925 0.47)
			(stroke
				(width 0.05)
				(type default)
			)
			(fill no)
			(layer "F.CrtYd")
		)
		(fp_rect
			(start -0.5 -0.25)
			(end 0.5 0.25)
			(stroke
				(width 0.15)
				(type solid)
			)
			(fill no)
			(layer "F.Fab")
		)
		(pad "1" smd roundrect
			(at -0.48 0 180)
			(size 0.59 0.64)
			(layers "F.Cu" "F.Mask" "F.Paste")
			(roundrect_rratio 0.25)
			(net 488 "/2xSFP+/I2C_{SFP0}.SCL")
			(pintype "passive")
			(teardrops
				(best_length_ratio 0.2)
				(max_length 1)
				(best_width_ratio 0.9)
				(max_width 2)
				(curved_edges yes)
				(filter_ratio 0.9)
				(enabled yes)
				(allow_two_segments yes)
				(prefer_zone_connections yes)
			)
		)
		(pad "2" smd roundrect
			(at 0.48 0 180)
			(size 0.59 0.64)
			(layers "F.Cu" "F.Mask" "F.Paste")
			(roundrect_rratio 0.25)
			(net 165 "/2xSFP+/SCL0")
			(pintype "passive")
			(teardrops
				(best_length_ratio 0.2)
				(max_length 1)
				(best_width_ratio 0.9)
				(max_width 2)
				(curved_edges yes)
				(filter_ratio 0.9)
				(enabled yes)
				(allow_two_segments yes)
				(prefer_zone_connections yes)
			)
		)
	)
	(footprint "antmicro-footprints:R_0402_1005Metric"
		(layer "F.Cu")
		(at 178.35 103.87 90)
		(descr "Resistor SMD 0402")
		(tags "resistor SMD 0402")
		(property "Reference" "R121"
			(at 0.81 0.45 90)
			(layer "F.SilkS")
			(effects
				(font
					(size 0.7 0.7)
					(thickness 0.15)
				)
				(justify left bottom)
			)
		)
		(property "Value" "R_10k_0402"
			(at -1.011843 1.772047 90)
			(layer "F.Fab")
			(effects
				(font
					(size 0.7 0.7)
					(thickness 0.15)
				)
				(justify left bottom)
			)
		)
		(property "Datasheet" "https://www.bourns.com/docs/product-datasheets/cr.pdf"
			(at 0 0 90)
			(layer "F.Fab")
			(hide yes)
			(effects
				(font
					(size 1.27 1.27)
					(thickness 0.15)
				)
			)
		)
		(property "Author" "Antmicro"
			(at 282.22 -74.48 0)
			(layer "F.Fab")
			(hide yes)
			(effects
				(font
					(size 1 1)
					(thickness 0.15)
				)
			)
		)
		(property "License" "Apache-2.0"
			(at 282.22 -74.48 0)
			(layer "F.Fab")
			(hide yes)
			(effects
				(font
					(size 1 1)
					(thickness 0.15)
				)
			)
		)
		(property "MPN" "CR0402-FX-1002GLF"
			(at 282.22 -74.48 0)
			(layer "F.Fab")
			(hide yes)
			(effects
				(font
					(size 1 1)
					(thickness 0.15)
				)
			)
		)
		(property "Manufacturer" "Bourns"
			(at 282.22 -74.48 0)
			(layer "F.Fab")
			(hide yes)
			(effects
				(font
					(size 1 1)
					(thickness 0.15)
				)
			)
		)
		(property "Public" "False"
			(at 282.22 -74.48 0)
			(layer "F.Fab")
			(hide yes)
			(effects
				(font
					(size 1 1)
					(thickness 0.15)
				)
			)
		)
		(property "Tolerance" "1%"
			(at 282.22 -74.48 0)
			(layer "F.Fab")
			(hide yes)
			(effects
				(font
					(size 1 1)
					(thickness 0.15)
				)
			)
		)
		(property "Val" "10k"
			(at 282.22 -74.48 0)
			(layer "F.Fab")
			(hide yes)
			(effects
				(font
					(size 1 1)
					(thickness 0.15)
				)
			)
		)
		(sheetname "M.2 key M #1")
		(sheetfile "m2keym_low.kicad_sch")
		(attr smd dnp)
		(fp_rect
			(start -0.925 -0.47)
			(end 0.925 0.47)
			(stroke
				(width 0.05)
				(type default)
			)
			(fill no)
			(layer "F.CrtYd")
		)
		(fp_rect
			(start -0.5 -0.25)
			(end 0.5 0.25)
			(stroke
				(width 0.15)
				(type solid)
			)
			(fill no)
			(layer "F.Fab")
		)
		(pad "1" smd roundrect
			(at -0.48 0 90)
			(size 0.59 0.64)
			(layers "F.Cu" "F.Mask" "F.Paste")
			(roundrect_rratio 0.25)
			(net 228 "/M.2 key M #1/~{PERST_D}")
			(pintype "passive")
			(teardrops
				(best_length_ratio 0.2)
				(max_length 1)
				(best_width_ratio 0.9)
				(max_width 2)
				(curved_edges yes)
				(filter_ratio 0.9)
				(enabled yes)
				(allow_two_segments yes)
				(prefer_zone_connections yes)
			)
		)
		(pad "2" smd roundrect
			(at 0.48 0 90)
			(size 0.59 0.64)
			(layers "F.Cu" "F.Mask" "F.Paste")
			(roundrect_rratio 0.25)
			(net 2 "+3V3")
			(pintype "passive")
			(teardrops
				(best_length_ratio 0.2)
				(max_length 1)
				(best_width_ratio 0.9)
				(max_width 2)
				(curved_edges yes)
				(filter_ratio 0.9)
				(enabled yes)
				(allow_two_segments yes)
				(prefer_zone_connections yes)
			)
		)
	)
	(footprint "antmicro-footprints:R_0402_1005Metric"
		(layer "F.Cu")
		(at 178.4 145 180)
		(descr "Resistor SMD 0402")
		(tags "resistor SMD 0402")
		(property "Reference" "R39"
			(at -2.95 -0.45 0)
			(layer "F.SilkS")
			(effects
				(font
					(size 0.7 0.7)
					(thickness 0.15)
				)
				(justify right bottom)
			)
		)
		(property "Value" "R_0R_0402"
			(at -1.011843 1.772046 0)
			(layer "F.Fab")
			(effects
				(font
					(size 0.7 0.7)
					(thickness 0.15)
				)
				(justify right bottom)
			)
		)
		(property "Datasheet" "https://industrial.panasonic.com/cdbs/www-data/pdf/RDA0000/AOA0000C301.pdf"
			(at 0 0 0)
			(layer "F.Fab")
			(hide yes)
			(effects
				(font
					(size 1.27 1.27)
					(thickness 0.15)
				)
			)
		)
		(property "Author" "Antmicro"
			(at 337.899999 332.52 0)
			(layer "F.Fab")
			(hide yes)
			(effects
				(font
					(size 1 1)
					(thickness 0.15)
				)
			)
		)
		(property "Current" "1A"
			(at 337.899999 332.52 0)
			(layer "F.Fab")
			(hide yes)
			(effects
				(font
					(size 1 1)
					(thickness 0.15)
				)
			)
		)
		(property "License" "Apache-2.0"
			(at 337.899999 332.52 0)
			(layer "F.Fab")
			(hide yes)
			(effects
				(font
					(size 1 1)
					(thickness 0.15)
				)
			)
		)
		(property "MPN" "ERJ2GE0R00X"
			(at 337.899999 332.52 0)
			(layer "F.Fab")
			(hide yes)
			(effects
				(font
					(size 1 1)
					(thickness 0.15)
				)
			)
		)
		(property "Manufacturer" "Panasonic"
			(at 337.899999 332.52 0)
			(layer "F.Fab")
			(hide yes)
			(effects
				(font
					(size 1 1)
					(thickness 0.15)
				)
			)
		)
		(property "Public" "False"
			(at 337.899999 332.52 0)
			(layer "F.Fab")
			(hide yes)
			(effects
				(font
					(size 1 1)
					(thickness 0.15)
				)
			)
		)
		(property "Tolerance" ""
			(at 337.899999 332.52 0)
			(layer "F.Fab")
			(hide yes)
			(effects
				(font
					(size 1 1)
					(thickness 0.15)
				)
			)
		)
		(property "Val" "0R"
			(at 337.899999 332.52 0)
			(layer "F.Fab")
			(hide yes)
			(effects
				(font
					(size 1 1)
					(thickness 0.15)
				)
			)
		)
		(sheetname "2xSFP+")
		(sheetfile "2xSFP+.kicad_sch")
		(attr smd)
		(fp_rect
			(start -0.925 -0.47)
			(end 0.925 0.47)
			(stroke
				(width 0.05)
				(type default)
			)
			(fill no)
			(layer "F.CrtYd")
		)
		(fp_rect
			(start -0.5 -0.25)
			(end 0.5 0.25)
			(stroke
				(width 0.15)
				(type solid)
			)
			(fill no)
			(layer "F.Fab")
		)
		(pad "1" smd roundrect
			(at -0.48 0 180)
			(size 0.59 0.64)
			(layers "F.Cu" "F.Mask" "F.Paste")
			(roundrect_rratio 0.25)
			(net 431 "/2xSFP+/MOD0_ABS")
			(pintype "passive")
			(teardrops
				(best_length_ratio 0.2)
				(max_length 1)
				(best_width_ratio 0.9)
				(max_width 2)
				(curved_edges yes)
				(filter_ratio 0.9)
				(enabled yes)
				(allow_two_segments yes)
				(prefer_zone_connections yes)
			)
		)
		(pad "2" smd roundrect
			(at 0.48 0 180)
			(size 0.59 0.64)
			(layers "F.Cu" "F.Mask" "F.Paste")
			(roundrect_rratio 0.25)
			(net 166 "Net-(J2A-MOD_{ABS})")
			(pintype "passive")
			(teardrops
				(best_length_ratio 0.2)
				(max_length 1)
				(best_width_ratio 0.9)
				(max_width 2)
				(curved_edges yes)
				(filter_ratio 0.9)
				(enabled yes)
				(allow_two_segments yes)
				(prefer_zone_connections yes)
			)
		)
	)
	(footprint "antmicro-footprints:R_0402_1005Metric"
		(layer "F.Cu")
		(at 114.4 144.36 90)
		(descr "Resistor SMD 0402")
		(tags "resistor SMD 0402")
		(property "Reference" "R212"
			(at 0.8 0.4 90)
			(layer "F.SilkS")
			(effects
				(font
					(size 0.7 0.7)
					(thickness 0.15)
				)
				(justify left bottom)
			)
		)
		(property "Value" "R_1k_0402"
			(at -1.011843 1.772047 90)
			(layer "F.Fab")
			(effects
				(font
					(size 0.7 0.7)
					(thickness 0.15)
				)
				(justify left bottom)
			)
		)
		(property "Datasheet" "https://www.bourns.com/docs/product-datasheets/cr.pdf"
			(at 0 0 90)
			(layer "F.Fab")
			(hide yes)
			(effects
				(font
					(size 1.27 1.27)
					(thickness 0.15)
				)
			)
		)
		(property "Author" "Antmicro"
			(at 258.76 29.96 0)
			(layer "F.Fab")
			(hide yes)
			(effects
				(font
					(size 1 1)
					(thickness 0.15)
				)
			)
		)
		(property "License" "Apache-2.0"
			(at 258.76 29.96 0)
			(layer "F.Fab")
			(hide yes)
			(effects
				(font
					(size 1 1)
					(thickness 0.15)
				)
			)
		)
		(property "MPN" "CR0402-FX-1001GLF"
			(at 258.76 29.96 0)
			(layer "F.Fab")
			(hide yes)
			(effects
				(font
					(size 1 1)
					(thickness 0.15)
				)
			)
		)
		(property "Manufacturer" "Bourns"
			(at 258.76 29.96 0)
			(layer "F.Fab")
			(hide yes)
			(effects
				(font
					(size 1 1)
					(thickness 0.15)
				)
			)
		)
		(property "Public" "False"
			(at 258.76 29.96 0)
			(layer "F.Fab")
			(hide yes)
			(effects
				(font
					(size 1 1)
					(thickness 0.15)
				)
			)
		)
		(property "Tolerance" "1%"
			(at 258.76 29.96 0)
			(layer "F.Fab")
			(hide yes)
			(effects
				(font
					(size 1 1)
					(thickness 0.15)
				)
			)
		)
		(property "Val" "1k"
			(at 258.76 29.96 0)
			(layer "F.Fab")
			(hide yes)
			(effects
				(font
					(size 1 1)
					(thickness 0.15)
				)
			)
		)
		(sheetname "PCIe redriver")
		(sheetfile "pcie_redriver.kicad_sch")
		(attr smd)
		(fp_rect
			(start -0.925 -0.47)
			(end 0.925 0.47)
			(stroke
				(width 0.05)
				(type default)
			)
			(fill no)
			(layer "F.CrtYd")
		)
		(fp_rect
			(start -0.5 -0.25)
			(end 0.5 0.25)
			(stroke
				(width 0.15)
				(type solid)
			)
			(fill no)
			(layer "F.Fab")
		)
		(pad "1" smd roundrect
			(at -0.48 0 90)
			(size 0.59 0.64)
			(layers "F.Cu" "F.Mask" "F.Paste")
			(roundrect_rratio 0.25)
			(net 2 "+3V3")
			(pintype "passive")
			(teardrops
				(best_length_ratio 0.2)
				(max_length 1)
				(best_width_ratio 0.9)
				(max_width 2)
				(curved_edges yes)
				(filter_ratio 0.9)
				(enabled yes)
				(allow_two_segments yes)
				(prefer_zone_connections yes)
			)
		)
		(pad "2" smd roundrect
			(at 0.48 0 90)
			(size 0.59 0.64)
			(layers "F.Cu" "F.Mask" "F.Paste")
			(roundrect_rratio 0.25)
			(net 628 "/PCIe redriver/TX_SW")
			(pintype "passive")
			(teardrops
				(best_length_ratio 0.2)
				(max_length 1)
				(best_width_ratio 0.9)
				(max_width 2)
				(curved_edges yes)
				(filter_ratio 0.9)
				(enabled yes)
				(allow_two_segments yes)
				(prefer_zone_connections yes)
			)
		)
	)
	(footprint "antmicro-footprints:R_0402_1005Metric"
		(layer "F.Cu")
		(at 191.469122 140.186326 -135)
		(descr "Resistor SMD 0402")
		(tags "resistor SMD 0402")
		(property "Reference" "R229"
			(at 1.069206 -0.415818 45)
			(layer "F.SilkS")
			(effects
				(font
					(size 0.7 0.7)
					(thickness 0.15)
				)
				(justify right bottom)
			)
		)
		(property "Value" "R_1k_0402"
			(at -1.011843 1.772046 45)
			(layer "F.Fab")
			(effects
				(font
					(size 0.7 0.7)
					(thickness 0.15)
				)
				(justify right bottom)
			)
		)
		(property "Datasheet" "https://www.bourns.com/docs/product-datasheets/cr.pdf"
			(at 0 0 45)
			(layer "B.Fab")
			(hide yes)
			(effects
				(font
					(size 1.27 1.27)
					(thickness 0.15)
				)
				(justify mirror)
			)
		)
		(property "Author" "Antmicro"
			(at 0 0 45)
			(layer "F.Fab")
			(hide yes)
			(effects
				(font
					(size 1 1)
					(thickness 0.15)
				)
			)
		)
		(property "License" "Apache-2.0"
			(at 0 0 45)
			(layer "F.Fab")
			(hide yes)
			(effects
				(font
					(size 1 1)
					(thickness 0.15)
				)
			)
		)
		(property "MPN" "CR0402-FX-1001GLF"
			(at 0 0 45)
			(layer "F.Fab")
			(hide yes)
			(effects
				(font
					(size 1 1)
					(thickness 0.15)
				)
			)
		)
		(property "Manufacturer" "Bourns"
			(at 0 0 45)
			(layer "F.Fab")
			(hide yes)
			(effects
				(font
					(size 1 1)
					(thickness 0.15)
				)
			)
		)
		(property "Public" "False"
			(at 0 0 45)
			(layer "F.Fab")
			(hide yes)
			(effects
				(font
					(size 1 1)
					(thickness 0.15)
				)
			)
		)
		(property "Tolerance" "1%"
			(at 0 0 45)
			(layer "F.Fab")
			(hide yes)
			(effects
				(font
					(size 1 1)
					(thickness 0.15)
				)
			)
		)
		(property "Val" "1k"
			(at 0 0 45)
			(layer "F.Fab")
			(hide yes)
			(effects
				(font
					(size 1 1)
					(thickness 0.15)
				)
			)
		)
		(sheetname "PCIe redriver")
		(sheetfile "pcie_redriver.kicad_sch")
		(attr smd)
		(fp_poly
			(pts
				(xy -0.925 -0.47) (xy 0.925 -0.47) (xy 0.925 0.47) (xy -0.925 0.47)
			)
			(stroke
				(width 0.05)
				(type default)
			)
			(fill no)
			(layer "F.CrtYd")
		)
		(fp_poly
			(pts
				(xy -0.5 -0.25) (xy 0.5 -0.25) (xy 0.5 0.25) (xy -0.5 0.25)
			)
			(stroke
				(width 0.15)
				(type solid)
			)
			(fill no)
			(layer "F.Fab")
		)
		(pad "1" smd roundrect
			(at -0.48 0 225)
			(size 0.59 0.64)
			(layers "F.Cu" "F.Mask" "F.Paste")
			(roundrect_rratio 0.25)
			(net 2 "+3V3")
			(pintype "passive")
			(teardrops
				(best_length_ratio 0.2)
				(max_length 1)
				(best_width_ratio 0.9)
				(max_width 2)
				(curved_edges yes)
				(filter_ratio 0.9)
				(enabled yes)
				(allow_two_segments yes)
				(prefer_zone_connections yes)
			)
		)
		(pad "2" smd roundrect
			(at 0.48 0 225)
			(size 0.59 0.64)
			(layers "F.Cu" "F.Mask" "F.Paste")
			(roundrect_rratio 0.25)
			(net 978 "/PCIe redriver/RX_EQ0")
			(pintype "passive")
			(teardrops
				(best_length_ratio 0.2)
				(max_length 1)
				(best_width_ratio 0.9)
				(max_width 2)
				(curved_edges yes)
				(filter_ratio 0.9)
				(enabled yes)
				(allow_two_segments yes)
				(prefer_zone_connections yes)
			)
		)
	)
	(footprint "antmicro-footprints:TP_SMD_0.75mm"
		(layer "F.Cu")
		(at 153.1 128.71)
		(property "Reference" "TP59"
			(at 0.4 -3.3 90)
			(layer "F.SilkS")
			(effects
				(font
					(size 0.7 0.7)
					(thickness 0.15)
				)
				(justify left bottom)
			)
		)
		(property "Value" "TP_0.75mm_SMD"
			(at 0 1.2 0)
			(layer "F.Fab")
			(effects
				(font
					(size 0.7 0.7)
					(thickness 0.15)
				)
				(justify left bottom)
			)
		)
		(property "Author" "Antmicro"
			(at 0 0 0)
			(layer "F.Fab")
			(hide yes)
			(effects
				(font
					(size 1 1)
					(thickness 0.15)
				)
			)
		)
		(property "License" "Apache-2.0"
			(at 0 0 0)
			(layer "F.Fab")
			(hide yes)
			(effects
				(font
					(size 1 1)
					(thickness 0.15)
				)
			)
		)
		(property "MPN" ""
			(at 0 0 0)
			(layer "F.Fab")
			(hide yes)
			(effects
				(font
					(size 1 1)
					(thickness 0.15)
				)
			)
		)
		(property "Manufacturer" ""
			(at 0 0 0)
			(layer "F.Fab")
			(hide yes)
			(effects
				(font
					(size 1 1)
					(thickness 0.15)
				)
			)
		)
		(property "Public" "False"
			(at 0 0 0)
			(layer "F.Fab")
			(hide yes)
			(effects
				(font
					(size 1 1)
					(thickness 0.15)
				)
			)
		)
		(sheetname "KR to SFI #1")
		(sheetfile "kr_sfi.kicad_sch")
		(attr exclude_from_pos_files exclude_from_bom)
		(fp_circle
			(center 0 0)
			(end 0.475 0)
			(stroke
				(width 0.05)
				(type default)
			)
			(fill no)
			(layer "F.CrtYd")
		)
		(pad "1" smd circle
			(at 0 0)
			(size 0.75 0.75)
			(layers "F.Cu" "F.Mask")
			(net 722 "/2xSFP+/KR to SFI #1/TDI")
			(pinfunction "1")
			(pintype "passive")
			(teardrops
				(best_length_ratio 0.4)
				(max_length 1)
				(best_width_ratio 0.9)
				(max_width 2)
				(curved_edges yes)
				(filter_ratio 0.9)
				(enabled yes)
				(allow_two_segments yes)
				(prefer_zone_connections yes)
			)
		)
	)
	(footprint "antmicro-footprints:SOT-23-3"
		(layer "F.Cu")
		(at 202.45 80.75 90)
		(property "Reference" "Q13"
			(at -1.2 2.65 90)
			(layer "F.SilkS")
			(effects
				(font
					(size 0.7 0.7)
					(thickness 0.15)
				)
				(justify left bottom)
			)
		)
		(property "Value" "MMBT3904LT1G"
			(at -1.9 2.7 90)
			(layer "F.Fab")
			(effects
				(font
					(size 0.7 0.7)
					(thickness 0.15)
				)
				(justify left bottom)
			)
		)
		(property "Datasheet" "https://eu.mouser.com/datasheet/2/308/1/MMBT3904LT1_D-2316262.pdf"
			(at 0 0 90)
			(layer "F.Fab")
			(hide yes)
			(effects
				(font
					(size 1.27 1.27)
					(thickness 0.15)
				)
			)
		)
		(property "Author" "Antmicro"
			(at 279.335773 -117.971447 0)
			(layer "F.Fab")
			(hide yes)
			(effects
				(font
					(size 1 1)
					(thickness 0.15)
				)
			)
		)
		(property "License" "Apache-2.0"
			(at 279.335773 -117.971447 0)
			(layer "F.Fab")
			(hide yes)
			(effects
				(font
					(size 1 1)
					(thickness 0.15)
				)
			)
		)
		(property "MPN" "MMBT3904LT1G"
			(at 279.335773 -117.971447 0)
			(layer "F.Fab")
			(hide yes)
			(effects
				(font
					(size 1 1)
					(thickness 0.15)
				)
			)
		)
		(property "Manufacturer" "Onsemi"
			(at 279.335773 -117.971447 0)
			(layer "F.Fab")
			(hide yes)
			(effects
				(font
					(size 1 1)
					(thickness 0.15)
				)
			)
		)
		(property "Public" "False"
			(at 279.335773 -117.971447 0)
			(layer "F.Fab")
			(hide yes)
			(effects
				(font
					(size 1 1)
					(thickness 0.15)
				)
			)
		)
		(property ki_fp_filters "SOT?323*")
		(sheetname "Power")
		(sheetfile "power.kicad_sch")
		(attr smd)
		(fp_line
			(start 0.7 -1.5)
			(end -0.7 -1.5)
			(stroke
				(width 0.15)
				(type solid)
			)
			(layer "F.SilkS")
		)
		(fp_line
			(start -0.85 -1.35)
			(end -0.7 -1.5)
			(stroke
				(width 0.15)
				(type solid)
			)
			(layer "F.SilkS")
		)
		(fp_line
			(start -1.45 -1.35)
			(end -0.85 -1.35)
			(stroke
				(width 0.15)
				(type solid)
			)
			(layer "F.SilkS")
		)
		(fp_line
			(start 0.7 -0.4)
			(end 0.7 -1.5)
			(stroke
				(width 0.15)
				(type solid)
			)
			(layer "F.SilkS")
		)
		(fp_line
			(start 0.7 0.4)
			(end 0.7 1.5)
			(stroke
				(width 0.15)
				(type solid)
			)
			(layer "F.SilkS")
		)
		(fp_line
			(start 0.7 1.5)
			(end -0.7 1.5)
			(stroke
				(width 0.15)
				(type solid)
			)
			(layer "F.SilkS")
		)
		(fp_line
			(start -0.7 1.5)
			(end -0.7 1.35)
			(stroke
				(width 0.15)
				(type solid)
			)
			(layer "F.SilkS")
		)
		(fp_line
			(start 0.825 -1.6)
			(end 0.825 -0.45)
			(stroke
				(width 0.05)
				(type solid)
			)
			(layer "F.CrtYd")
		)
		(fp_line
			(start -0.9 -1.6)
			(end 0.825 -1.6)
			(stroke
				(width 0.05)
				(type solid)
			)
			(layer "F.CrtYd")
		)
		(fp_line
			(start -0.9 -1.6)
			(end -0.9 -1.4)
			(stroke
				(width 0.05)
				(type solid)
			)
			(layer "F.CrtYd")
		)
		(fp_line
			(start -0.9 -1.4)
			(end -1.75 -1.4)
			(stroke
				(width 0.05)
				(type solid)
			)
			(layer "F.CrtYd")
		)
		(fp_line
			(start -0.85 -0.5)
			(end -1.75 -0.5)
			(stroke
				(width 0.05)
				(type solid)
			)
			(layer "F.CrtYd")
		)
		(fp_line
			(start -1.75 -0.5)
			(end -1.75 -1.4)
			(stroke
				(width 0.05)
				(type solid)
			)
			(layer "F.CrtYd")
		)
		(fp_line
			(start 1.75 -0.45)
			(end 1.75 0.45)
			(stroke
				(width 0.05)
				(type solid)
			)
			(layer "F.CrtYd")
		)
		(fp_line
			(start 0.825 -0.45)
			(end 1.75 -0.45)
			(stroke
				(width 0.05)
				(type solid)
			)
			(layer "F.CrtYd")
		)
		(fp_line
			(start 1.75 0.45)
			(end 0.85 0.45)
			(stroke
				(width 0.05)
				(type solid)
			)
			(layer "F.CrtYd")
		)
		(fp_line
			(start 0.85 0.45)
			(end 0.85 1.65)
			(stroke
				(width 0.05)
				(type solid)
			)
			(layer "F.CrtYd")
		)
		(fp_line
			(start -0.85 0.5)
			(end -0.85 -0.5)
			(stroke
				(width 0.05)
				(type solid)
			)
			(layer "F.CrtYd")
		)
		(fp_line
			(start -1.75 0.5)
			(end -0.85 0.5)
			(stroke
				(width 0.05)
				(type solid)
			)
			(layer "F.CrtYd")
		)
		(fp_line
			(start -0.85 1.4)
			(end -1.75 1.4)
			(stroke
				(width 0.05)
				(type solid)
			)
			(layer "F.CrtYd")
		)
		(fp_line
			(start -1.75 1.4)
			(end -1.75 0.5)
			(stroke
				(width 0.05)
				(type solid)
			)
			(layer "F.CrtYd")
		)
		(fp_line
			(start 0.85 1.65)
			(end -0.85 1.65)
			(stroke
				(width 0.05)
				(type solid)
			)
			(layer "F.CrtYd")
		)
		(fp_line
			(start -0.85 1.65)
			(end -0.85 1.4)
			(stroke
				(width 0.05)
				(type solid)
			)
			(layer "F.CrtYd")
		)
		(fp_line
			(start -0.437 -1.526)
			(end 0.688 -1.526)
			(stroke
				(width 0.15)
				(type solid)
			)
			(layer "F.Fab")
		)
		(fp_line
			(start -0.437 -1.526)
			(end -0.712 -1.325)
			(stroke
				(width 0.15)
				(type solid)
			)
			(layer "F.Fab")
		)
		(fp_line
			(start -0.712 -1.325)
			(end -0.712 1.523)
			(stroke
				(width 0.15)
				(type solid)
			)
			(layer "F.Fab")
		)
		(fp_line
			(start 0.688 1.519)
			(end 0.688 -1.52)
			(stroke
				(width 0.15)
				(type solid)
			)
			(layer "F.Fab")
		)
		(fp_line
			(start -0.712 1.519)
			(end 0.688 1.519)
			(stroke
				(width 0.15)
				(type solid)
			)
			(layer "F.Fab")
		)
		(pad "1" smd roundrect
			(at -1.1 -0.951 90)
			(size 1 0.6)
			(layers "F.Cu" "F.Mask" "F.Paste")
			(roundrect_rratio 0.15)
			(net 987 "Net-(Q13-B)")
			(pinfunction "B")
			(pintype "input")
			(teardrops
				(best_length_ratio 0.2)
				(max_length 1)
				(best_width_ratio 0.9)
				(max_width 2)
				(curved_edges yes)
				(filter_ratio 0.9)
				(enabled yes)
				(allow_two_segments yes)
				(prefer_zone_connections yes)
			)
		)
		(pad "2" smd roundrect
			(at -1.1 0.949 90)
			(size 1 0.6)
			(layers "F.Cu" "F.Mask" "F.Paste")
			(roundrect_rratio 0.15)
			(net 1 "GND")
			(pinfunction "E")
			(pintype "passive")
			(teardrops
				(best_length_ratio 0.2)
				(max_length 1)
				(best_width_ratio 0.9)
				(max_width 2)
				(curved_edges yes)
				(filter_ratio 0.9)
				(enabled yes)
				(allow_two_segments yes)
				(prefer_zone_connections yes)
			)
		)
		(pad "3" smd roundrect
			(at 1.1 -0.0005 90)
			(size 1 0.6)
			(layers "F.Cu" "F.Mask" "F.Paste")
			(roundrect_rratio 0.15)
			(net 988 "Net-(Q13-C)")
			(pinfunction "C")
			(pintype "passive")
			(teardrops
				(best_length_ratio 0.2)
				(max_length 1)
				(best_width_ratio 0.9)
				(max_width 2)
				(curved_edges yes)
				(filter_ratio 0.9)
				(enabled yes)
				(allow_two_segments yes)
				(prefer_zone_connections yes)
			)
		)
	)
	(footprint "antmicro-footprints:TP_SMD_0.75mm"
		(layer "F.Cu")
		(at 145.3 128.71)
		(property "Reference" "TP57"
			(at 0.4 -3.3 90)
			(layer "F.SilkS")
			(effects
				(font
					(size 0.7 0.7)
					(thickness 0.15)
				)
				(justify left bottom)
			)
		)
		(property "Value" "TP_0.75mm_SMD"
			(at 0 1.2 0)
			(layer "F.Fab")
			(effects
				(font
					(size 0.7 0.7)
					(thickness 0.15)
				)
				(justify left bottom)
			)
		)
		(property "Author" "Antmicro"
			(at 0 0 0)
			(layer "F.Fab")
			(hide yes)
			(effects
				(font
					(size 1 1)
					(thickness 0.15)
				)
			)
		)
		(property "License" "Apache-2.0"
			(at 0 0 0)
			(layer "F.Fab")
			(hide yes)
			(effects
				(font
					(size 1 1)
					(thickness 0.15)
				)
			)
		)
		(property "MPN" ""
			(at 0 0 0)
			(layer "F.Fab")
			(hide yes)
			(effects
				(font
					(size 1 1)
					(thickness 0.15)
				)
			)
		)
		(property "Manufacturer" ""
			(at 0 0 0)
			(layer "F.Fab")
			(hide yes)
			(effects
				(font
					(size 1 1)
					(thickness 0.15)
				)
			)
		)
		(property "Public" "False"
			(at 0 0 0)
			(layer "F.Fab")
			(hide yes)
			(effects
				(font
					(size 1 1)
					(thickness 0.15)
				)
			)
		)
		(sheetname "KR to SFI #1")
		(sheetfile "kr_sfi.kicad_sch")
		(attr exclude_from_pos_files exclude_from_bom)
		(fp_circle
			(center 0 0)
			(end 0.475 0)
			(stroke
				(width 0.05)
				(type default)
			)
			(fill no)
			(layer "F.CrtYd")
		)
		(pad "1" smd circle
			(at 0 0)
			(size 0.75 0.75)
			(layers "F.Cu" "F.Mask")
			(net 720 "Net-(U43C-REFCLK1+)")
			(pinfunction "1")
			(pintype "passive")
			(teardrops
				(best_length_ratio 0.4)
				(max_length 1)
				(best_width_ratio 0.9)
				(max_width 2)
				(curved_edges yes)
				(filter_ratio 0.9)
				(enabled yes)
				(allow_two_segments yes)
				(prefer_zone_connections yes)
			)
		)
	)
	(footprint "antmicro-footprints:Choke_0805_2012Metric"
		(layer "F.Cu")
		(at 127.25 113.31 180)
		(property "Reference" "T1"
			(at 1.6 -1.85 0)
			(unlocked yes)
			(layer "F.SilkS")
			(effects
				(font
					(size 0.7 0.7)
					(thickness 0.15)
				)
				(justify left bottom)
			)
		)
		(property "Value" "Choke_SRF2012A-801Y"
			(at 0 -7 180)
			(unlocked yes)
			(layer "F.Fab")
			(effects
				(font
					(size 0.7 0.7)
					(thickness 0.15)
				)
				(justify left bottom)
			)
		)
		(property "Datasheet" "https://www.bourns.com/docs/product-datasheets/srf2012a-801y.pdf"
			(at 0 0 180)
			(layer "F.Fab")
			(hide yes)
			(effects
				(font
					(size 1.27 1.27)
					(thickness 0.15)
				)
			)
		)
		(property "Author" "Antmicro"
			(at 254.5 226.62 0)
			(layer "F.Fab")
			(hide yes)
			(effects
				(font
					(size 1 1)
					(thickness 0.15)
				)
			)
		)
		(property "IMax" "0.3 A"
			(at 254.5 226.62 0)
			(layer "F.Fab")
			(hide yes)
			(effects
				(font
					(size 1 1)
					(thickness 0.15)
				)
			)
		)
		(property "License" "Apache-2.0"
			(at 254.5 226.62 0)
			(layer "F.Fab")
			(hide yes)
			(effects
				(font
					(size 1 1)
					(thickness 0.15)
				)
			)
		)
		(property "MPN" "SRF2012A-801Y"
			(at 254.5 226.62 0)
			(layer "F.Fab")
			(hide yes)
			(effects
				(font
					(size 1 1)
					(thickness 0.15)
				)
			)
		)
		(property "Manufacturer" "Bourns"
			(at 254.5 226.62 0)
			(layer "F.Fab")
			(hide yes)
			(effects
				(font
					(size 1 1)
					(thickness 0.15)
				)
			)
		)
		(property "Public" "False"
			(at 254.5 226.62 0)
			(layer "F.Fab")
			(hide yes)
			(effects
				(font
					(size 1 1)
					(thickness 0.15)
				)
			)
		)
		(property ki_fp_filters "IND_ACM9070_TDK")
		(sheetname "2xUSB3.0+RJ45")
		(sheetfile "usb3+rj45.kicad_sch")
		(attr smd)
		(fp_rect
			(start -1.5 -0.9)
			(end 1.5 0.9)
			(stroke
				(width 0.05)
				(type solid)
			)
			(fill no)
			(layer "F.CrtYd")
		)
		(pad "1" smd roundrect
			(at -0.96 -0.46 180)
			(size 0.675 0.475)
			(layers "F.Cu" "F.Mask" "F.Paste")
			(roundrect_rratio 0.25)
			(net 689 "/2xUSB3.0+RJ45/DA_FL+")
			(pinfunction "1")
			(pintype "passive")
			(teardrops
				(best_length_ratio 0.2)
				(max_length 1)
				(best_width_ratio 0.9)
				(max_width 2)
				(curved_edges yes)
				(filter_ratio 0.9)
				(enabled yes)
				(allow_two_segments yes)
				(prefer_zone_connections yes)
			)
		)
		(pad "2" smd roundrect
			(at 0.96 -0.46 180)
			(size 0.675 0.475)
			(layers "F.Cu" "F.Mask" "F.Paste")
			(roundrect_rratio 0.25)
			(net 146 "/2xUSB3.0+RJ45/DA+")
			(pinfunction "2")
			(pintype "passive")
			(teardrops
				(best_length_ratio 0.2)
				(max_length 1)
				(best_width_ratio 0.9)
				(max_width 2)
				(curved_edges yes)
				(filter_ratio 0.9)
				(enabled yes)
				(allow_two_segments yes)
				(prefer_zone_connections yes)
			)
		)
		(pad "3" smd roundrect
			(at 0.96 0.46 180)
			(size 0.675 0.475)
			(layers "F.Cu" "F.Mask" "F.Paste")
			(roundrect_rratio 0.25)
			(net 147 "/2xUSB3.0+RJ45/DA-")
			(pinfunction "3")
			(pintype "passive")
			(teardrops
				(best_length_ratio 0.2)
				(max_length 1)
				(best_width_ratio 0.9)
				(max_width 2)
				(curved_edges yes)
				(filter_ratio 0.9)
				(enabled yes)
				(allow_two_segments yes)
				(prefer_zone_connections yes)
			)
		)
		(pad "4" smd roundrect
			(at -0.96 0.46 180)
			(size 0.675 0.475)
			(layers "F.Cu" "F.Mask" "F.Paste")
			(roundrect_rratio 0.25)
			(net 690 "/2xUSB3.0+RJ45/DA_FL-")
			(pinfunction "4")
			(pintype "passive")
			(teardrops
				(best_length_ratio 0.2)
				(max_length 1)
				(best_width_ratio 0.9)
				(max_width 2)
				(curved_edges yes)
				(filter_ratio 0.9)
				(enabled yes)
				(allow_two_segments yes)
				(prefer_zone_connections yes)
			)
		)
	)
	(footprint "antmicro-footprints:R_0402_1005Metric"
		(layer "F.Cu")
		(at 212.59 132.26)
		(descr "Resistor SMD 0402")
		(tags "resistor SMD 0402")
		(property "Reference" "R314"
			(at -3.64 0.37 0)
			(layer "F.SilkS")
			(effects
				(font
					(size 0.7 0.7)
					(thickness 0.15)
				)
				(justify left bottom)
			)
		)
		(property "Value" "R_0R_0402"
			(at -1.011843 1.772047 0)
			(layer "F.Fab")
			(effects
				(font
					(size 0.7 0.7)
					(thickness 0.15)
				)
				(justify left bottom)
			)
		)
		(property "Datasheet" "https://industrial.panasonic.com/cdbs/www-data/pdf/RDA0000/AOA0000C301.pdf"
			(at 0 0 0)
			(layer "F.Fab")
			(hide yes)
			(effects
				(font
					(size 1.27 1.27)
					(thickness 0.15)
				)
			)
		)
		(property "Author" "Antmicro"
			(at 0 0 0)
			(layer "F.Fab")
			(hide yes)
			(effects
				(font
					(size 1 1)
					(thickness 0.15)
				)
			)
		)
		(property "Current" "1A"
			(at 0 0 0)
			(layer "F.Fab")
			(hide yes)
			(effects
				(font
					(size 1 1)
					(thickness 0.15)
				)
			)
		)
		(property "License" "Apache-2.0"
			(at 0 0 0)
			(layer "F.Fab")
			(hide yes)
			(effects
				(font
					(size 1 1)
					(thickness 0.15)
				)
			)
		)
		(property "MPN" "ERJ2GE0R00X"
			(at 0 0 0)
			(layer "F.Fab")
			(hide yes)
			(effects
				(font
					(size 1 1)
					(thickness 0.15)
				)
			)
		)
		(property "Manufacturer" "Panasonic"
			(at 0 0 0)
			(layer "F.Fab")
			(hide yes)
			(effects
				(font
					(size 1 1)
					(thickness 0.15)
				)
			)
		)
		(property "Public" "False"
			(at 0 0 0)
			(layer "F.Fab")
			(hide yes)
			(effects
				(font
					(size 1 1)
					(thickness 0.15)
				)
			)
		)
		(property "Tolerance" ""
			(at 0 0 0)
			(layer "F.Fab")
			(hide yes)
			(effects
				(font
					(size 1 1)
					(thickness 0.15)
				)
			)
		)
		(property "Val" "0R"
			(at 0 0 0)
			(layer "F.Fab")
			(hide yes)
			(effects
				(font
					(size 1 1)
					(thickness 0.15)
				)
			)
		)
		(sheetname "PCIe misc")
		(sheetfile "pcie_misc.kicad_sch")
		(attr smd dnp)
		(fp_rect
			(start -0.925 -0.47)
			(end 0.925 0.47)
			(stroke
				(width 0.05)
				(type default)
			)
			(fill no)
			(layer "F.CrtYd")
		)
		(fp_rect
			(start -0.5 -0.25)
			(end 0.5 0.25)
			(stroke
				(width 0.15)
				(type solid)
			)
			(fill no)
			(layer "F.Fab")
		)
		(pad "1" smd roundrect
			(at -0.48 0)
			(size 0.59 0.64)
			(layers "F.Cu" "F.Mask" "F.Paste")
			(roundrect_rratio 0.25)
			(net 945 "/GPIO expander/GPIOEX5")
			(pintype "passive")
			(teardrops
				(best_length_ratio 0.2)
				(max_length 1)
				(best_width_ratio 0.9)
				(max_width 2)
				(curved_edges yes)
				(filter_ratio 0.9)
				(enabled yes)
				(allow_two_segments yes)
				(prefer_zone_connections yes)
			)
		)
		(pad "2" smd roundrect
			(at 0.48 0)
			(size 0.59 0.64)
			(layers "F.Cu" "F.Mask" "F.Paste")
			(roundrect_rratio 0.25)
			(net 603 "Net-(U37-~{OE1})")
			(pintype "passive")
			(teardrops
				(best_length_ratio 0.2)
				(max_length 1)
				(best_width_ratio 0.9)
				(max_width 2)
				(curved_edges yes)
				(filter_ratio 0.9)
				(enabled yes)
				(allow_two_segments yes)
				(prefer_zone_connections yes)
			)
		)
	)
	(footprint "antmicro-footprints:SC-74-6_1.5x2.9mm_P0.95mm"
		(layer "F.Cu")
		(at 256.350707 78.135)
		(tags "sc74 sc-74 sot23-6 sot457 tsop6 tsop-6")
		(property "Reference" "U25"
			(at -1.129999 2.325 0)
			(layer "F.SilkS")
			(effects
				(font
					(size 0.7 0.7)
					(thickness 0.15)
				)
				(justify left bottom)
			)
		)
		(property "Value" "74LVC1G157-Q100H_SOT457"
			(at 0.001 2.7 0)
			(layer "F.Fab")
			(effects
				(font
					(size 0.7 0.7)
					(thickness 0.15)
				)
				(justify left bottom)
			)
		)
		(property "Datasheet" "https://www.mouser.com/datasheet/2/916/74LVC1G157_Q100-1578792.pdf"
			(at 0 0 0)
			(layer "F.Fab")
			(hide yes)
			(effects
				(font
					(size 1.27 1.27)
					(thickness 0.15)
				)
			)
		)
		(property "Author" "Antmicro"
			(at 0 0 0)
			(layer "F.Fab")
			(hide yes)
			(effects
				(font
					(size 1 1)
					(thickness 0.15)
				)
			)
		)
		(property "License" "Apache-2.0"
			(at 0 0 0)
			(layer "F.Fab")
			(hide yes)
			(effects
				(font
					(size 1 1)
					(thickness 0.15)
				)
			)
		)
		(property "MPN" "74LVC1G157-Q100H"
			(at 0 0 0)
			(layer "F.Fab")
			(hide yes)
			(effects
				(font
					(size 1 1)
					(thickness 0.15)
				)
			)
		)
		(property "Manufacturer" "Nexperia"
			(at 0 0 0)
			(layer "F.Fab")
			(hide yes)
			(effects
				(font
					(size 1 1)
					(thickness 0.15)
				)
			)
		)
		(sheetname "Misc")
		(sheetfile "misc.kicad_sch")
		(attr smd)
		(fp_circle
			(center -1.11 -1.454)
			(end -1.06 -1.454)
			(stroke
				(width 0.15)
				(type solid)
			)
			(fill yes)
			(layer "F.SilkS")
		)
		(fp_rect
			(start -1.7 -1.7)
			(end 1.7 1.7)
			(stroke
				(width 0.05)
				(type solid)
			)
			(fill no)
			(layer "F.CrtYd")
		)
		(fp_line
			(start -1.269 -0.915)
			(end -1.269 1.372)
			(stroke
				(width 0.15)
				(type solid)
			)
			(layer "F.Fab")
		)
		(fp_line
			(start -1.269 1.372)
			(end -1.167 1.372)
			(stroke
				(width 0.15)
				(type solid)
			)
			(layer "F.Fab")
		)
		(fp_line
			(start -1.167 1.372)
			(end 1.22 1.372)
			(stroke
				(width 0.15)
				(type solid)
			)
			(layer "F.Fab")
		)
		(fp_line
			(start -0.76 -1.422)
			(end -1.269 -0.915)
			(stroke
				(width 0.15)
				(type solid)
			)
			(layer "F.Fab")
		)
		(fp_line
			(start 1.22 -1.422)
			(end -0.76 -1.422)
			(stroke
				(width 0.15)
				(type solid)
			)
			(layer "F.Fab")
		)
		(fp_line
			(start 1.22 1.372)
			(end 1.22 -1.422)
			(stroke
				(width 0.15)
				(type solid)
			)
			(layer "F.Fab")
		)
		(pad "1" smd roundrect
			(at -1.2 -0.95)
			(size 0.8 0.55)
			(layers "F.Cu" "F.Mask" "F.Paste")
			(roundrect_rratio 0.15)
			(net 400 "/Com Express 7 MGMT/FAN_PWM")
			(pinfunction "I1")
			(pintype "input")
			(teardrops
				(best_length_ratio 0.2)
				(max_length 1)
				(best_width_ratio 0.9)
				(max_width 2)
				(curved_edges yes)
				(filter_ratio 0.9)
				(enabled yes)
				(allow_two_segments yes)
				(prefer_zone_connections yes)
			)
		)
		(pad "2" smd roundrect
			(at -1.2 0)
			(size 0.8 0.55)
			(layers "F.Cu" "F.Mask" "F.Paste")
			(roundrect_rratio 0.15)
			(net 1 "GND")
			(pinfunction "GND")
			(pintype "power_in")
			(teardrops
				(best_length_ratio 0.2)
				(max_length 1)
				(best_width_ratio 0.9)
				(max_width 2)
				(curved_edges yes)
				(filter_ratio 0.9)
				(enabled yes)
				(allow_two_segments yes)
				(prefer_zone_connections yes)
			)
		)
		(pad "3" smd roundrect
			(at -1.2 0.95)
			(size 0.8 0.55)
			(layers "F.Cu" "F.Mask" "F.Paste")
			(roundrect_rratio 0.15)
			(net 597 "/Misc/PWM1")
			(pinfunction "I0")
			(pintype "input")
			(teardrops
				(best_length_ratio 0.2)
				(max_length 1)
				(best_width_ratio 0.9)
				(max_width 2)
				(curved_edges yes)
				(filter_ratio 0.9)
				(enabled yes)
				(allow_two_segments yes)
				(prefer_zone_connections yes)
			)
		)
		(pad "4" smd roundrect
			(at 1.2 0.95)
			(size 0.8 0.55)
			(layers "F.Cu" "F.Mask" "F.Paste")
			(roundrect_rratio 0.15)
			(net 782 "/Misc/PWM_{A3V3}")
			(pinfunction "Y")
			(pintype "output")
			(teardrops
				(best_length_ratio 0.2)
				(max_length 1)
				(best_width_ratio 0.9)
				(max_width 2)
				(curved_edges yes)
				(filter_ratio 0.9)
				(enabled yes)
				(allow_two_segments yes)
				(prefer_zone_connections yes)
			)
		)
		(pad "5" smd roundrect
			(at 1.2 0)
			(size 0.8 0.55)
			(layers "F.Cu" "F.Mask" "F.Paste")
			(roundrect_rratio 0.15)
			(net 2 "+3V3")
			(pinfunction "VCC")
			(pintype "power_in")
			(teardrops
				(best_length_ratio 0.2)
				(max_length 1)
				(best_width_ratio 0.9)
				(max_width 2)
				(curved_edges yes)
				(filter_ratio 0.9)
				(enabled yes)
				(allow_two_segments yes)
				(prefer_zone_connections yes)
			)
		)
		(pad "6" smd roundrect
			(at 1.2 -0.95)
			(size 0.8 0.55)
			(layers "F.Cu" "F.Mask" "F.Paste")
			(roundrect_rratio 0.15)
			(net 595 "/Misc/PWM_{SRCSEL}")
			(pinfunction "S")
			(pintype "input")
			(teardrops
				(best_length_ratio 0.2)
				(max_length 1)
				(best_width_ratio 0.9)
				(max_width 2)
				(curved_edges yes)
				(filter_ratio 0.9)
				(enabled yes)
				(allow_two_segments yes)
				(prefer_zone_connections yes)
			)
		)
	)
	(footprint "antmicro-footprints:C_0402_1005Metric"
		(layer "F.Cu")
		(at 245.000709 78.135 -90)
		(descr "Capacitor SMD 0402")
		(tags "capacitor SMD 0402")
		(property "Reference" "C87"
			(at 0.825 -0.469999 90)
			(layer "F.SilkS")
			(effects
				(font
					(size 0.7 0.7)
					(thickness 0.15)
				)
				(justify right bottom)
			)
		)
		(property "Value" "C_100n_0402"
			(at -1.022927 2.155213 90)
			(layer "F.Fab")
			(effects
				(font
					(size 0.7 0.7)
					(thickness 0.15)
				)
				(justify right bottom)
			)
		)
		(property "Datasheet" "https://www.murata.com/products/productdetail?partno=GRM155R61H104KE14%23"
			(at 0 0 270)
			(layer "F.Fab")
			(hide yes)
			(effects
				(font
					(size 1.27 1.27)
					(thickness 0.15)
				)
			)
		)
		(property "Author" "Antmicro"
			(at 166.865709 323.135709 0)
			(layer "F.Fab")
			(hide yes)
			(effects
				(font
					(size 1 1)
					(thickness 0.15)
				)
			)
		)
		(property "Dielectric" "X5R"
			(at 166.865709 323.135709 0)
			(layer "F.Fab")
			(hide yes)
			(effects
				(font
					(size 1 1)
					(thickness 0.15)
				)
			)
		)
		(property "License" "Apache-2.0"
			(at 166.865709 323.135709 0)
			(layer "F.Fab")
			(hide yes)
			(effects
				(font
					(size 1 1)
					(thickness 0.15)
				)
			)
		)
		(property "MPN" "GRM155R61H104KE14D"
			(at 166.865709 323.135709 0)
			(layer "F.Fab")
			(hide yes)
			(effects
				(font
					(size 1 1)
					(thickness 0.15)
				)
			)
		)
		(property "Manufacturer" "Murata"
			(at 166.865709 323.135709 0)
			(layer "F.Fab")
			(hide yes)
			(effects
				(font
					(size 1 1)
					(thickness 0.15)
				)
			)
		)
		(property "Public" "False"
			(at 166.865709 323.135709 0)
			(layer "F.Fab")
			(hide yes)
			(effects
				(font
					(size 1 1)
					(thickness 0.15)
				)
			)
		)
		(property "Val" "100n"
			(at 166.865709 323.135709 0)
			(layer "F.Fab")
			(hide yes)
			(effects
				(font
					(size 1 1)
					(thickness 0.15)
				)
			)
		)
		(property "Voltage" "50V"
			(at 166.865709 323.135709 0)
			(layer "F.Fab")
			(hide yes)
			(effects
				(font
					(size 1 1)
					(thickness 0.15)
				)
			)
		)
		(sheetname "Misc")
		(sheetfile "misc.kicad_sch")
		(attr smd)
		(fp_rect
			(start -0.925 -0.47)
			(end 0.925 0.47)
			(stroke
				(width 0.05)
				(type default)
			)
			(fill no)
			(layer "F.CrtYd")
		)
		(fp_line
			(start -0.494 0.248)
			(end -0.494 -0.25)
			(stroke
				(width 0.15)
				(type solid)
			)
			(layer "F.Fab")
		)
		(fp_line
			(start 0.504 0.248)
			(end -0.494 0.248)
			(stroke
				(width 0.15)
				(type solid)
			)
			(layer "F.Fab")
		)
		(fp_line
			(start -0.494 -0.25)
			(end 0.504 -0.25)
			(stroke
				(width 0.15)
				(type solid)
			)
			(layer "F.Fab")
		)
		(fp_line
			(start 0.504 -0.25)
			(end 0.504 0.248)
			(stroke
				(width 0.15)
				(type solid)
			)
			(layer "F.Fab")
		)
		(pad "1" smd roundrect
			(at -0.48 0 270)
			(size 0.59 0.64)
			(layers "F.Cu" "F.Mask" "F.Paste")
			(roundrect_rratio 0.25)
			(net 1 "GND")
			(pintype "passive")
			(teardrops
				(best_length_ratio 0.2)
				(max_length 1)
				(best_width_ratio 0.9)
				(max_width 2)
				(curved_edges yes)
				(filter_ratio 0.9)
				(enabled yes)
				(allow_two_segments yes)
				(prefer_zone_connections yes)
			)
		)
		(pad "2" smd roundrect
			(at 0.48 0 270)
			(size 0.59 0.64)
			(layers "F.Cu" "F.Mask" "F.Paste")
			(roundrect_rratio 0.25)
			(net 2 "+3V3")
			(pintype "passive")
			(teardrops
				(best_length_ratio 0.2)
				(max_length 1)
				(best_width_ratio 0.9)
				(max_width 2)
				(curved_edges yes)
				(filter_ratio 0.9)
				(enabled yes)
				(allow_two_segments yes)
				(prefer_zone_connections yes)
			)
		)
	)
	(footprint "antmicro-footprints:R_0402_1005Metric"
		(layer "F.Cu")
		(at 306.65 155.71 -90)
		(descr "Resistor SMD 0402")
		(tags "resistor SMD 0402")
		(property "Reference" "R164"
			(at -0.9 0.5 90)
			(layer "F.SilkS")
			(effects
				(font
					(size 0.7 0.7)
					(thickness 0.15)
				)
				(justify right bottom)
			)
		)
		(property "Value" "R_100k_0402"
			(at -1.011843 1.772047 90)
			(layer "F.Fab")
			(effects
				(font
					(size 0.7 0.7)
					(thickness 0.15)
				)
				(justify right bottom)
			)
		)
		(property "Datasheet" "https://www.bourns.com/docs/product-datasheets/cr.pdf"
			(at 0 0 270)
			(layer "F.Fab")
			(hide yes)
			(effects
				(font
					(size 1.27 1.27)
					(thickness 0.15)
				)
			)
		)
		(property "Author" "Antmicro"
			(at 150.94 462.36 0)
			(layer "F.Fab")
			(hide yes)
			(effects
				(font
					(size 1 1)
					(thickness 0.15)
				)
			)
		)
		(property "License" "Apache-2.0"
			(at 150.94 462.36 0)
			(layer "F.Fab")
			(hide yes)
			(effects
				(font
					(size 1 1)
					(thickness 0.15)
				)
			)
		)
		(property "MPN" "CR0402-FX-1003GLF"
			(at 150.94 462.36 0)
			(layer "F.Fab")
			(hide yes)
			(effects
				(font
					(size 1 1)
					(thickness 0.15)
				)
			)
		)
		(property "Manufacturer" "Bourns"
			(at 150.94 462.36 0)
			(layer "F.Fab")
			(hide yes)
			(effects
				(font
					(size 1 1)
					(thickness 0.15)
				)
			)
		)
		(property "Public" "False"
			(at 150.94 462.36 0)
			(layer "F.Fab")
			(hide yes)
			(effects
				(font
					(size 1 1)
					(thickness 0.15)
				)
			)
		)
		(property "Tolerance" "1%"
			(at 150.94 462.36 0)
			(layer "F.Fab")
			(hide yes)
			(effects
				(font
					(size 1 1)
					(thickness 0.15)
				)
			)
		)
		(property "Val" "100k"
			(at 150.94 462.36 0)
			(layer "F.Fab")
			(hide yes)
			(effects
				(font
					(size 1 1)
					(thickness 0.15)
				)
			)
		)
		(sheetname "Com Express 7 MGMT")
		(sheetfile "com_express_7_mgmt.kicad_sch")
		(attr smd)
		(fp_rect
			(start -0.925 -0.47)
			(end 0.925 0.47)
			(stroke
				(width 0.05)
				(type default)
			)
			(fill no)
			(layer "F.CrtYd")
		)
		(fp_rect
			(start -0.5 -0.25)
			(end 0.5 0.25)
			(stroke
				(width 0.15)
				(type solid)
			)
			(fill no)
			(layer "F.Fab")
		)
		(pad "1" smd roundrect
			(at -0.48 0 270)
			(size 0.59 0.64)
			(layers "F.Cu" "F.Mask" "F.Paste")
			(roundrect_rratio 0.25)
			(net 1 "GND")
			(pintype "passive")
			(teardrops
				(best_length_ratio 0.2)
				(max_length 1)
				(best_width_ratio 0.9)
				(max_width 2)
				(curved_edges yes)
				(filter_ratio 0.9)
				(enabled yes)
				(allow_two_segments yes)
				(prefer_zone_connections yes)
			)
		)
		(pad "2" smd roundrect
			(at 0.48 0 270)
			(size 0.59 0.64)
			(layers "F.Cu" "F.Mask" "F.Paste")
			(roundrect_rratio 0.25)
			(net 382 "Net-(J12D-~{CB_RESET})")
			(pintype "passive")
			(teardrops
				(best_length_ratio 0.2)
				(max_length 1)
				(best_width_ratio 0.9)
				(max_width 2)
				(curved_edges yes)
				(filter_ratio 0.9)
				(enabled yes)
				(allow_two_segments yes)
				(prefer_zone_connections yes)
			)
		)
	)
	(footprint "antmicro-footprints:USON-10_2.5x1mm_P0.5mm"
		(layer "F.Cu")
		(at 314.75 163.96)
		(descr "USON-10 2.5x1mm_ Pitch 0.5mm")
		(tags "USON-10 2.5x1mm Pitch 0.5mm")
		(property "Reference" "U12"
			(at -0.9 1.1 270)
			(layer "F.SilkS")
			(effects
				(font
					(size 0.7 0.7)
					(thickness 0.15)
				)
				(justify left bottom)
			)
		)
		(property "Value" "ESD204DQAR"
			(at 0.018 2.499 0)
			(layer "F.Fab")
			(effects
				(font
					(size 0.7 0.7)
					(thickness 0.15)
				)
				(justify left bottom)
			)
		)
		(property "Datasheet" "https://www.ti.com/lit/ds/symlink/esd204.pdf?ts=1706004844383&ref_url=https%253A%252F%252Fwww.ti.com%252Finterface%252Fdiodes%252Fesd-protection-diodes%252Fproducts.html"
			(at 0 0 0)
			(layer "F.Fab")
			(hide yes)
			(effects
				(font
					(size 1.27 1.27)
					(thickness 0.15)
				)
			)
		)
		(property "Author" "Antmicro"
			(at 0 0 0)
			(layer "F.Fab")
			(hide yes)
			(effects
				(font
					(size 1 1)
					(thickness 0.15)
				)
			)
		)
		(property "License" "Apache-2.0"
			(at 0 0 0)
			(layer "F.Fab")
			(hide yes)
			(effects
				(font
					(size 1 1)
					(thickness 0.15)
				)
			)
		)
		(property "MPN" "ESD204DQAR"
			(at 0 0 0)
			(layer "F.Fab")
			(hide yes)
			(effects
				(font
					(size 1 1)
					(thickness 0.15)
				)
			)
		)
		(property "Manufacturer" "Texas Instruments"
			(at 0 0 0)
			(layer "F.Fab")
			(hide yes)
			(effects
				(font
					(size 1 1)
					(thickness 0.15)
				)
			)
		)
		(sheetname "Backplane")
		(sheetfile "backplane.kicad_sch")
		(attr smd)
		(fp_line
			(start 0.498 -1.401)
			(end -0.5 -1.401)
			(stroke
				(width 0.15)
				(type solid)
			)
			(layer "F.SilkS")
		)
		(fp_line
			(start 0.498 1.398)
			(end -0.5 1.398)
			(stroke
				(width 0.15)
				(type solid)
			)
			(layer "F.SilkS")
		)
		(fp_circle
			(center -0.68 -1.27)
			(end -0.63 -1.27)
			(stroke
				(width 0.15)
				(type solid)
			)
			(fill yes)
			(layer "F.SilkS")
		)
		(fp_rect
			(start -0.8 -1.5)
			(end 0.8 1.499)
			(stroke
				(width 0.05)
				(type solid)
			)
			(fill no)
			(layer "F.CrtYd")
		)
		(fp_line
			(start -0.5 -1)
			(end -0.5 1.249)
			(stroke
				(width 0.15)
				(type solid)
			)
			(layer "F.Fab")
		)
		(fp_line
			(start -0.5 1.249)
			(end 0.498 1.249)
			(stroke
				(width 0.15)
				(type solid)
			)
			(layer "F.Fab")
		)
		(fp_line
			(start -0.25 -1.25)
			(end -0.5 -1)
			(stroke
				(width 0.15)
				(type solid)
			)
			(layer "F.Fab")
		)
		(fp_line
			(start 0.498 -1.25)
			(end -0.25 -1.25)
			(stroke
				(width 0.15)
				(type solid)
			)
			(layer "F.Fab")
		)
		(fp_line
			(start 0.498 -1.25)
			(end 0.498 1.249)
			(stroke
				(width 0.15)
				(type solid)
			)
			(layer "F.Fab")
		)
		(pad "1" smd roundrect
			(at -0.387 -1 270)
			(size 0.25 0.55)
			(layers "F.Cu" "F.Mask" "F.Paste")
			(roundrect_rratio 0.25)
			(net 202 "unconnected-(U12-Pad1)")
			(pintype "passive+no_connect")
			(teardrops
				(best_length_ratio 0.2)
				(max_length 1)
				(best_width_ratio 0.9)
				(max_width 2)
				(curved_edges yes)
				(filter_ratio 0.9)
				(enabled yes)
				(allow_two_segments yes)
				(prefer_zone_connections yes)
			)
		)
		(pad "2" smd roundrect
			(at -0.387 -0.5 270)
			(size 0.25 0.55)
			(layers "F.Cu" "F.Mask" "F.Paste")
			(roundrect_rratio 0.25)
			(net 528 "/Backplane/~{PERST}")
			(pintype "passive")
			(teardrops
				(best_length_ratio 0.2)
				(max_length 1)
				(best_width_ratio 0.9)
				(max_width 2)
				(curved_edges yes)
				(filter_ratio 0.9)
				(enabled yes)
				(allow_two_segments yes)
				(prefer_zone_connections yes)
			)
		)
		(pad "3" smd roundrect
			(at -0.387 0 270)
			(size 0.4 0.55)
			(layers "F.Cu" "F.Mask" "F.Paste")
			(roundrect_rratio 0.25)
			(net 1 "GND")
			(pintype "power_in")
			(teardrops
				(best_length_ratio 0.2)
				(max_length 1)
				(best_width_ratio 0.9)
				(max_width 2)
				(curved_edges yes)
				(filter_ratio 0.9)
				(enabled yes)
				(allow_two_segments yes)
				(prefer_zone_connections yes)
			)
		)
		(pad "4" smd roundrect
			(at -0.387 0.498 270)
			(size 0.25 0.55)
			(layers "F.Cu" "F.Mask" "F.Paste")
			(roundrect_rratio 0.25)
			(net 526 "/Backplane/~{PRSNT}")
			(pintype "passive")
			(teardrops
				(best_length_ratio 0.2)
				(max_length 1)
				(best_width_ratio 0.9)
				(max_width 2)
				(curved_edges yes)
				(filter_ratio 0.9)
				(enabled yes)
				(allow_two_segments yes)
				(prefer_zone_connections yes)
			)
		)
		(pad "5" smd roundrect
			(at -0.387 0.998 270)
			(size 0.25 0.55)
			(layers "F.Cu" "F.Mask" "F.Paste")
			(roundrect_rratio 0.25)
			(net 527 "/Backplane/GPIO")
			(pintype "passive")
			(teardrops
				(best_length_ratio 0.2)
				(max_length 1)
				(best_width_ratio 0.9)
				(max_width 2)
				(curved_edges yes)
				(filter_ratio 0.9)
				(enabled yes)
				(allow_two_segments yes)
				(prefer_zone_connections yes)
			)
		)
		(pad "6" smd roundrect
			(at 0.385 0.998 270)
			(size 0.25 0.55)
			(layers "F.Cu" "F.Mask" "F.Paste")
			(roundrect_rratio 0.25)
			(net 527 "/Backplane/GPIO")
			(pintype "passive")
			(teardrops
				(best_length_ratio 0.2)
				(max_length 1)
				(best_width_ratio 0.9)
				(max_width 2)
				(curved_edges yes)
				(filter_ratio 0.9)
				(enabled yes)
				(allow_two_segments yes)
				(prefer_zone_connections yes)
			)
		)
		(pad "7" smd roundrect
			(at 0.385 0.498 270)
			(size 0.25 0.55)
			(layers "F.Cu" "F.Mask" "F.Paste")
			(roundrect_rratio 0.25)
			(net 526 "/Backplane/~{PRSNT}")
			(pintype "passive")
			(teardrops
				(best_length_ratio 0.2)
				(max_length 1)
				(best_width_ratio 0.9)
				(max_width 2)
				(curved_edges yes)
				(filter_ratio 0.9)
				(enabled yes)
				(allow_two_segments yes)
				(prefer_zone_connections yes)
			)
		)
		(pad "8" smd roundrect
			(at 0.385 0 270)
			(size 0.4 0.55)
			(layers "F.Cu" "F.Mask" "F.Paste")
			(roundrect_rratio 0.25)
			(net 1 "GND")
			(pintype "passive")
			(teardrops
				(best_length_ratio 0.2)
				(max_length 1)
				(best_width_ratio 0.9)
				(max_width 2)
				(curved_edges yes)
				(filter_ratio 0.9)
				(enabled yes)
				(allow_two_segments yes)
				(prefer_zone_connections yes)
			)
		)
		(pad "9" smd roundrect
			(at 0.385 -0.5 270)
			(size 0.25 0.55)
			(layers "F.Cu" "F.Mask" "F.Paste")
			(roundrect_rratio 0.25)
			(net 528 "/Backplane/~{PERST}")
			(pintype "passive")
			(teardrops
				(best_length_ratio 0.2)
				(max_length 1)
				(best_width_ratio 0.9)
				(max_width 2)
				(curved_edges yes)
				(filter_ratio 0.9)
				(enabled yes)
				(allow_two_segments yes)
				(prefer_zone_connections yes)
			)
		)
		(pad "10" smd roundrect
			(at 0.385 -1 270)
			(size 0.25 0.55)
			(layers "F.Cu" "F.Mask" "F.Paste")
			(roundrect_rratio 0.25)
			(net 993 "unconnected-(U12-Pad1)_1")
			(pintype "passive+no_connect")
			(teardrops
				(best_length_ratio 0.2)
				(max_length 1)
				(best_width_ratio 0.9)
				(max_width 2)
				(curved_edges yes)
				(filter_ratio 0.9)
				(enabled yes)
				(allow_two_segments yes)
				(prefer_zone_connections yes)
			)
		)
	)
	(footprint "antmicro-footprints:R_0402_1005Metric"
		(layer "F.Cu")
		(at 211.28 129.425 180)
		(descr "Resistor SMD 0402")
		(tags "resistor SMD 0402")
		(property "Reference" "R194"
			(at 0.83 -0.735 0)
			(layer "F.SilkS")
			(effects
				(font
					(size 0.7 0.7)
					(thickness 0.15)
				)
				(justify right bottom)
			)
		)
		(property "Value" "R_0R_0402"
			(at -1.011843 1.772047 0)
			(layer "F.Fab")
			(effects
				(font
					(size 0.7 0.7)
					(thickness 0.15)
				)
				(justify right bottom)
			)
		)
		(property "Datasheet" "https://industrial.panasonic.com/cdbs/www-data/pdf/RDA0000/AOA0000C301.pdf"
			(at 0 0 180)
			(layer "F.Fab")
			(hide yes)
			(effects
				(font
					(size 1.27 1.27)
					(thickness 0.15)
				)
			)
		)
		(property "Author" "Antmicro"
			(at 422.56 258.85 0)
			(layer "F.Fab")
			(hide yes)
			(effects
				(font
					(size 1 1)
					(thickness 0.15)
				)
			)
		)
		(property "Current" "1A"
			(at 422.56 258.85 0)
			(layer "F.Fab")
			(hide yes)
			(effects
				(font
					(size 1 1)
					(thickness 0.15)
				)
			)
		)
		(property "License" "Apache-2.0"
			(at 422.56 258.85 0)
			(layer "F.Fab")
			(hide yes)
			(effects
				(font
					(size 1 1)
					(thickness 0.15)
				)
			)
		)
		(property "MPN" "ERJ2GE0R00X"
			(at 422.56 258.85 0)
			(layer "F.Fab")
			(hide yes)
			(effects
				(font
					(size 1 1)
					(thickness 0.15)
				)
			)
		)
		(property "Manufacturer" "Panasonic"
			(at 422.56 258.85 0)
			(layer "F.Fab")
			(hide yes)
			(effects
				(font
					(size 1 1)
					(thickness 0.15)
				)
			)
		)
		(property "Public" "False"
			(at 422.56 258.85 0)
			(layer "F.Fab")
			(hide yes)
			(effects
				(font
					(size 1 1)
					(thickness 0.15)
				)
			)
		)
		(property "Tolerance" ""
			(at 422.56 258.85 0)
			(layer "F.Fab")
			(hide yes)
			(effects
				(font
					(size 1 1)
					(thickness 0.15)
				)
			)
		)
		(property "Val" "0R"
			(at 422.56 258.85 0)
			(layer "F.Fab")
			(hide yes)
			(effects
				(font
					(size 1 1)
					(thickness 0.15)
				)
			)
		)
		(sheetname "PCIe misc")
		(sheetfile "pcie_misc.kicad_sch")
		(attr smd)
		(fp_rect
			(start -0.925 -0.47)
			(end 0.925 0.47)
			(stroke
				(width 0.05)
				(type default)
			)
			(fill no)
			(layer "F.CrtYd")
		)
		(fp_rect
			(start -0.5 -0.25)
			(end 0.5 0.25)
			(stroke
				(width 0.15)
				(type solid)
			)
			(fill no)
			(layer "F.Fab")
		)
		(pad "1" smd roundrect
			(at -0.48 0 180)
			(size 0.59 0.64)
			(layers "F.Cu" "F.Mask" "F.Paste")
			(roundrect_rratio 0.25)
			(net 613 "/PCIe misc/DIF1+")
			(pintype "passive")
			(teardrops
				(best_length_ratio 0.2)
				(max_length 1)
				(best_width_ratio 0.9)
				(max_width 2)
				(curved_edges yes)
				(filter_ratio 0.9)
				(enabled yes)
				(allow_two_segments yes)
				(prefer_zone_connections yes)
			)
		)
		(pad "2" smd roundrect
			(at 0.48 0 180)
			(size 0.59 0.64)
			(layers "F.Cu" "F.Mask" "F.Paste")
			(roundrect_rratio 0.25)
			(net 193 "/OCuLink/PCIe_{REF0}.CK-")
			(pintype "passive")
			(teardrops
				(best_length_ratio 0.2)
				(max_length 1)
				(best_width_ratio 0.9)
				(max_width 2)
				(curved_edges yes)
				(filter_ratio 0.9)
				(enabled yes)
				(allow_two_segments yes)
				(prefer_zone_connections yes)
			)
		)
	)
	(footprint "antmicro-footprints:Conn_Molex_Nano-Fit_1x2_105309-1202"
		(layer "F.Cu")
		(at 306.3 168.79 180)
		(descr "Based on: https://www.molex.com/content/dam/molex/molex-dot-com/products/automated/en-us/salesdrawingpdf/105/105430/1054301202_sd.pdf?inline")
		(property "Reference" "J6"
			(at 4.4 1.79 0)
			(layer "F.SilkS")
			(effects
				(font
					(size 0.7 0.7)
					(thickness 0.15)
				)
				(justify right top)
			)
		)
		(property "Value" "Molex_Nano-Fit_1x2_105309-1202"
			(at 0 3.05 0)
			(layer "F.Fab")
			(effects
				(font
					(size 0.7 0.7)
					(thickness 0.15)
				)
				(justify right top)
			)
		)
		(property "Datasheet" "https://tools.molex.com/pdm_docs/sd/1053092202_sd.pdf"
			(at 0 0 0)
			(layer "F.Fab")
			(hide yes)
			(effects
				(font
					(size 1.27 1.27)
					(thickness 0.15)
				)
			)
		)
		(property "Description" "Pin Header, Power, 2.5 mm, 1 Rows, 2 Contacts, Through Hole Straight, Nano-Fit"
			(at 0 0 0)
			(layer "F.Fab")
			(hide yes)
			(effects
				(font
					(size 1.27 1.27)
					(thickness 0.15)
				)
			)
		)
		(attr through_hole)
		(fp_line
			(start 4.239 -1.74)
			(end 4.239 4.6)
			(stroke
				(width 0.15)
				(type solid)
			)
			(layer "F.SilkS")
		)
		(fp_line
			(start -1.7 4.6)
			(end 4.239 4.6)
			(stroke
				(width 0.15)
				(type solid)
			)
			(layer "F.SilkS")
		)
		(fp_line
			(start -1.7 -1.74)
			(end 4.239 -1.74)
			(stroke
				(width 0.15)
				(type solid)
			)
			(layer "F.SilkS")
		)
		(fp_line
			(start -1.7 -1.74)
			(end -1.7 4.6)
			(stroke
				(width 0.15)
				(type solid)
			)
			(layer "F.SilkS")
		)
		(fp_circle
			(center -2 0.01)
			(end -1.95 0.01)
			(stroke
				(width 0.15)
				(type solid)
			)
			(fill yes)
			(layer "F.SilkS")
		)
		(fp_rect
			(start -2.25 -2.35)
			(end 4.85 5.15)
			(stroke
				(width 0.05)
				(type solid)
			)
			(fill no)
			(layer "F.CrtYd")
		)
		(fp_text user "License: Apache-2.0"
			(at -2.175 6.3 0)
			(layer "F.Fab")
			(effects
				(font
					(size 0.7 0.7)
					(thickness 0.15)
				)
				(justify right top)
			)
		)
		(fp_text user "${REFERENCE}"
			(at -2.175 7.5 0)
			(layer "F.Fab")
			(effects
				(font
					(size 0.7 0.7)
					(thickness 0.15)
				)
				(justify right top)
			)
		)
		(fp_text user "Author: Antmicro"
			(at -2.175 8.7 0)
			(layer "F.Fab")
			(effects
				(font
					(size 0.7 0.7)
					(thickness 0.15)
				)
				(justify right top)
			)
		)
		(pad "" np_thru_hole circle
			(at 1.25 1.34 180)
			(size 1.3 1.3)
			(drill 1.3)
			(layers "*.Cu" "*.Mask")
		)
		(pad "1" thru_hole circle
			(at 0 0 180)
			(size 2 2)
			(drill 1.3)
			(layers "*.Cu" "*.Mask")
			(remove_unused_layers no)
			(pintype "input")
		)
		(pad "2" thru_hole circle
			(at 2.5 0 180)
			(size 2 2)
			(drill 1.3)
			(layers "*.Cu" "*.Mask")
			(remove_unused_layers no)
			(pintype "input")
		)
	)
	(footprint "antmicro-footprints:C_0402_1005Metric"
		(layer "F.Cu")
		(at 300.55 118.36 90)
		(descr "Capacitor SMD 0402")
		(tags "capacitor SMD 0402")
		(property "Reference" "C56"
			(at -1.05 -0.5 90)
			(layer "F.SilkS")
			(effects
				(font
					(size 0.7 0.7)
					(thickness 0.15)
				)
				(justify left bottom)
			)
		)
		(property "Value" "C_1u_0402"
			(at -1.022927 2.155213 90)
			(layer "F.Fab")
			(effects
				(font
					(size 0.7 0.7)
					(thickness 0.15)
				)
				(justify left bottom)
			)
		)
		(property "Datasheet" "https://product.tdk.com/en/search/capacitor/ceramic/mlcc/info?part_no=C1005X6S1A105K050BC"
			(at 0 0 90)
			(layer "F.Fab")
			(hide yes)
			(effects
				(font
					(size 1.27 1.27)
					(thickness 0.15)
				)
			)
		)
		(property "Author" "Antmicro"
			(at 418.91 -182.19 0)
			(layer "F.Fab")
			(hide yes)
			(effects
				(font
					(size 1 1)
					(thickness 0.15)
				)
			)
		)
		(property "Dielectric" ""
			(at 418.91 -182.19 0)
			(layer "F.Fab")
			(hide yes)
			(effects
				(font
					(size 1 1)
					(thickness 0.15)
				)
			)
		)
		(property "License" "Apache-2.0"
			(at 418.91 -182.19 0)
			(layer "F.Fab")
			(hide yes)
			(effects
				(font
					(size 1 1)
					(thickness 0.15)
				)
			)
		)
		(property "MPN" "C1005X6S1A105K050BC"
			(at 418.91 -182.19 0)
			(layer "F.Fab")
			(hide yes)
			(effects
				(font
					(size 1 1)
					(thickness 0.15)
				)
			)
		)
		(property "Manufacturer" "TDK"
			(at 418.91 -182.19 0)
			(layer "F.Fab")
			(hide yes)
			(effects
				(font
					(size 1 1)
					(thickness 0.15)
				)
			)
		)
		(property "Public" "False"
			(at 418.91 -182.19 0)
			(layer "F.Fab")
			(hide yes)
			(effects
				(font
					(size 1 1)
					(thickness 0.15)
				)
			)
		)
		(property "Val" "1u"
			(at 418.91 -182.19 0)
			(layer "F.Fab")
			(hide yes)
			(effects
				(font
					(size 1 1)
					(thickness 0.15)
				)
			)
		)
		(property "Voltage" ""
			(at 418.91 -182.19 0)
			(layer "F.Fab")
			(hide yes)
			(effects
				(font
					(size 1 1)
					(thickness 0.15)
				)
			)
		)
		(sheetname "Power")
		(sheetfile "power.kicad_sch")
		(attr smd)
		(fp_rect
			(start -0.925 -0.47)
			(end 0.925 0.47)
			(stroke
				(width 0.05)
				(type default)
			)
			(fill no)
			(layer "F.CrtYd")
		)
		(fp_line
			(start 0.504 -0.25)
			(end 0.504 0.248)
			(stroke
				(width 0.15)
				(type solid)
			)
			(layer "F.Fab")
		)
		(fp_line
			(start -0.494 -0.25)
			(end 0.504 -0.25)
			(stroke
				(width 0.15)
				(type solid)
			)
			(layer "F.Fab")
		)
		(fp_line
			(start 0.504 0.248)
			(end -0.494 0.248)
			(stroke
				(width 0.15)
				(type solid)
			)
			(layer "F.Fab")
		)
		(fp_line
			(start -0.494 0.248)
			(end -0.494 -0.25)
			(stroke
				(width 0.15)
				(type solid)
			)
			(layer "F.Fab")
		)
		(pad "1" smd roundrect
			(at -0.48 0 90)
			(size 0.59 0.64)
			(layers "F.Cu" "F.Mask" "F.Paste")
			(roundrect_rratio 0.25)
			(net 1 "GND")
			(pintype "passive")
			(teardrops
				(best_length_ratio 0.2)
				(max_length 1)
				(best_width_ratio 0.9)
				(max_width 2)
				(curved_edges yes)
				(filter_ratio 0.9)
				(enabled yes)
				(allow_two_segments yes)
				(prefer_zone_connections yes)
			)
		)
		(pad "2" smd roundrect
			(at 0.48 0 90)
			(size 0.59 0.64)
			(layers "F.Cu" "F.Mask" "F.Paste")
			(roundrect_rratio 0.25)
			(net 74 "+1V0")
			(pintype "passive")
			(teardrops
				(best_length_ratio 0.2)
				(max_length 1)
				(best_width_ratio 0.9)
				(max_width 2)
				(curved_edges yes)
				(filter_ratio 0.9)
				(enabled yes)
				(allow_two_segments yes)
				(prefer_zone_connections yes)
			)
		)
	)
	(footprint "antmicro-footprints:R_0402_1005Metric"
		(layer "F.Cu")
		(at 112.9 148.86 180)
		(descr "Resistor SMD 0402")
		(tags "resistor SMD 0402")
		(property "Reference" "R202"
			(at 0.85 -0.45 0)
			(layer "F.SilkS")
			(effects
				(font
					(size 0.7 0.7)
					(thickness 0.15)
				)
				(justify right bottom)
			)
		)
		(property "Value" "R_1k_0402"
			(at -1.011843 1.772047 0)
			(layer "F.Fab")
			(effects
				(font
					(size 0.7 0.7)
					(thickness 0.15)
				)
				(justify right bottom)
			)
		)
		(property "Datasheet" "https://www.bourns.com/docs/product-datasheets/cr.pdf"
			(at 0 0 180)
			(layer "F.Fab")
			(hide yes)
			(effects
				(font
					(size 1.27 1.27)
					(thickness 0.15)
				)
			)
		)
		(property "Author" "Antmicro"
			(at 225.8 297.72 0)
			(layer "F.Fab")
			(hide yes)
			(effects
				(font
					(size 1 1)
					(thickness 0.15)
				)
			)
		)
		(property "License" "Apache-2.0"
			(at 225.8 297.72 0)
			(layer "F.Fab")
			(hide yes)
			(effects
				(font
					(size 1 1)
					(thickness 0.15)
				)
			)
		)
		(property "MPN" "CR0402-FX-1001GLF"
			(at 225.8 297.72 0)
			(layer "F.Fab")
			(hide yes)
			(effects
				(font
					(size 1 1)
					(thickness 0.15)
				)
			)
		)
		(property "Manufacturer" "Bourns"
			(at 225.8 297.72 0)
			(layer "F.Fab")
			(hide yes)
			(effects
				(font
					(size 1 1)
					(thickness 0.15)
				)
			)
		)
		(property "Public" "False"
			(at 225.8 297.72 0)
			(layer "F.Fab")
			(hide yes)
			(effects
				(font
					(size 1 1)
					(thickness 0.15)
				)
			)
		)
		(property "Tolerance" "1%"
			(at 225.8 297.72 0)
			(layer "F.Fab")
			(hide yes)
			(effects
				(font
					(size 1 1)
					(thickness 0.15)
				)
			)
		)
		(property "Val" "1k"
			(at 225.8 297.72 0)
			(layer "F.Fab")
			(hide yes)
			(effects
				(font
					(size 1 1)
					(thickness 0.15)
				)
			)
		)
		(sheetname "PCIe redriver")
		(sheetfile "pcie_redriver.kicad_sch")
		(attr smd)
		(fp_rect
			(start -0.925 -0.47)
			(end 0.925 0.47)
			(stroke
				(width 0.05)
				(type default)
			)
			(fill no)
			(layer "F.CrtYd")
		)
		(fp_rect
			(start -0.5 -0.25)
			(end 0.5 0.25)
			(stroke
				(width 0.15)
				(type solid)
			)
			(fill no)
			(layer "F.Fab")
		)
		(pad "1" smd roundrect
			(at -0.48 0 180)
			(size 0.59 0.64)
			(layers "F.Cu" "F.Mask" "F.Paste")
			(roundrect_rratio 0.25)
			(net 2 "+3V3")
			(pintype "passive")
			(teardrops
				(best_length_ratio 0.2)
				(max_length 1)
				(best_width_ratio 0.9)
				(max_width 2)
				(curved_edges yes)
				(filter_ratio 0.9)
				(enabled yes)
				(allow_two_segments yes)
				(prefer_zone_connections yes)
			)
		)
		(pad "2" smd roundrect
			(at 0.48 0 180)
			(size 0.59 0.64)
			(layers "F.Cu" "F.Mask" "F.Paste")
			(roundrect_rratio 0.25)
			(net 623 "/PCIe redriver/TX_EQ0")
			(pintype "passive")
			(teardrops
				(best_length_ratio 0.2)
				(max_length 1)
				(best_width_ratio 0.9)
				(max_width 2)
				(curved_edges yes)
				(filter_ratio 0.9)
				(enabled yes)
				(allow_two_segments yes)
				(prefer_zone_connections yes)
			)
		)
	)
	(footprint "antmicro-footprints:R_0201"
		(layer "F.Cu")
		(at 137.412 147.935 -90)
		(descr "Resistor SMD 0201")
		(tags "resistor SMD 0201")
		(property "Reference" "R285"
			(at 6.475 -0.288 270)
			(layer "F.SilkS")
			(effects
				(font
					(size 0.7 0.7)
					(thickness 0.15)
				)
				(justify left bottom)
			)
		)
		(property "Value" "R_0R_0201"
			(at 0 1.25 270)
			(layer "F.Fab")
			(effects
				(font
					(size 0.7 0.7)
					(thickness 0.15)
				)
				(justify left bottom)
			)
		)
		(property "Datasheet" "https://www.bourns.com/docs/product-datasheets/cr.pdf"
			(at 0 0 270)
			(layer "F.Fab")
			(hide yes)
			(effects
				(font
					(size 1.27 1.27)
					(thickness 0.15)
				)
			)
		)
		(property "Author" "Antmicro"
			(at -10.523 285.347 0)
			(layer "F.Fab")
			(hide yes)
			(effects
				(font
					(size 1 1)
					(thickness 0.15)
				)
			)
		)
		(property "License" "Apache-2.0"
			(at -10.523 285.347 0)
			(layer "F.Fab")
			(hide yes)
			(effects
				(font
					(size 1 1)
					(thickness 0.15)
				)
			)
		)
		(property "MPN" "CR0201-FX-0R00GLF"
			(at -10.523 285.347 0)
			(layer "F.Fab")
			(hide yes)
			(effects
				(font
					(size 1 1)
					(thickness 0.15)
				)
			)
		)
		(property "Manufacturer" "Bourns"
			(at -10.523 285.347 0)
			(layer "F.Fab")
			(hide yes)
			(effects
				(font
					(size 1 1)
					(thickness 0.15)
				)
			)
		)
		(property "Tolerance" "1%"
			(at -10.523 285.347 0)
			(layer "F.Fab")
			(hide yes)
			(effects
				(font
					(size 1 1)
					(thickness 0.15)
				)
			)
		)
		(property "Val" "0R"
			(at -10.523 285.347 0)
			(layer "F.Fab")
			(hide yes)
			(effects
				(font
					(size 1 1)
					(thickness 0.15)
				)
			)
		)
		(sheetname "KR to SFI #2")
		(sheetfile "kr_sfi.kicad_sch")
		(attr smd dnp)
		(fp_rect
			(start -0.7 -0.35)
			(end 0.7 0.35)
			(stroke
				(width 0.05)
				(type default)
			)
			(fill no)
			(layer "F.CrtYd")
		)
		(fp_rect
			(start -0.3 -0.15)
			(end 0.298 0.148)
			(stroke
				(width 0.15)
				(type solid)
			)
			(fill no)
			(layer "F.Fab")
		)
		(pad "" smd roundrect
			(at -0.346 0 270)
			(size 0.318 0.36)
			(layers "F.Paste")
			(roundrect_rratio 0.25)
			(teardrops
				(best_length_ratio 0.2)
				(max_length 1)
				(best_width_ratio 0.9)
				(max_width 2)
				(curved_edges yes)
				(filter_ratio 0.9)
				(enabled yes)
				(allow_two_segments yes)
				(prefer_zone_connections yes)
			)
		)
		(pad "" smd roundrect
			(at 0.344 0 270)
			(size 0.318 0.36)
			(layers "F.Paste")
			(roundrect_rratio 0.25)
			(teardrops
				(best_length_ratio 0.2)
				(max_length 1)
				(best_width_ratio 0.9)
				(max_width 2)
				(curved_edges yes)
				(filter_ratio 0.9)
				(enabled yes)
				(allow_two_segments yes)
				(prefer_zone_connections yes)
			)
		)
		(pad "1" smd roundrect
			(at -0.32 0 270)
			(size 0.46 0.4)
			(layers "F.Cu" "F.Mask")
			(roundrect_rratio 0.25)
			(net 119 "/2xSFP+/10GKR_SFP1.TX+")
			(pintype "passive")
			(teardrops
				(best_length_ratio 0.2)
				(max_length 1)
				(best_width_ratio 0.9)
				(max_width 2)
				(curved_edges yes)
				(filter_ratio 0.9)
				(enabled yes)
				(allow_two_segments yes)
				(prefer_zone_connections yes)
			)
		)
		(pad "2" smd roundrect
			(at 0.32 0 270)
			(size 0.46 0.4)
			(layers "F.Cu" "F.Mask")
			(roundrect_rratio 0.25)
			(net 955 "/2xSFP+/KR to SFI #2/BYP_TX+")
			(pintype "passive")
			(teardrops
				(best_length_ratio 0.2)
				(max_length 1)
				(best_width_ratio 0.9)
				(max_width 2)
				(curved_edges yes)
				(filter_ratio 0.9)
				(enabled yes)
				(allow_two_segments yes)
				(prefer_zone_connections yes)
			)
		)
	)
	(footprint "antmicro-footprints:C_Pol_EIA-B"
		(layer "F.Cu")
		(at 308.825 116.435)
		(property "Reference" "C51"
			(at 2.275 0.475 0)
			(layer "F.SilkS")
			(effects
				(font
					(size 0.7 0.7)
					(thickness 0.15)
				)
				(justify left bottom)
			)
		)
		(property "Value" "C_Pol_100u_10V_KEMET-T520-B"
			(at 0 2.85 0)
			(layer "F.Fab")
			(effects
				(font
					(size 0.7 0.7)
					(thickness 0.15)
				)
				(justify left bottom)
			)
		)
		(property "Datasheet" "https://www.kemet.com/en/us/capacitors/product/T520B107M010ATE070.html"
			(at 0 0 0)
			(layer "F.Fab")
			(hide yes)
			(effects
				(font
					(size 1.27 1.27)
					(thickness 0.15)
				)
			)
		)
		(property "Author" "Antmicro"
			(at 0 0 0)
			(layer "F.Fab")
			(hide yes)
			(effects
				(font
					(size 1 1)
					(thickness 0.15)
				)
			)
		)
		(property "Dielectric" "template_dielectric"
			(at 0 0 0)
			(layer "F.Fab")
			(hide yes)
			(effects
				(font
					(size 1 1)
					(thickness 0.15)
				)
			)
		)
		(property "License" "Apache-2.0"
			(at 0 0 0)
			(layer "F.Fab")
			(hide yes)
			(effects
				(font
					(size 1 1)
					(thickness 0.15)
				)
			)
		)
		(property "MPN" "T520B107M010ATE070"
			(at 0 0 0)
			(layer "F.Fab")
			(hide yes)
			(effects
				(font
					(size 1 1)
					(thickness 0.15)
				)
			)
		)
		(property "Manufacturer" "KEMET"
			(at 0 0 0)
			(layer "F.Fab")
			(hide yes)
			(effects
				(font
					(size 1 1)
					(thickness 0.15)
				)
			)
		)
		(property "Public" "False"
			(at 0 0 0)
			(layer "F.Fab")
			(hide yes)
			(effects
				(font
					(size 1 1)
					(thickness 0.15)
				)
			)
		)
		(property "Val" "100u"
			(at 0 0 0)
			(layer "F.Fab")
			(hide yes)
			(effects
				(font
					(size 1 1)
					(thickness 0.15)
				)
			)
		)
		(property "Voltage" "10V"
			(at 0 0 0)
			(layer "F.Fab")
			(hide yes)
			(effects
				(font
					(size 1 1)
					(thickness 0.15)
				)
			)
		)
		(sheetname "Power")
		(sheetfile "power.kicad_sch")
		(attr smd)
		(fp_line
			(start -2.521 -1.676)
			(end -2.123 -1.676)
			(stroke
				(width 0.15)
				(type solid)
			)
			(layer "F.SilkS")
		)
		(fp_line
			(start -2.325 -1.475)
			(end -2.325 -1.878)
			(stroke
				(width 0.15)
				(type solid)
			)
			(layer "F.SilkS")
		)
		(fp_line
			(start -1.8 -1.6)
			(end 1.8 -1.6)
			(stroke
				(width 0.15)
				(type solid)
			)
			(layer "F.SilkS")
		)
		(fp_line
			(start -1.8 -1.3)
			(end -1.8 -1.6)
			(stroke
				(width 0.15)
				(type solid)
			)
			(layer "F.SilkS")
		)
		(fp_line
			(start -1.8 1.3)
			(end -1.8 1.6)
			(stroke
				(width 0.15)
				(type solid)
			)
			(layer "F.SilkS")
		)
		(fp_line
			(start 1.8 -1.3)
			(end 1.8 -1.6)
			(stroke
				(width 0.15)
				(type solid)
			)
			(layer "F.SilkS")
		)
		(fp_line
			(start 1.8 1.3)
			(end 1.8 1.6)
			(stroke
				(width 0.15)
				(type solid)
			)
			(layer "F.SilkS")
		)
		(fp_line
			(start 1.8 1.6)
			(end -1.8 1.6)
			(stroke
				(width 0.15)
				(type solid)
			)
			(layer "F.SilkS")
		)
		(fp_line
			(start -2.411 -1.35)
			(end -2.41 1.35)
			(stroke
				(width 0.05)
				(type solid)
			)
			(layer "F.CrtYd")
		)
		(fp_line
			(start -1.97 -1.75)
			(end -1.97 -1.35)
			(stroke
				(width 0.05)
				(type solid)
			)
			(layer "F.CrtYd")
		)
		(fp_line
			(start -1.97 -1.35)
			(end -2.41 -1.35)
			(stroke
				(width 0.05)
				(type solid)
			)
			(layer "F.CrtYd")
		)
		(fp_line
			(start -1.97 1.35)
			(end -2.41 1.35)
			(stroke
				(width 0.05)
				(type solid)
			)
			(layer "F.CrtYd")
		)
		(fp_line
			(start -1.97 1.35)
			(end -1.97 1.75)
			(stroke
				(width 0.05)
				(type solid)
			)
			(layer "F.CrtYd")
		)
		(fp_line
			(start 1.959 -1.75)
			(end -1.97 -1.75)
			(stroke
				(width 0.05)
				(type solid)
			)
			(layer "F.CrtYd")
		)
		(fp_line
			(start 1.959 -1.75)
			(end 1.959 -1.35)
			(stroke
				(width 0.05)
				(type solid)
			)
			(layer "F.CrtYd")
		)
		(fp_line
			(start 1.96 1.35)
			(end 1.96 1.75)
			(stroke
				(width 0.05)
				(type solid)
			)
			(layer "F.CrtYd")
		)
		(fp_line
			(start 1.96 1.75)
			(end -1.97 1.75)
			(stroke
				(width 0.05)
				(type solid)
			)
			(layer "F.CrtYd")
		)
		(fp_line
			(start 2.399 -1.35)
			(end 1.959 -1.35)
			(stroke
				(width 0.05)
				(type solid)
			)
			(layer "F.CrtYd")
		)
		(fp_line
			(start 2.399 -1.35)
			(end 2.4 1.35)
			(stroke
				(width 0.05)
				(type solid)
			)
			(layer "F.CrtYd")
		)
		(fp_line
			(start 2.4 1.35)
			(end 1.96 1.35)
			(stroke
				(width 0.05)
				(type solid)
			)
			(layer "F.CrtYd")
		)
		(fp_line
			(start -1.7 1.324)
			(end -1.551 1.475)
			(stroke
				(width 0.15)
				(type solid)
			)
			(layer "F.Fab")
		)
		(fp_rect
			(start -1.72 -1.5)
			(end 1.719 1.499)
			(stroke
				(width 0.15)
				(type solid)
			)
			(fill no)
			(layer "F.Fab")
		)
		(pad "1" smd roundrect
			(at -1.551 0)
			(size 1.2 2.2)
			(layers "F.Cu" "F.Mask" "F.Paste")
			(roundrect_rratio 0.1)
			(net 70 "Net-(C49-Pad2)")
			(pintype "passive")
			(teardrops
				(best_length_ratio 0.2)
				(max_length 1)
				(best_width_ratio 0.9)
				(max_width 2)
				(curved_edges yes)
				(filter_ratio 0.9)
				(enabled yes)
				(allow_two_segments yes)
				(prefer_zone_connections yes)
			)
		)
		(pad "2" smd roundrect
			(at 1.55 0)
			(size 1.2 2.2)
			(layers "F.Cu" "F.Mask" "F.Paste")
			(roundrect_rratio 0.1)
			(net 1 "GND")
			(pintype "passive")
			(teardrops
				(best_length_ratio 0.2)
				(max_length 1)
				(best_width_ratio 0.9)
				(max_width 2)
				(curved_edges yes)
				(filter_ratio 0.9)
				(enabled yes)
				(allow_two_segments yes)
				(prefer_zone_connections yes)
			)
		)
	)
	(footprint "antmicro-footprints:TP_SMD_0.75mm"
		(layer "F.Cu")
		(at 199.70861 72.802163 -90)
		(property "Reference" "TP99"
			(at 0 -0.6 90)
			(layer "F.SilkS")
			(hide yes)
			(effects
				(font
					(size 0.7 0.7)
					(thickness 0.15)
				)
				(justify right bottom)
			)
		)
		(property "Value" "TP_0.75mm_SMD"
			(at 0 1.2 90)
			(layer "F.Fab")
			(effects
				(font
					(size 0.7 0.7)
					(thickness 0.15)
				)
				(justify right bottom)
			)
		)
		(property "Author" "Antmicro"
			(at 126.906447 272.510773 0)
			(layer "F.Fab")
			(hide yes)
			(effects
				(font
					(size 1 1)
					(thickness 0.15)
				)
			)
		)
		(property "License" "Apache-2.0"
			(at 126.906447 272.510773 0)
			(layer "F.Fab")
			(hide yes)
			(effects
				(font
					(size 1 1)
					(thickness 0.15)
				)
			)
		)
		(property "MPN" ""
			(at 126.906447 272.510773 0)
			(layer "F.Fab")
			(hide yes)
			(effects
				(font
					(size 1 1)
					(thickness 0.15)
				)
			)
		)
		(property "Manufacturer" ""
			(at 126.906447 272.510773 0)
			(layer "F.Fab")
			(hide yes)
			(effects
				(font
					(size 1 1)
					(thickness 0.15)
				)
			)
		)
		(property "Public" "False"
			(at 126.906447 272.510773 0)
			(layer "F.Fab")
			(hide yes)
			(effects
				(font
					(size 1 1)
					(thickness 0.15)
				)
			)
		)
		(sheetname "Power")
		(sheetfile "power.kicad_sch")
		(attr exclude_from_pos_files exclude_from_bom)
		(fp_circle
			(center 0 0)
			(end 0.475 0)
			(stroke
				(width 0.05)
				(type default)
			)
			(fill no)
			(layer "F.CrtYd")
		)
		(pad "1" smd circle
			(at 0 0 270)
			(size 0.75 0.75)
			(layers "F.Cu" "F.Mask")
			(net 78 "+1V8")
			(pinfunction "1")
			(pintype "passive")
			(teardrops
				(best_length_ratio 0.4)
				(max_length 1)
				(best_width_ratio 0.9)
				(max_width 2)
				(curved_edges yes)
				(filter_ratio 0.9)
				(enabled yes)
				(allow_two_segments yes)
				(prefer_zone_connections yes)
			)
		)
	)
	(footprint "antmicro-footprints:C_0603_1608Metric"
		(layer "F.Cu")
		(at 315.6005 95.1365 90)
		(descr "Capacitor SMD 0603")
		(tags "capacitor 0603")
		(property "Reference" "C58"
			(at 1.1765 0.4495 90)
			(layer "F.SilkS")
			(effects
				(font
					(size 0.7 0.7)
					(thickness 0.15)
				)
				(justify left bottom)
			)
		)
		(property "Value" "C_22u_16V_0603"
			(at -1.42757 1.770288 90)
			(layer "F.Fab")
			(effects
				(font
					(size 0.7 0.7)
					(thickness 0.15)
				)
				(justify left bottom)
			)
		)
		(property "Datasheet" "https://product.samsungsem.com/mlcc/CL10A226MO7JZN.do"
			(at 0 0 90)
			(layer "F.Fab")
			(hide yes)
			(effects
				(font
					(size 1.27 1.27)
					(thickness 0.15)
				)
			)
		)
		(property "Author" "Antmicro"
			(at 410.737 -220.464 0)
			(layer "F.Fab")
			(hide yes)
			(effects
				(font
					(size 1 1)
					(thickness 0.15)
				)
			)
		)
		(property "Dielectric" ""
			(at 410.737 -220.464 0)
			(layer "F.Fab")
			(hide yes)
			(effects
				(font
					(size 1 1)
					(thickness 0.15)
				)
			)
		)
		(property "License" "Apache-2.0"
			(at 410.737 -220.464 0)
			(layer "F.Fab")
			(hide yes)
			(effects
				(font
					(size 1 1)
					(thickness 0.15)
				)
			)
		)
		(property "MPN" "CL10A226MO7JZNC"
			(at 410.737 -220.464 0)
			(layer "F.Fab")
			(hide yes)
			(effects
				(font
					(size 1 1)
					(thickness 0.15)
				)
			)
		)
		(property "Manufacturer" "Samsung Electro-Mechanics"
			(at 410.737 -220.464 0)
			(layer "F.Fab")
			(hide yes)
			(effects
				(font
					(size 1 1)
					(thickness 0.15)
				)
			)
		)
		(property "Public" "False"
			(at 410.737 -220.464 0)
			(layer "F.Fab")
			(hide yes)
			(effects
				(font
					(size 1 1)
					(thickness 0.15)
				)
			)
		)
		(property "Val" "22u"
			(at 410.737 -220.464 0)
			(layer "F.Fab")
			(hide yes)
			(effects
				(font
					(size 1 1)
					(thickness 0.15)
				)
			)
		)
		(property "Voltage" "16V"
			(at 410.737 -220.464 0)
			(layer "F.Fab")
			(hide yes)
			(effects
				(font
					(size 1 1)
					(thickness 0.15)
				)
			)
		)
		(sheetname "Power")
		(sheetfile "power.kicad_sch")
		(attr smd)
		(fp_line
			(start -0.15 -0.4)
			(end 0.15 -0.4)
			(stroke
				(width 0.15)
				(type solid)
			)
			(layer "F.SilkS")
		)
		(fp_line
			(start -0.15 0.4)
			(end 0.15 0.4)
			(stroke
				(width 0.15)
				(type solid)
			)
			(layer "F.SilkS")
		)
		(fp_rect
			(start -1.25 -0.65)
			(end 1.25 0.65)
			(stroke
				(width 0.05)
				(type solid)
			)
			(fill no)
			(layer "F.CrtYd")
		)
		(fp_rect
			(start -0.8 -0.4)
			(end 0.8 0.4)
			(stroke
				(width 0.15)
				(type solid)
			)
			(fill no)
			(layer "F.Fab")
		)
		(pad "1" smd roundrect
			(at -0.7 0 90)
			(size 0.8 1)
			(layers "F.Cu" "F.Mask" "F.Paste")
			(roundrect_rratio 0.2)
			(net 1 "GND")
			(pintype "passive")
			(teardrops
				(best_length_ratio 0.2)
				(max_length 1)
				(best_width_ratio 0.9)
				(max_width 2)
				(curved_edges yes)
				(filter_ratio 0.9)
				(enabled yes)
				(allow_two_segments yes)
				(prefer_zone_connections yes)
			)
		)
		(pad "2" smd roundrect
			(at 0.7 0 90)
			(size 0.8 1)
			(layers "F.Cu" "F.Mask" "F.Paste")
			(roundrect_rratio 0.2)
			(net 62 "+12V_AON")
			(pintype "passive")
			(teardrops
				(best_length_ratio 0.2)
				(max_length 1)
				(best_width_ratio 0.9)
				(max_width 2)
				(curved_edges yes)
				(filter_ratio 0.9)
				(enabled yes)
				(allow_two_segments yes)
				(prefer_zone_connections yes)
			)
		)
	)
	(footprint "antmicro-footprints:Choke_0805_2012Metric"
		(layer "F.Cu")
		(at 127.25 109.42 180)
		(property "Reference" "T3"
			(at 1.6 -1.85 0)
			(unlocked yes)
			(layer "F.SilkS")
			(effects
				(font
					(size 0.7 0.7)
					(thickness 0.15)
				)
				(justify left bottom)
			)
		)
		(property "Value" "Choke_SRF2012A-801Y"
			(at 0 -7 180)
			(unlocked yes)
			(layer "F.Fab")
			(effects
				(font
					(size 0.7 0.7)
					(thickness 0.15)
				)
				(justify left bottom)
			)
		)
		(property "Datasheet" "https://www.bourns.com/docs/product-datasheets/srf2012a-801y.pdf"
			(at 0 0 180)
			(layer "F.Fab")
			(hide yes)
			(effects
				(font
					(size 1.27 1.27)
					(thickness 0.15)
				)
			)
		)
		(property "Author" "Antmicro"
			(at 254.5 218.84 0)
			(layer "F.Fab")
			(hide yes)
			(effects
				(font
					(size 1 1)
					(thickness 0.15)
				)
			)
		)
		(property "IMax" "0.3 A"
			(at 254.5 218.84 0)
			(layer "F.Fab")
			(hide yes)
			(effects
				(font
					(size 1 1)
					(thickness 0.15)
				)
			)
		)
		(property "License" "Apache-2.0"
			(at 254.5 218.84 0)
			(layer "F.Fab")
			(hide yes)
			(effects
				(font
					(size 1 1)
					(thickness 0.15)
				)
			)
		)
		(property "MPN" "SRF2012A-801Y"
			(at 254.5 218.84 0)
			(layer "F.Fab")
			(hide yes)
			(effects
				(font
					(size 1 1)
					(thickness 0.15)
				)
			)
		)
		(property "Manufacturer" "Bourns"
			(at 254.5 218.84 0)
			(layer "F.Fab")
			(hide yes)
			(effects
				(font
					(size 1 1)
					(thickness 0.15)
				)
			)
		)
		(property "Public" "False"
			(at 254.5 218.84 0)
			(layer "F.Fab")
			(hide yes)
			(effects
				(font
					(size 1 1)
					(thickness 0.15)
				)
			)
		)
		(property ki_fp_filters "IND_ACM9070_TDK")
		(sheetname "2xUSB3.0+RJ45")
		(sheetfile "usb3+rj45.kicad_sch")
		(attr smd)
		(fp_rect
			(start -1.5 -0.9)
			(end 1.5 0.9)
			(stroke
				(width 0.05)
				(type solid)
			)
			(fill no)
			(layer "F.CrtYd")
		)
		(pad "1" smd roundrect
			(at -0.96 -0.46 180)
			(size 0.675 0.475)
			(layers "F.Cu" "F.Mask" "F.Paste")
			(roundrect_rratio 0.25)
			(net 693 "/2xUSB3.0+RJ45/DC_FL+")
			(pinfunction "1")
			(pintype "passive")
			(teardrops
				(best_length_ratio 0.2)
				(max_length 1)
				(best_width_ratio 0.9)
				(max_width 2)
				(curved_edges yes)
				(filter_ratio 0.9)
				(enabled yes)
				(allow_two_segments yes)
				(prefer_zone_connections yes)
			)
		)
		(pad "2" smd roundrect
			(at 0.96 -0.46 180)
			(size 0.675 0.475)
			(layers "F.Cu" "F.Mask" "F.Paste")
			(roundrect_rratio 0.25)
			(net 149 "/2xUSB3.0+RJ45/DC+")
			(pinfunction "2")
			(pintype "passive")
			(teardrops
				(best_length_ratio 0.2)
				(max_length 1)
				(best_width_ratio 0.9)
				(max_width 2)
				(curved_edges yes)
				(filter_ratio 0.9)
				(enabled yes)
				(allow_two_segments yes)
				(prefer_zone_connections yes)
			)
		)
		(pad "3" smd roundrect
			(at 0.96 0.46 180)
			(size 0.675 0.475)
			(layers "F.Cu" "F.Mask" "F.Paste")
			(roundrect_rratio 0.25)
			(net 150 "/2xUSB3.0+RJ45/DC-")
			(pinfunction "3")
			(pintype "passive")
			(teardrops
				(best_length_ratio 0.2)
				(max_length 1)
				(best_width_ratio 0.9)
				(max_width 2)
				(curved_edges yes)
				(filter_ratio 0.9)
				(enabled yes)
				(allow_two_segments yes)
				(prefer_zone_connections yes)
			)
		)
		(pad "4" smd roundrect
			(at -0.96 0.46 180)
			(size 0.675 0.475)
			(layers "F.Cu" "F.Mask" "F.Paste")
			(roundrect_rratio 0.25)
			(net 694 "/2xUSB3.0+RJ45/DC_FL-")
			(pinfunction "4")
			(pintype "passive")
			(teardrops
				(best_length_ratio 0.2)
				(max_length 1)
				(best_width_ratio 0.9)
				(max_width 2)
				(curved_edges yes)
				(filter_ratio 0.9)
				(enabled yes)
				(allow_two_segments yes)
				(prefer_zone_connections yes)
			)
		)
	)
	(footprint "antmicro-footprints:TP_SMD_0.75mm"
		(layer "F.Cu")
		(at 130.39 129.56)
		(property "Reference" "TP88"
			(at 0.46 -1.25 90)
			(layer "F.SilkS")
			(effects
				(font
					(size 0.7 0.7)
					(thickness 0.15)
				)
				(justify left bottom)
			)
		)
		(property "Value" "TP_0.75mm_SMD"
			(at 0 1.2 0)
			(layer "F.Fab")
			(effects
				(font
					(size 0.7 0.7)
					(thickness 0.15)
				)
				(justify left bottom)
			)
		)
		(property "Author" "Antmicro"
			(at 0 0 0)
			(layer "F.Fab")
			(hide yes)
			(effects
				(font
					(size 1 1)
					(thickness 0.15)
				)
			)
		)
		(property "License" "Apache-2.0"
			(at 0 0 0)
			(layer "F.Fab")
			(hide yes)
			(effects
				(font
					(size 1 1)
					(thickness 0.15)
				)
			)
		)
		(property "MPN" ""
			(at 0 0 0)
			(layer "F.Fab")
			(hide yes)
			(effects
				(font
					(size 1 1)
					(thickness 0.15)
				)
			)
		)
		(property "Manufacturer" ""
			(at 0 0 0)
			(layer "F.Fab")
			(hide yes)
			(effects
				(font
					(size 1 1)
					(thickness 0.15)
				)
			)
		)
		(property "Public" "False"
			(at 0 0 0)
			(layer "F.Fab")
			(hide yes)
			(effects
				(font
					(size 1 1)
					(thickness 0.15)
				)
			)
		)
		(sheetname "KR to SFI #2")
		(sheetfile "kr_sfi.kicad_sch")
		(attr exclude_from_pos_files exclude_from_bom)
		(fp_circle
			(center 0 0)
			(end 0.475 0)
			(stroke
				(width 0.05)
				(type default)
			)
			(fill no)
			(layer "F.CrtYd")
		)
		(pad "1" smd circle
			(at 0 0)
			(size 0.75 0.75)
			(layers "F.Cu" "F.Mask")
			(net 751 "Net-(U45C-CLKOUTA-)")
			(pinfunction "1")
			(pintype "passive")
			(teardrops
				(best_length_ratio 0.4)
				(max_length 1)
				(best_width_ratio 0.9)
				(max_width 2)
				(curved_edges yes)
				(filter_ratio 0.9)
				(enabled yes)
				(allow_two_segments yes)
				(prefer_zone_connections yes)
			)
		)
	)
	(footprint "antmicro-footprints:R_0402_1005Metric"
		(layer "F.Cu")
		(at 143.45 84.06)
		(descr "Resistor SMD 0402")
		(tags "resistor SMD 0402")
		(property "Reference" "R132"
			(at -3.7 0.45 0)
			(layer "F.SilkS")
			(effects
				(font
					(size 0.7 0.7)
					(thickness 0.15)
				)
				(justify left bottom)
			)
		)
		(property "Value" "R_0R_0402"
			(at -1.011843 1.772047 0)
			(layer "F.Fab")
			(effects
				(font
					(size 0.7 0.7)
					(thickness 0.15)
				)
				(justify left bottom)
			)
		)
		(property "Datasheet" "https://industrial.panasonic.com/cdbs/www-data/pdf/RDA0000/AOA0000C301.pdf"
			(at 0 0 0)
			(layer "F.Fab")
			(hide yes)
			(effects
				(font
					(size 1.27 1.27)
					(thickness 0.15)
				)
			)
		)
		(property "Author" "Antmicro"
			(at 0 0 0)
			(layer "F.Fab")
			(hide yes)
			(effects
				(font
					(size 1 1)
					(thickness 0.15)
				)
			)
		)
		(property "Current" "1A"
			(at 0 0 0)
			(layer "F.Fab")
			(hide yes)
			(effects
				(font
					(size 1 1)
					(thickness 0.15)
				)
			)
		)
		(property "License" "Apache-2.0"
			(at 0 0 0)
			(layer "F.Fab")
			(hide yes)
			(effects
				(font
					(size 1 1)
					(thickness 0.15)
				)
			)
		)
		(property "MPN" "ERJ2GE0R00X"
			(at 0 0 0)
			(layer "F.Fab")
			(hide yes)
			(effects
				(font
					(size 1 1)
					(thickness 0.15)
				)
			)
		)
		(property "Manufacturer" "Panasonic"
			(at 0 0 0)
			(layer "F.Fab")
			(hide yes)
			(effects
				(font
					(size 1 1)
					(thickness 0.15)
				)
			)
		)
		(property "Public" "False"
			(at 0 0 0)
			(layer "F.Fab")
			(hide yes)
			(effects
				(font
					(size 1 1)
					(thickness 0.15)
				)
			)
		)
		(property "Tolerance" ""
			(at 0 0 0)
			(layer "F.Fab")
			(hide yes)
			(effects
				(font
					(size 1 1)
					(thickness 0.15)
				)
			)
		)
		(property "Val" "0R"
			(at 0 0 0)
			(layer "F.Fab")
			(hide yes)
			(effects
				(font
					(size 1 1)
					(thickness 0.15)
				)
			)
		)
		(sheetname "M.2 key E")
		(sheetfile "m2keye.kicad_sch")
		(attr smd)
		(fp_rect
			(start -0.925 -0.47)
			(end 0.925 0.47)
			(stroke
				(width 0.05)
				(type default)
			)
			(fill no)
			(layer "F.CrtYd")
		)
		(fp_rect
			(start -0.5 -0.25)
			(end 0.5 0.25)
			(stroke
				(width 0.15)
				(type solid)
			)
			(fill no)
			(layer "F.Fab")
		)
		(pad "1" smd roundrect
			(at -0.48 0)
			(size 0.59 0.64)
			(layers "F.Cu" "F.Mask" "F.Paste")
			(roundrect_rratio 0.25)
			(net 528 "/Backplane/~{PERST}")
			(pintype "passive")
			(teardrops
				(best_length_ratio 0.2)
				(max_length 1)
				(best_width_ratio 0.9)
				(max_width 2)
				(curved_edges yes)
				(filter_ratio 0.9)
				(enabled yes)
				(allow_two_segments yes)
				(prefer_zone_connections yes)
			)
		)
		(pad "2" smd roundrect
			(at 0.48 0)
			(size 0.59 0.64)
			(layers "F.Cu" "F.Mask" "F.Paste")
			(roundrect_rratio 0.25)
			(net 23 "/M.2 key E/~{PERST_D}")
			(pintype "passive")
			(teardrops
				(best_length_ratio 0.2)
				(max_length 1)
				(best_width_ratio 0.9)
				(max_width 2)
				(curved_edges yes)
				(filter_ratio 0.9)
				(enabled yes)
				(allow_two_segments yes)
				(prefer_zone_connections yes)
			)
		)
	)
	(footprint "antmicro-footprints:R_0402_1005Metric"
		(layer "F.Cu")
		(at 134.425 84.310001)
		(descr "Resistor SMD 0402")
		(tags "resistor SMD 0402")
		(property "Reference" "R231"
			(at 0.775 0.449999 0)
			(layer "F.SilkS")
			(effects
				(font
					(size 0.7 0.7)
					(thickness 0.15)
				)
				(justify left bottom)
			)
		)
		(property "Value" "R_0R_0402"
			(at -1.011843 1.772047 0)
			(layer "F.Fab")
			(effects
				(font
					(size 0.7 0.7)
					(thickness 0.15)
				)
				(justify left bottom)
			)
		)
		(property "Datasheet" "https://industrial.panasonic.com/cdbs/www-data/pdf/RDA0000/AOA0000C301.pdf"
			(at 0 0 0)
			(layer "F.Fab")
			(hide yes)
			(effects
				(font
					(size 1.27 1.27)
					(thickness 0.15)
				)
			)
		)
		(property "Author" "Antmicro"
			(at 0 0 0)
			(layer "F.Fab")
			(hide yes)
			(effects
				(font
					(size 1 1)
					(thickness 0.15)
				)
			)
		)
		(property "Current" "1A"
			(at 0 0 0)
			(layer "F.Fab")
			(hide yes)
			(effects
				(font
					(size 1 1)
					(thickness 0.15)
				)
			)
		)
		(property "License" "Apache-2.0"
			(at 0 0 0)
			(layer "F.Fab")
			(hide yes)
			(effects
				(font
					(size 1 1)
					(thickness 0.15)
				)
			)
		)
		(property "MPN" "ERJ2GE0R00X"
			(at 0 0 0)
			(layer "F.Fab")
			(hide yes)
			(effects
				(font
					(size 1 1)
					(thickness 0.15)
				)
			)
		)
		(property "Manufacturer" "Panasonic"
			(at 0 0 0)
			(layer "F.Fab")
			(hide yes)
			(effects
				(font
					(size 1 1)
					(thickness 0.15)
				)
			)
		)
		(property "Public" "False"
			(at 0 0 0)
			(layer "F.Fab")
			(hide yes)
			(effects
				(font
					(size 1 1)
					(thickness 0.15)
				)
			)
		)
		(property "Tolerance" ""
			(at 0 0 0)
			(layer "F.Fab")
			(hide yes)
			(effects
				(font
					(size 1 1)
					(thickness 0.15)
				)
			)
		)
		(property "Val" "0R"
			(at 0 0 0)
			(layer "F.Fab")
			(hide yes)
			(effects
				(font
					(size 1 1)
					(thickness 0.15)
				)
			)
		)
		(sheetname "GPIO expander")
		(sheetfile "gpio_exp.kicad_sch")
		(attr smd dnp)
		(fp_rect
			(start -0.925 -0.47)
			(end 0.925 0.47)
			(stroke
				(width 0.05)
				(type default)
			)
			(fill no)
			(layer "F.CrtYd")
		)
		(fp_rect
			(start -0.5 -0.25)
			(end 0.5 0.25)
			(stroke
				(width 0.15)
				(type solid)
			)
			(fill no)
			(layer "F.Fab")
		)
		(pad "1" smd roundrect
			(at -0.48 0)
			(size 0.59 0.64)
			(layers "F.Cu" "F.Mask" "F.Paste")
			(roundrect_rratio 0.25)
			(net 633 "Net-(U41-A0)")
			(pintype "passive")
			(teardrops
				(best_length_ratio 0.2)
				(max_length 1)
				(best_width_ratio 0.9)
				(max_width 2)
				(curved_edges yes)
				(filter_ratio 0.9)
				(enabled yes)
				(allow_two_segments yes)
				(prefer_zone_connections yes)
			)
		)
		(pad "2" smd roundrect
			(at 0.48 0)
			(size 0.59 0.64)
			(layers "F.Cu" "F.Mask" "F.Paste")
			(roundrect_rratio 0.25)
			(net 2 "+3V3")
			(pintype "passive")
			(teardrops
				(best_length_ratio 0.2)
				(max_length 1)
				(best_width_ratio 0.9)
				(max_width 2)
				(curved_edges yes)
				(filter_ratio 0.9)
				(enabled yes)
				(allow_two_segments yes)
				(prefer_zone_connections yes)
			)
		)
	)
	(footprint "antmicro-footprints:TP_SMD_0.75mm"
		(layer "F.Cu")
		(at 138.85 128.71)
		(property "Reference" "TP90"
			(at 0.5 -3.3 90)
			(layer "F.SilkS")
			(effects
				(font
					(size 0.7 0.7)
					(thickness 0.15)
				)
				(justify left bottom)
			)
		)
		(property "Value" "TP_0.75mm_SMD"
			(at 0 1.2 0)
			(layer "F.Fab")
			(effects
				(font
					(size 0.7 0.7)
					(thickness 0.15)
				)
				(justify left bottom)
			)
		)
		(property "Author" "Antmicro"
			(at 0 0 0)
			(layer "F.Fab")
			(hide yes)
			(effects
				(font
					(size 1 1)
					(thickness 0.15)
				)
			)
		)
		(property "License" "Apache-2.0"
			(at 0 0 0)
			(layer "F.Fab")
			(hide yes)
			(effects
				(font
					(size 1 1)
					(thickness 0.15)
				)
			)
		)
		(property "MPN" ""
			(at 0 0 0)
			(layer "F.Fab")
			(hide yes)
			(effects
				(font
					(size 1 1)
					(thickness 0.15)
				)
			)
		)
		(property "Manufacturer" ""
			(at 0 0 0)
			(layer "F.Fab")
			(hide yes)
			(effects
				(font
					(size 1 1)
					(thickness 0.15)
				)
			)
		)
		(property "Public" "False"
			(at 0 0 0)
			(layer "F.Fab")
			(hide yes)
			(effects
				(font
					(size 1 1)
					(thickness 0.15)
				)
			)
		)
		(sheetname "KR to SFI #2")
		(sheetfile "kr_sfi.kicad_sch")
		(attr exclude_from_pos_files exclude_from_bom)
		(fp_circle
			(center 0 0)
			(end 0.475 0)
			(stroke
				(width 0.05)
				(type default)
			)
			(fill no)
			(layer "F.CrtYd")
		)
		(pad "1" smd circle
			(at 0 0)
			(size 0.75 0.75)
			(layers "F.Cu" "F.Mask")
			(net 753 "Net-(U45C-CLKOUTB-)")
			(pinfunction "1")
			(pintype "passive")
			(teardrops
				(best_length_ratio 0.4)
				(max_length 1)
				(best_width_ratio 0.9)
				(max_width 2)
				(curved_edges yes)
				(filter_ratio 0.9)
				(enabled yes)
				(allow_two_segments yes)
				(prefer_zone_connections yes)
			)
		)
	)
	(footprint "antmicro-footprints:Spacer_Drill3.7mm_H5mm_9774050151R"
		(layer "F.Cu")
		(at 161.93 80.8 90)
		(descr "Spacer M=3 h=5mm fi=5.1mm")
		(property "Reference" "H7"
			(at 0 -3.2 90)
			(layer "F.SilkS")
			(hide yes)
			(effects
				(font
					(size 0.7 0.7)
					(thickness 0.15)
				)
				(justify left bottom)
			)
		)
		(property "Value" "Spacer_Drill3.7mm_H5mm_9774050151R"
			(at 0 4 90)
			(layer "F.Fab")
			(effects
				(font
					(size 0.7 0.7)
					(thickness 0.15)
				)
				(justify left bottom)
			)
		)
		(property "Datasheet" "https://www.we-online.com/catalog/datasheet/9774050151.pdf"
			(at 0 0 90)
			(layer "F.Fab")
			(hide yes)
			(effects
				(font
					(size 1.27 1.27)
					(thickness 0.15)
				)
			)
		)
		(property "Author" "Antmicro"
			(at 242.74 -81.12 0)
			(layer "F.Fab")
			(hide yes)
			(effects
				(font
					(size 1 1)
					(thickness 0.15)
				)
			)
		)
		(property "License" "Apache-2.0"
			(at 242.74 -81.12 0)
			(layer "F.Fab")
			(hide yes)
			(effects
				(font
					(size 1 1)
					(thickness 0.15)
				)
			)
		)
		(property "MPN" "9774050151R"
			(at 242.74 -81.12 0)
			(layer "F.Fab")
			(hide yes)
			(effects
				(font
					(size 1 1)
					(thickness 0.15)
				)
			)
		)
		(property "Manufacturer" "Würth Elektronik"
			(at 242.74 -81.12 0)
			(layer "F.Fab")
			(hide yes)
			(effects
				(font
					(size 1 1)
					(thickness 0.15)
				)
			)
		)
		(sheetname "Com Express 7 Interfaces")
		(sheetfile "com_express_7_interfaces.kicad_sch")
		(solder_paste_margin_ratio -1)
		(attr smd)
		(fp_circle
			(center 0 0)
			(end 3.05 0)
			(stroke
				(width 0.05)
				(type solid)
			)
			(fill no)
			(layer "F.CrtYd")
		)
		(fp_circle
			(center 0 0)
			(end 2.6 0)
			(stroke
				(width 0.15)
				(type solid)
			)
			(fill no)
			(layer "F.Fab")
		)
		(pad "" smd custom
			(at -1.7 -1.7 90)
			(size 0.62 0.62)
			(layers "F.Paste")
			(thermal_bridge_angle 90)
			(options
				(clearance outline)
				(anchor circle)
			)
			(primitives
				(gr_arc
					(start -0.250195 1.279127)
					(mid 0.285453 0.294389)
					(end 1.266786 -0.24747)
					(width 0.2)
				)
				(gr_arc
					(start -0.34334 1.279127)
					(mid 0.218448 0.232561)
					(end 1.259603 -0.339191)
					(width 0.2)
				)
				(gr_arc
					(start -0.436309 1.279127)
					(mid 0.152481 0.169693)
					(end 1.255279 -0.431435)
					(width 0.2)
				)
				(gr_arc
					(start -0.529126 1.279127)
					(mid 0.087542 0.105784)
					(end 1.253811 -0.524161)
					(width 0.2)
				)
				(gr_arc
					(start -0.621807 1.279127)
					(mid 0.0309 0.033527)
					(end 1.275473 -0.621136)
					(width 0.2)
				)
				(gr_arc
					(start -0.71437 1.279127)
					(mid -0.037758 -0.026651)
					(end 1.263664 -0.711602)
					(width 0.2)
				)
				(gr_arc
					(start -0.806826 1.279127)
					(mid -0.105837 -0.087395)
					(end 1.253435 -0.802342)
					(width 0.2)
				)
				(gr_arc
					(start -0.899187 1.279127)
					(mid -0.165236 -0.156885)
					(end 1.267475 -0.897258)
					(width 0.2)
				)
				(gr_arc
					(start -0.991463 1.279127)
					(mid -0.228522 -0.222449)
					(end 1.270645 -0.990112)
					(width 0.2)
				)
				(gr_arc
					(start -1.083663 1.279127)
					(mid -0.294507 -0.285313)
					(end 1.266278 -1.081674)
					(width 0.2)
				)
				(gr_line
					(start 1.279127 -0.250195)
					(end 1.279127 -1.083663)
					(width 0.2)
				)
				(gr_line
					(start -0.250195 1.279127)
					(end -1.083663 1.279127)
					(width 0.2)
				)
			)
			(teardrops
				(best_length_ratio 0.2)
				(max_length 1)
				(best_width_ratio 0.9)
				(max_width 2)
				(curved_edges yes)
				(filter_ratio 0.9)
				(enabled yes)
				(allow_two_segments yes)
				(prefer_zone_connections yes)
			)
		)
		(pad "" smd custom
			(at -1.7 1.7 180)
			(size 0.62 0.62)
			(layers "F.Paste")
			(thermal_bridge_angle 90)
			(options
				(clearance outline)
				(anchor circle)
			)
			(primitives
				(gr_arc
					(start -0.250195 1.279127)
					(mid 0.285453 0.294389)
					(end 1.266786 -0.24747)
					(width 0.2)
				)
				(gr_arc
					(start -0.34334 1.279127)
					(mid 0.218448 0.232561)
					(end 1.259603 -0.339191)
					(width 0.2)
				)
				(gr_arc
					(start -0.436309 1.279127)
					(mid 0.152481 0.169693)
					(end 1.255279 -0.431435)
					(width 0.2)
				)
				(gr_arc
					(start -0.529126 1.279127)
					(mid 0.087542 0.105784)
					(end 1.253811 -0.524161)
					(width 0.2)
				)
				(gr_arc
					(start -0.621807 1.279127)
					(mid 0.0309 0.033527)
					(end 1.275473 -0.621136)
					(width 0.2)
				)
				(gr_arc
					(start -0.71437 1.279127)
					(mid -0.037758 -0.026651)
					(end 1.263664 -0.711602)
					(width 0.2)
				)
				(gr_arc
					(start -0.806826 1.279127)
					(mid -0.105837 -0.087395)
					(end 1.253435 -0.802342)
					(width 0.2)
				)
				(gr_arc
					(start -0.899187 1.279127)
					(mid -0.165236 -0.156885)
					(end 1.267475 -0.897258)
					(width 0.2)
				)
				(gr_arc
					(start -0.991463 1.279127)
					(mid -0.228522 -0.222449)
					(end 1.270645 -0.990112)
					(width 0.2)
				)
				(gr_arc
					(start -1.083663 1.279127)
					(mid -0.294507 -0.285313)
					(end 1.266278 -1.081674)
					(width 0.2)
				)
				(gr_line
					(start 1.279127 -0.250195)
					(end 1.279127 -1.083663)
					(width 0.2)
				)
				(gr_line
					(start -0.250195 1.279127)
					(end -1.083663 1.279127)
					(width 0.2)
				)
			)
			(teardrops
				(best_length_ratio 0.2)
				(max_length 1)
				(best_width_ratio 0.9)
				(max_width 2)
				(curved_edges yes)
				(filter_ratio 0.9)
				(enabled yes)
				(allow_two_segments yes)
				(prefer_zone_connections yes)
			)
		)
		(pad "" smd custom
			(at 1.7 -1.7)
			(size 0.62 0.62)
			(layers "F.Paste")
			(thermal_bridge_angle 90)
			(options
				(clearance outline)
				(anchor circle)
			)
			(primitives
				(gr_arc
					(start -0.250195 1.279127)
					(mid 0.285453 0.294389)
					(end 1.266786 -0.24747)
					(width 0.2)
				)
				(gr_arc
					(start -0.34334 1.279127)
					(mid 0.218448 0.232561)
					(end 1.259603 -0.339191)
					(width 0.2)
				)
				(gr_arc
					(start -0.436309 1.279127)
					(mid 0.152481 0.169693)
					(end 1.255279 -0.431435)
					(width 0.2)
				)
				(gr_arc
					(start -0.529126 1.279127)
					(mid 0.087542 0.105784)
					(end 1.253811 -0.524161)
					(width 0.2)
				)
				(gr_arc
					(start -0.621807 1.279127)
					(mid 0.0309 0.033527)
					(end 1.275473 -0.621136)
					(width 0.2)
				)
				(gr_arc
					(start -0.71437 1.279127)
					(mid -0.037758 -0.026651)
					(end 1.263664 -0.711602)
					(width 0.2)
				)
				(gr_arc
					(start -0.806826 1.279127)
					(mid -0.105837 -0.087395)
					(end 1.253435 -0.802342)
					(width 0.2)
				)
				(gr_arc
					(start -0.899187 1.279127)
					(mid -0.165236 -0.156885)
					(end 1.267475 -0.897258)
					(width 0.2)
				)
				(gr_arc
					(start -0.991463 1.279127)
					(mid -0.228522 -0.222449)
					(end 1.270645 -0.990112)
					(width 0.2)
				)
				(gr_arc
					(start -1.083663 1.279127)
					(mid -0.294507 -0.285313)
					(end 1.266278 -1.081674)
					(width 0.2)
				)
				(gr_line
					(start 1.279127 -0.250195)
					(end 1.279127 -1.083663)
					(width 0.2)
				)
				(gr_line
					(start -0.250195 1.279127)
					(end -1.083663 1.279127)
					(width 0.2)
				)
			)
			(teardrops
				(best_length_ratio 0.2)
				(max_length 1)
				(best_width_ratio 0.9)
				(max_width 2)
				(curved_edges yes)
				(filter_ratio 0.9)
				(enabled yes)
				(allow_two_segments yes)
				(prefer_zone_connections yes)
			)
		)
		(pad "" smd custom
			(at 1.7 1.7 270)
			(size 0.62 0.62)
			(layers "F.Paste")
			(thermal_bridge_angle 90)
			(options
				(clearance outline)
				(anchor circle)
			)
			(primitives
				(gr_arc
					(start -0.250195 1.279127)
					(mid 0.285453 0.294389)
					(end 1.266786 -0.24747)
					(width 0.2)
				)
				(gr_arc
					(start -0.34334 1.279127)
					(mid 0.218448 0.232561)
					(end 1.259603 -0.339191)
					(width 0.2)
				)
				(gr_arc
					(start -0.436309 1.279127)
					(mid 0.152481 0.169693)
					(end 1.255279 -0.431435)
					(width 0.2)
				)
				(gr_arc
					(start -0.529126 1.279127)
					(mid 0.087542 0.105784)
					(end 1.253811 -0.524161)
					(width 0.2)
				)
				(gr_arc
					(start -0.621807 1.279127)
					(mid 0.0309 0.033527)
					(end 1.275473 -0.621136)
					(width 0.2)
				)
				(gr_arc
					(start -0.71437 1.279127)
					(mid -0.037758 -0.026651)
					(end 1.263664 -0.711602)
					(width 0.2)
				)
				(gr_arc
					(start -0.806826 1.279127)
					(mid -0.105837 -0.087395)
					(end 1.253435 -0.802342)
					(width 0.2)
				)
				(gr_arc
					(start -0.899187 1.279127)
					(mid -0.165236 -0.156885)
					(end 1.267475 -0.897258)
					(width 0.2)
				)
				(gr_arc
					(start -0.991463 1.279127)
					(mid -0.228522 -0.222449)
					(end 1.270645 -0.990112)
					(width 0.2)
				)
				(gr_arc
					(start -1.083663 1.279127)
					(mid -0.294507 -0.285313)
					(end 1.266278 -1.081674)
					(width 0.2)
				)
				(gr_line
					(start 1.279127 -0.250195)
					(end 1.279127 -1.083663)
					(width 0.2)
				)
				(gr_line
					(start -0.250195 1.279127)
					(end -1.083663 1.279127)
					(width 0.2)
				)
			)
			(teardrops
				(best_length_ratio 0.2)
				(max_length 1)
				(best_width_ratio 0.9)
				(max_width 2)
				(curved_edges yes)
				(filter_ratio 0.9)
				(enabled yes)
				(allow_two_segments yes)
				(prefer_zone_connections yes)
			)
		)
		(pad "1" thru_hole circle
			(at 0 0 90)
			(size 6 6)
			(drill 3.7)
			(layers "*.Cu" "*.Mask")
			(remove_unused_layers no)
			(net 1 "GND")
			(pintype "passive")
			(teardrops
				(best_length_ratio 0.4)
				(max_length 1)
				(best_width_ratio 0.9)
				(max_width 2)
				(curved_edges yes)
				(filter_ratio 0.9)
				(enabled yes)
				(allow_two_segments yes)
				(prefer_zone_connections yes)
			)
		)
	)
	(footprint "antmicro-footprints:R_0402_1005Metric"
		(layer "F.Cu")
		(at 299.05 103.46 -90)
		(descr "Resistor SMD 0402")
		(tags "resistor SMD 0402")
		(property "Reference" "R119"
			(at 0.85 -0.4 90)
			(layer "F.SilkS")
			(effects
				(font
					(size 0.7 0.7)
					(thickness 0.15)
				)
				(justify right bottom)
			)
		)
		(property "Value" "R_0R_0402"
			(at -1.011843 1.772047 90)
			(layer "F.Fab")
			(effects
				(font
					(size 0.7 0.7)
					(thickness 0.15)
				)
				(justify right bottom)
			)
		)
		(property "Datasheet" "https://industrial.panasonic.com/cdbs/www-data/pdf/RDA0000/AOA0000C301.pdf"
			(at 0 0 270)
			(layer "F.Fab")
			(hide yes)
			(effects
				(font
					(size 1.27 1.27)
					(thickness 0.15)
				)
			)
		)
		(property "Author" "Antmicro"
			(at 195.59 402.51 0)
			(layer "F.Fab")
			(hide yes)
			(effects
				(font
					(size 1 1)
					(thickness 0.15)
				)
			)
		)
		(property "Current" "1A"
			(at 195.59 402.51 0)
			(layer "F.Fab")
			(hide yes)
			(effects
				(font
					(size 1 1)
					(thickness 0.15)
				)
			)
		)
		(property "License" "Apache-2.0"
			(at 195.59 402.51 0)
			(layer "F.Fab")
			(hide yes)
			(effects
				(font
					(size 1 1)
					(thickness 0.15)
				)
			)
		)
		(property "MPN" "ERJ2GE0R00X"
			(at 195.59 402.51 0)
			(layer "F.Fab")
			(hide yes)
			(effects
				(font
					(size 1 1)
					(thickness 0.15)
				)
			)
		)
		(property "Manufacturer" "Panasonic"
			(at 195.59 402.51 0)
			(layer "F.Fab")
			(hide yes)
			(effects
				(font
					(size 1 1)
					(thickness 0.15)
				)
			)
		)
		(property "Public" "False"
			(at 195.59 402.51 0)
			(layer "F.Fab")
			(hide yes)
			(effects
				(font
					(size 1 1)
					(thickness 0.15)
				)
			)
		)
		(property "Tolerance" ""
			(at 195.59 402.51 0)
			(layer "F.Fab")
			(hide yes)
			(effects
				(font
					(size 1 1)
					(thickness 0.15)
				)
			)
		)
		(property "Val" "0R"
			(at 195.59 402.51 0)
			(layer "F.Fab")
			(hide yes)
			(effects
				(font
					(size 1 1)
					(thickness 0.15)
				)
			)
		)
		(sheetname "Power")
		(sheetfile "power.kicad_sch")
		(attr smd)
		(fp_rect
			(start -0.925 -0.47)
			(end 0.925 0.47)
			(stroke
				(width 0.05)
				(type default)
			)
			(fill no)
			(layer "F.CrtYd")
		)
		(fp_rect
			(start -0.5 -0.25)
			(end 0.5 0.25)
			(stroke
				(width 0.15)
				(type solid)
			)
			(fill no)
			(layer "F.Fab")
		)
		(pad "1" smd roundrect
			(at -0.48 0 270)
			(size 0.59 0.64)
			(layers "F.Cu" "F.Mask" "F.Paste")
			(roundrect_rratio 0.25)
			(net 79 "Net-(U23-VOUT)")
			(pintype "passive")
			(teardrops
				(best_length_ratio 0.2)
				(max_length 1)
				(best_width_ratio 0.9)
				(max_width 2)
				(curved_edges yes)
				(filter_ratio 0.9)
				(enabled yes)
				(allow_two_segments yes)
				(prefer_zone_connections yes)
			)
		)
		(pad "2" smd roundrect
			(at 0.48 0 270)
			(size 0.59 0.64)
			(layers "F.Cu" "F.Mask" "F.Paste")
			(roundrect_rratio 0.25)
			(net 73 "+3V3_AON")
			(pintype "passive")
			(teardrops
				(best_length_ratio 0.2)
				(max_length 1)
				(best_width_ratio 0.9)
				(max_width 2)
				(curved_edges yes)
				(filter_ratio 0.9)
				(enabled yes)
				(allow_two_segments yes)
				(prefer_zone_connections yes)
			)
		)
	)
	(footprint "antmicro-footprints:LED_0603_1608Metric_G"
		(layer "F.Cu")
		(at 190.70861 74.802163 90)
		(descr "LED SMD 0603 Green")
		(tags "LED SMD 0603 Green")
		(property "Reference" "D30"
			(at -1.1 -0.55 90)
			(layer "F.SilkS")
			(effects
				(font
					(size 0.7 0.7)
					(thickness 0.15)
				)
				(justify left bottom)
			)
		)
		(property "Value" "LED_G_0603_LTST-C190GKT"
			(at -0.001 1.599 90)
			(layer "F.Fab")
			(effects
				(font
					(size 0.7 0.7)
					(thickness 0.15)
				)
				(justify left bottom)
			)
		)
		(property "Datasheet" "https://media.digikey.com/pdf/Data%20Sheets/Lite-On%20PDFs/LTST-C190GKT.pdf"
			(at 0 0 90)
			(layer "F.Fab")
			(hide yes)
			(effects
				(font
					(size 1.27 1.27)
					(thickness 0.15)
				)
			)
		)
		(property "Author" "Antmicro"
			(at 265.510773 -115.906447 0)
			(layer "F.Fab")
			(hide yes)
			(effects
				(font
					(size 1 1)
					(thickness 0.15)
				)
			)
		)
		(property "Color" "Green"
			(at 265.510773 -115.906447 0)
			(layer "F.Fab")
			(hide yes)
			(effects
				(font
					(size 1 1)
					(thickness 0.15)
				)
			)
		)
		(property "License" "Apache-2.0"
			(at 265.510773 -115.906447 0)
			(layer "F.Fab")
			(hide yes)
			(effects
				(font
					(size 1 1)
					(thickness 0.15)
				)
			)
		)
		(property "MPN" "LTST-C190GKT"
			(at 265.510773 -115.906447 0)
			(layer "F.Fab")
			(hide yes)
			(effects
				(font
					(size 1 1)
					(thickness 0.15)
				)
			)
		)
		(property "Manufacturer" "Lite-On"
			(at 265.510773 -115.906447 0)
			(layer "F.Fab")
			(hide yes)
			(effects
				(font
					(size 1 1)
					(thickness 0.15)
				)
			)
		)
		(property "Public" "False"
			(at 265.510773 -115.906447 0)
			(layer "F.Fab")
			(hide yes)
			(effects
				(font
					(size 1 1)
					(thickness 0.15)
				)
			)
		)
		(sheetname "Power")
		(sheetfile "power.kicad_sch")
		(attr smd)
		(fp_line
			(start 0.22 -0.35)
			(end -0.22 -0.35)
			(stroke
				(width 0.15)
				(type solid)
			)
			(layer "F.SilkS")
		)
		(fp_line
			(start -1.18 -0.319)
			(end -1.18 0.321)
			(stroke
				(width 0.15)
				(type solid)
			)
			(layer "F.SilkS")
		)
		(fp_line
			(start 0.105328 0.001008)
			(end 0.24 0.001)
			(stroke
				(width 0.1)
				(type solid)
			)
			(layer "F.SilkS")
		)
		(fp_line
			(start -0.094672 0.001008)
			(end 0.105328 -0.198992)
			(stroke
				(width 0.1)
				(type solid)
			)
			(layer "F.SilkS")
		)
		(fp_line
			(start -0.094672 0.001008)
			(end -0.24 0.001008)
			(stroke
				(width 0.1)
				(type solid)
			)
			(layer "F.SilkS")
		)
		(fp_line
			(start 0.105328 0.201008)
			(end 0.105328 -0.198992)
			(stroke
				(width 0.1)
				(type solid)
			)
			(layer "F.SilkS")
		)
		(fp_line
			(start 0.105328 0.201008)
			(end -0.094672 0.001008)
			(stroke
				(width 0.1)
				(type solid)
			)
			(layer "F.SilkS")
		)
		(fp_line
			(start -0.094672 0.201008)
			(end -0.094672 -0.198992)
			(stroke
				(width 0.1)
				(type solid)
			)
			(layer "F.SilkS")
		)
		(fp_line
			(start 0.22 0.35)
			(end -0.22 0.35)
			(stroke
				(width 0.15)
				(type solid)
			)
			(layer "F.SilkS")
		)
		(fp_rect
			(start 1.25 0.65)
			(end -1.25 -0.65)
			(stroke
				(width 0.05)
				(type solid)
			)
			(fill no)
			(layer "F.CrtYd")
		)
		(fp_line
			(start 0.201 -0.202)
			(end -0.101 0)
			(stroke
				(width 0.15)
				(type solid)
			)
			(layer "F.Fab")
		)
		(fp_line
			(start -0.199 -0.202)
			(end -0.199 0.1)
			(stroke
				(width 0.15)
				(type solid)
			)
			(layer "F.Fab")
		)
		(fp_line
			(start 0.599 0)
			(end 0.201 0)
			(stroke
				(width 0.15)
				(type solid)
			)
			(layer "F.Fab")
		)
		(fp_line
			(start 0.201 0)
			(end 0.201 -0.202)
			(stroke
				(width 0.15)
				(type solid)
			)
			(layer "F.Fab")
		)
		(fp_line
			(start -0.101 0)
			(end 0.201 0.2)
			(stroke
				(width 0.15)
				(type solid)
			)
			(layer "F.Fab")
		)
		(fp_line
			(start -0.199 0)
			(end -0.597 0)
			(stroke
				(width 0.15)
				(type solid)
			)
			(layer "F.Fab")
		)
		(fp_line
			(start 0.201 0.2)
			(end 0.201 0)
			(stroke
				(width 0.15)
				(type solid)
			)
			(layer "F.Fab")
		)
		(fp_line
			(start -0.199 0.2)
			(end -0.199 0.1)
			(stroke
				(width 0.15)
				(type solid)
			)
			(layer "F.Fab")
		)
		(fp_rect
			(start 0.848 0.4)
			(end -0.85 -0.402)
			(stroke
				(width 0.15)
				(type solid)
			)
			(fill no)
			(layer "F.Fab")
		)
		(pad "1" smd roundrect
			(at -0.7 0 270)
			(size 0.8 1)
			(layers "F.Cu" "F.Mask" "F.Paste")
			(roundrect_rratio 0.2)
			(net 982 "Net-(D30-C)")
			(pinfunction "C")
			(pintype "passive")
			(teardrops
				(best_length_ratio 0.2)
				(max_length 1)
				(best_width_ratio 0.9)
				(max_width 2)
				(curved_edges yes)
				(filter_ratio 0.9)
				(enabled yes)
				(allow_two_segments yes)
				(prefer_zone_connections yes)
			)
		)
		(pad "2" smd roundrect
			(at 0.7 0 270)
			(size 0.8 1)
			(layers "F.Cu" "F.Mask" "F.Paste")
			(roundrect_rratio 0.2)
			(net 73 "+3V3_AON")
			(pinfunction "A")
			(pintype "passive")
			(teardrops
				(best_length_ratio 0.2)
				(max_length 1)
				(best_width_ratio 0.9)
				(max_width 2)
				(curved_edges yes)
				(filter_ratio 0.9)
				(enabled yes)
				(allow_two_segments yes)
				(prefer_zone_connections yes)
			)
		)
	)
	(footprint "antmicro-footprints:R_0201"
		(layer "F.Cu")
		(at 150.33 147.336 -90)
		(descr "Resistor SMD 0201")
		(tags "resistor SMD 0201")
		(property "Reference" "R275"
			(at 4.099 -0.57 270)
			(layer "F.SilkS")
			(effects
				(font
					(size 0.7 0.7)
					(thickness 0.15)
				)
				(justify left bottom)
			)
		)
		(property "Value" "R_0R_0201"
			(at 0 1.25 270)
			(layer "F.Fab")
			(effects
				(font
					(size 0.7 0.7)
					(thickness 0.15)
				)
				(justify left bottom)
			)
		)
		(property "Datasheet" "https://www.bourns.com/docs/product-datasheets/cr.pdf"
			(at 0 0 270)
			(layer "F.Fab")
			(hide yes)
			(effects
				(font
					(size 1.27 1.27)
					(thickness 0.15)
				)
			)
		)
		(property "Author" "Antmicro"
			(at 2.994 297.666 0)
			(layer "F.Fab")
			(hide yes)
			(effects
				(font
					(size 1 1)
					(thickness 0.15)
				)
			)
		)
		(property "License" "Apache-2.0"
			(at 2.994 297.666 0)
			(layer "F.Fab")
			(hide yes)
			(effects
				(font
					(size 1 1)
					(thickness 0.15)
				)
			)
		)
		(property "MPN" "CR0201-FX-0R00GLF"
			(at 2.994 297.666 0)
			(layer "F.Fab")
			(hide yes)
			(effects
				(font
					(size 1 1)
					(thickness 0.15)
				)
			)
		)
		(property "Manufacturer" "Bourns"
			(at 2.994 297.666 0)
			(layer "F.Fab")
			(hide yes)
			(effects
				(font
					(size 1 1)
					(thickness 0.15)
				)
			)
		)
		(property "Tolerance" "1%"
			(at 2.994 297.666 0)
			(layer "F.Fab")
			(hide yes)
			(effects
				(font
					(size 1 1)
					(thickness 0.15)
				)
			)
		)
		(property "Val" "0R"
			(at 2.994 297.666 0)
			(layer "F.Fab")
			(hide yes)
			(effects
				(font
					(size 1 1)
					(thickness 0.15)
				)
			)
		)
		(sheetname "KR to SFI #1")
		(sheetfile "kr_sfi.kicad_sch")
		(attr smd)
		(fp_rect
			(start -0.7 -0.35)
			(end 0.7 0.35)
			(stroke
				(width 0.05)
				(type default)
			)
			(fill no)
			(layer "F.CrtYd")
		)
		(fp_rect
			(start -0.3 -0.15)
			(end 0.298 0.148)
			(stroke
				(width 0.15)
				(type solid)
			)
			(fill no)
			(layer "F.Fab")
		)
		(pad "" smd roundrect
			(at -0.346 0 270)
			(size 0.318 0.36)
			(layers "F.Paste")
			(roundrect_rratio 0.25)
			(teardrops
				(best_length_ratio 0.2)
				(max_length 1)
				(best_width_ratio 0.9)
				(max_width 2)
				(curved_edges yes)
				(filter_ratio 0.9)
				(enabled yes)
				(allow_two_segments yes)
				(prefer_zone_connections yes)
			)
		)
		(pad "" smd roundrect
			(at 0.344 0 270)
			(size 0.318 0.36)
			(layers "F.Paste")
			(roundrect_rratio 0.25)
			(teardrops
				(best_length_ratio 0.2)
				(max_length 1)
				(best_width_ratio 0.9)
				(max_width 2)
				(curved_edges yes)
				(filter_ratio 0.9)
				(enabled yes)
				(allow_two_segments yes)
				(prefer_zone_connections yes)
			)
		)
		(pad "1" smd roundrect
			(at -0.32 0 270)
			(size 0.46 0.4)
			(layers "F.Cu" "F.Mask")
			(roundrect_rratio 0.25)
			(net 686 "/2xSFP+/KR to SFI #1/SFI_R.RX-")
			(pintype "passive")
			(teardrops
				(best_length_ratio 0.2)
				(max_length 1)
				(best_width_ratio 0.9)
				(max_width 2)
				(curved_edges yes)
				(filter_ratio 0.9)
				(enabled yes)
				(allow_two_segments yes)
				(prefer_zone_connections yes)
			)
		)
		(pad "2" smd roundrect
			(at 0.32 0 270)
			(size 0.46 0.4)
			(layers "F.Cu" "F.Mask")
			(roundrect_rratio 0.25)
			(net 170 "/2xSFP+/SFI0.RX-")
			(pintype "passive")
			(teardrops
				(best_length_ratio 0.2)
				(max_length 1)
				(best_width_ratio 0.9)
				(max_width 2)
				(curved_edges yes)
				(filter_ratio 0.9)
				(enabled yes)
				(allow_two_segments yes)
				(prefer_zone_connections yes)
			)
		)
	)
	(footprint "antmicro-footprints:L_WE-MAPI-4020"
		(layer "F.Cu")
		(at 311.215499 91.4365 180)
		(property "Reference" "L3"
			(at -2.234501 1.3765 0)
			(layer "F.SilkS")
			(effects
				(font
					(size 0.7 0.7)
					(thickness 0.15)
				)
				(justify left bottom)
			)
		)
		(property "Value" "L_1u8_6.8A_WE-MAPI-4020"
			(at -2.4 3.4 0)
			(layer "F.Fab")
			(effects
				(font
					(size 0.7 0.7)
					(thickness 0.15)
				)
				(justify left bottom)
			)
		)
		(property "Datasheet" "https://www.we-online.com/components/products/datasheet/74438356018.pdf"
			(at 0 0 180)
			(layer "F.Fab")
			(hide yes)
			(effects
				(font
					(size 1.27 1.27)
					(thickness 0.15)
				)
			)
		)
		(property "Author" "Antmicro"
			(at 622.430998 182.873 0)
			(layer "F.Fab")
			(hide yes)
			(effects
				(font
					(size 1 1)
					(thickness 0.15)
				)
			)
		)
		(property "IMax" "6.8 A"
			(at 622.430998 182.873 0)
			(layer "F.Fab")
			(hide yes)
			(effects
				(font
					(size 1 1)
					(thickness 0.15)
				)
			)
		)
		(property "ISat" "6.5 A"
			(at 622.430998 182.873 0)
			(layer "F.Fab")
			(hide yes)
			(effects
				(font
					(size 1 1)
					(thickness 0.15)
				)
			)
		)
		(property "License" "Apache-2.0"
			(at 622.430998 182.873 0)
			(layer "F.Fab")
			(hide yes)
			(effects
				(font
					(size 1 1)
					(thickness 0.15)
				)
			)
		)
		(property "MPN" "74438356018"
			(at 622.430998 182.873 0)
			(layer "F.Fab")
			(hide yes)
			(effects
				(font
					(size 1 1)
					(thickness 0.15)
				)
			)
		)
		(property "Manufacturer" "Würth Elektronik"
			(at 622.430998 182.873 0)
			(layer "F.Fab")
			(hide yes)
			(effects
				(font
					(size 1 1)
					(thickness 0.15)
				)
			)
		)
		(property "Public" "False"
			(at 622.430998 182.873 0)
			(layer "F.Fab")
			(hide yes)
			(effects
				(font
					(size 1 1)
					(thickness 0.15)
				)
			)
		)
		(property "Size" "4.1x4.1mm"
			(at 622.430998 182.873 0)
			(layer "F.Fab")
			(hide yes)
			(effects
				(font
					(size 1 1)
					(thickness 0.15)
				)
			)
		)
		(property "Val" "1u8/6.8A"
			(at 622.430998 182.873 0)
			(layer "F.Fab")
			(hide yes)
			(effects
				(font
					(size 1 1)
					(thickness 0.15)
				)
			)
		)
		(sheetname "Power")
		(sheetfile "power.kicad_sch")
		(attr smd)
		(fp_rect
			(start -2.2 -2.2)
			(end 2.2 2.2)
			(stroke
				(width 0.15)
				(type solid)
			)
			(fill no)
			(layer "F.SilkS")
		)
		(fp_rect
			(start -2.3 -2.3)
			(end 2.3 2.3)
			(stroke
				(width 0.05)
				(type solid)
			)
			(fill no)
			(layer "F.CrtYd")
		)
		(fp_rect
			(start -2.05 -2.05)
			(end 2.05 2.05)
			(stroke
				(width 0.15)
				(type solid)
			)
			(fill no)
			(layer "F.Fab")
		)
		(pad "1" smd roundrect
			(at -1.185 0 270)
			(size 3.7 1)
			(layers "F.Cu" "F.Mask" "F.Paste")
			(roundrect_rratio 0.1)
			(net 870 "Net-(U21-SW)")
			(pintype "passive")
			(teardrops
				(best_length_ratio 0.2)
				(max_length 1)
				(best_width_ratio 0.9)
				(max_width 2)
				(curved_edges yes)
				(filter_ratio 0.9)
				(enabled yes)
				(allow_two_segments yes)
				(prefer_zone_connections yes)
			)
		)
		(pad "2" smd roundrect
			(at 1.185 0 270)
			(size 3.7 1)
			(layers "F.Cu" "F.Mask" "F.Paste")
			(roundrect_rratio 0.1)
			(net 75 "Net-(U50-IN+)")
			(pintype "passive")
			(teardrops
				(best_length_ratio 0.2)
				(max_length 1)
				(best_width_ratio 0.9)
				(max_width 2)
				(curved_edges yes)
				(filter_ratio 0.9)
				(enabled yes)
				(allow_two_segments yes)
				(prefer_zone_connections yes)
			)
		)
	)
	(footprint "antmicro-footprints:R_0402_1005Metric"
		(layer "F.Cu")
		(at 310.1 74.81 180)
		(descr "Resistor SMD 0402")
		(tags "resistor SMD 0402")
		(property "Reference" "R165"
			(at 0.8 -0.45 0)
			(layer "F.SilkS")
			(effects
				(font
					(size 0.7 0.7)
					(thickness 0.15)
				)
				(justify right bottom)
			)
		)
		(property "Value" "R_2k2_0402"
			(at -1.011843 1.772047 0)
			(layer "F.Fab")
			(effects
				(font
					(size 0.7 0.7)
					(thickness 0.15)
				)
				(justify right bottom)
			)
		)
		(property "Datasheet" "https://www.bourns.com/docs/product-datasheets/cr.pdf"
			(at 0 0 180)
			(layer "F.Fab")
			(hide yes)
			(effects
				(font
					(size 1.27 1.27)
					(thickness 0.15)
				)
			)
		)
		(property "Author" "Antmicro"
			(at 620.2 149.62 0)
			(layer "F.Fab")
			(hide yes)
			(effects
				(font
					(size 1 1)
					(thickness 0.15)
				)
			)
		)
		(property "License" "Apache-2.0"
			(at 620.2 149.62 0)
			(layer "F.Fab")
			(hide yes)
			(effects
				(font
					(size 1 1)
					(thickness 0.15)
				)
			)
		)
		(property "MPN" "CR0402-FX-2201GLF"
			(at 620.2 149.62 0)
			(layer "F.Fab")
			(hide yes)
			(effects
				(font
					(size 1 1)
					(thickness 0.15)
				)
			)
		)
		(property "Manufacturer" "Bourns"
			(at 620.2 149.62 0)
			(layer "F.Fab")
			(hide yes)
			(effects
				(font
					(size 1 1)
					(thickness 0.15)
				)
			)
		)
		(property "Public" "False"
			(at 620.2 149.62 0)
			(layer "F.Fab")
			(hide yes)
			(effects
				(font
					(size 1 1)
					(thickness 0.15)
				)
			)
		)
		(property "Tolerance" "1%"
			(at 620.2 149.62 0)
			(layer "F.Fab")
			(hide yes)
			(effects
				(font
					(size 1 1)
					(thickness 0.15)
				)
			)
		)
		(property "Val" "2k2"
			(at 620.2 149.62 0)
			(layer "F.Fab")
			(hide yes)
			(effects
				(font
					(size 1 1)
					(thickness 0.15)
				)
			)
		)
		(sheetname "Com Express 7 MGMT")
		(sheetfile "com_express_7_mgmt.kicad_sch")
		(attr smd)
		(fp_rect
			(start -0.925 -0.47)
			(end 0.925 0.47)
			(stroke
				(width 0.05)
				(type default)
			)
			(fill no)
			(layer "F.CrtYd")
		)
		(fp_rect
			(start -0.5 -0.25)
			(end 0.5 0.25)
			(stroke
				(width 0.15)
				(type solid)
			)
			(fill no)
			(layer "F.Fab")
		)
		(pad "1" smd roundrect
			(at -0.48 0 180)
			(size 0.59 0.64)
			(layers "F.Cu" "F.Mask" "F.Paste")
			(roundrect_rratio 0.25)
			(net 41 "Net-(BT1-+)")
			(pintype "passive")
			(teardrops
				(best_length_ratio 0.2)
				(max_length 1)
				(best_width_ratio 0.9)
				(max_width 2)
				(curved_edges yes)
				(filter_ratio 0.9)
				(enabled yes)
				(allow_two_segments yes)
				(prefer_zone_connections yes)
			)
		)
		(pad "2" smd roundrect
			(at 0.48 0 180)
			(size 0.59 0.64)
			(layers "F.Cu" "F.Mask" "F.Paste")
			(roundrect_rratio 0.25)
			(net 135 "Net-(D19-Pad3)")
			(pintype "passive")
			(teardrops
				(best_length_ratio 0.2)
				(max_length 1)
				(best_width_ratio 0.9)
				(max_width 2)
				(curved_edges yes)
				(filter_ratio 0.9)
				(enabled yes)
				(allow_two_segments yes)
				(prefer_zone_connections yes)
			)
		)
	)
	(footprint "antmicro-footprints:C_0603_1608Metric"
		(layer "F.Cu")
		(at 314.2505 95.1365 90)
		(descr "Capacitor SMD 0603")
		(tags "capacitor 0603")
		(property "Reference" "C59"
			(at 1.1765 0.5995 90)
			(layer "F.SilkS")
			(effects
				(font
					(size 0.7 0.7)
					(thickness 0.15)
				)
				(justify left bottom)
			)
		)
		(property "Value" "C_22u_16V_0603"
			(at -1.42757 1.770288 90)
			(layer "F.Fab")
			(effects
				(font
					(size 0.7 0.7)
					(thickness 0.15)
				)
				(justify left bottom)
			)
		)
		(property "Datasheet" "https://product.samsungsem.com/mlcc/CL10A226MO7JZN.do"
			(at 0 0 90)
			(layer "F.Fab")
			(hide yes)
			(effects
				(font
					(size 1.27 1.27)
					(thickness 0.15)
				)
			)
		)
		(property "Author" "Antmicro"
			(at 409.387 -219.114 0)
			(layer "F.Fab")
			(hide yes)
			(effects
				(font
					(size 1 1)
					(thickness 0.15)
				)
			)
		)
		(property "Dielectric" ""
			(at 409.387 -219.114 0)
			(layer "F.Fab")
			(hide yes)
			(effects
				(font
					(size 1 1)
					(thickness 0.15)
				)
			)
		)
		(property "License" "Apache-2.0"
			(at 409.387 -219.114 0)
			(layer "F.Fab")
			(hide yes)
			(effects
				(font
					(size 1 1)
					(thickness 0.15)
				)
			)
		)
		(property "MPN" "CL10A226MO7JZNC"
			(at 409.387 -219.114 0)
			(layer "F.Fab")
			(hide yes)
			(effects
				(font
					(size 1 1)
					(thickness 0.15)
				)
			)
		)
		(property "Manufacturer" "Samsung Electro-Mechanics"
			(at 409.387 -219.114 0)
			(layer "F.Fab")
			(hide yes)
			(effects
				(font
					(size 1 1)
					(thickness 0.15)
				)
			)
		)
		(property "Public" "False"
			(at 409.387 -219.114 0)
			(layer "F.Fab")
			(hide yes)
			(effects
				(font
					(size 1 1)
					(thickness 0.15)
				)
			)
		)
		(property "Val" "22u"
			(at 409.387 -219.114 0)
			(layer "F.Fab")
			(hide yes)
			(effects
				(font
					(size 1 1)
					(thickness 0.15)
				)
			)
		)
		(property "Voltage" "16V"
			(at 409.387 -219.114 0)
			(layer "F.Fab")
			(hide yes)
			(effects
				(font
					(size 1 1)
					(thickness 0.15)
				)
			)
		)
		(sheetname "Power")
		(sheetfile "power.kicad_sch")
		(attr smd)
		(fp_line
			(start -0.15 -0.4)
			(end 0.15 -0.4)
			(stroke
				(width 0.15)
				(type solid)
			)
			(layer "F.SilkS")
		)
		(fp_line
			(start -0.15 0.4)
			(end 0.15 0.4)
			(stroke
				(width 0.15)
				(type solid)
			)
			(layer "F.SilkS")
		)
		(fp_rect
			(start -1.25 -0.65)
			(end 1.25 0.65)
			(stroke
				(width 0.05)
				(type solid)
			)
			(fill no)
			(layer "F.CrtYd")
		)
		(fp_rect
			(start -0.8 -0.4)
			(end 0.8 0.4)
			(stroke
				(width 0.15)
				(type solid)
			)
			(fill no)
			(layer "F.Fab")
		)
		(pad "1" smd roundrect
			(at -0.7 0 90)
			(size 0.8 1)
			(layers "F.Cu" "F.Mask" "F.Paste")
			(roundrect_rratio 0.2)
			(net 1 "GND")
			(pintype "passive")
			(teardrops
				(best_length_ratio 0.2)
				(max_length 1)
				(best_width_ratio 0.9)
				(max_width 2)
				(curved_edges yes)
				(filter_ratio 0.9)
				(enabled yes)
				(allow_two_segments yes)
				(prefer_zone_connections yes)
			)
		)
		(pad "2" smd roundrect
			(at 0.7 0 90)
			(size 0.8 1)
			(layers "F.Cu" "F.Mask" "F.Paste")
			(roundrect_rratio 0.2)
			(net 62 "+12V_AON")
			(pintype "passive")
			(teardrops
				(best_length_ratio 0.2)
				(max_length 1)
				(best_width_ratio 0.9)
				(max_width 2)
				(curved_edges yes)
				(filter_ratio 0.9)
				(enabled yes)
				(allow_two_segments yes)
				(prefer_zone_connections yes)
			)
		)
	)
	(footprint "antmicro-footprints:F_1206_3216Metric"
		(layer "F.Cu")
		(at 310.85 149.11 90)
		(property "Reference" "F1"
			(at -0.7 2.1 90)
			(layer "F.SilkS")
			(effects
				(font
					(size 0.7 0.7)
					(thickness 0.15)
				)
				(justify left bottom)
			)
		)
		(property "Value" "F_12A_1206"
			(at -3.6 1.57 90)
			(layer "F.Fab")
			(effects
				(font
					(size 0.7 0.7)
					(thickness 0.15)
				)
				(justify right bottom mirror)
			)
		)
		(property "Datasheet" "https://us.schurter.com/pdf/english/typ_UST_1206.pdf"
			(at 0 0 90)
			(layer "F.Fab")
			(hide yes)
			(effects
				(font
					(size 1.27 1.27)
					(thickness 0.15)
				)
			)
		)
		(property "Author" "Antmicro"
			(at 459.96 -161.74 0)
			(layer "F.Fab")
			(hide yes)
			(effects
				(font
					(size 1 1)
					(thickness 0.15)
				)
			)
		)
		(property "License" "Apache-2.0"
			(at 459.96 -161.74 0)
			(layer "F.Fab")
			(hide yes)
			(effects
				(font
					(size 1 1)
					(thickness 0.15)
				)
			)
		)
		(property "MPN" "3413.0329.22"
			(at 459.96 -161.74 0)
			(layer "F.Fab")
			(hide yes)
			(effects
				(font
					(size 1 1)
					(thickness 0.15)
				)
			)
		)
		(property "Manufacturer" "Schurter"
			(at 459.96 -161.74 0)
			(layer "F.Fab")
			(hide yes)
			(effects
				(font
					(size 1 1)
					(thickness 0.15)
				)
			)
		)
		(sheetname "Power")
		(sheetfile "power.kicad_sch")
		(attr smd)
		(fp_line
			(start 0.8 -0.899)
			(end -0.8 -0.899)
			(stroke
				(width 0.15)
				(type solid)
			)
			(layer "F.SilkS")
		)
		(fp_line
			(start 0.8 0.901)
			(end -0.8 0.901)
			(stroke
				(width 0.15)
				(type solid)
			)
			(layer "F.SilkS")
		)
		(fp_rect
			(start -2.325 -1.15)
			(end 2.325 1.15)
			(stroke
				(width 0.05)
				(type default)
			)
			(fill no)
			(layer "F.CrtYd")
		)
		(fp_line
			(start 1.624 -0.861)
			(end 1.624 0.792)
			(stroke
				(width 0.15)
				(type solid)
			)
			(layer "F.Fab")
		)
		(fp_line
			(start -1.677 -0.861)
			(end 1.624 -0.861)
			(stroke
				(width 0.15)
				(type solid)
			)
			(layer "F.Fab")
		)
		(fp_line
			(start 1.624 0.792)
			(end -1.677 0.792)
			(stroke
				(width 0.15)
				(type solid)
			)
			(layer "F.Fab")
		)
		(fp_line
			(start -1.677 0.792)
			(end -1.677 -0.861)
			(stroke
				(width 0.15)
				(type solid)
			)
			(layer "F.Fab")
		)
		(pad "1" smd roundrect
			(at -1.5 0.001 90)
			(size 1.15 1.8)
			(layers "F.Cu" "F.Mask" "F.Paste")
			(roundrect_rratio 0.25)
			(net 144 "VCC")
			(pintype "passive")
			(teardrops
				(best_length_ratio 0.2)
				(max_length 1)
				(best_width_ratio 0.9)
				(max_width 2)
				(curved_edges yes)
				(filter_ratio 0.9)
				(enabled yes)
				(allow_two_segments yes)
				(prefer_zone_connections yes)
			)
		)
		(pad "2" smd roundrect
			(at 1.5 0.001 90)
			(size 1.15 1.8)
			(layers "F.Cu" "F.Mask" "F.Paste")
			(roundrect_rratio 0.25)
			(net 145 "Net-(D24-C)")
			(pintype "passive")
			(teardrops
				(best_length_ratio 0.2)
				(max_length 1)
				(best_width_ratio 0.9)
				(max_width 2)
				(curved_edges yes)
				(filter_ratio 0.9)
				(enabled yes)
				(allow_two_segments yes)
				(prefer_zone_connections yes)
			)
		)
	)
	(footprint "antmicro-footprints:SOT-23-3"
		(layer "F.Cu")
		(at 258.125 131.51 90)
		(property "Reference" "Q12"
			(at 1.4 0.425 180)
			(layer "F.SilkS")
			(effects
				(font
					(size 0.7 0.7)
					(thickness 0.15)
				)
				(justify left bottom)
			)
		)
		(property "Value" "BSS138-7-F"
			(at -1.9 2.7 90)
			(layer "F.Fab")
			(effects
				(font
					(size 0.7 0.7)
					(thickness 0.15)
				)
				(justify left bottom)
			)
		)
		(property "Datasheet" "https://www.diodes.com/assets/Datasheets/ds30144.pdf"
			(at 0 0 90)
			(layer "F.Fab")
			(hide yes)
			(effects
				(font
					(size 1.27 1.27)
					(thickness 0.15)
				)
			)
		)
		(property "Author" "Antmicro"
			(at 389.635 -126.615 0)
			(layer "F.Fab")
			(hide yes)
			(effects
				(font
					(size 1 1)
					(thickness 0.15)
				)
			)
		)
		(property "License" "Apache-2.0"
			(at 389.635 -126.615 0)
			(layer "F.Fab")
			(hide yes)
			(effects
				(font
					(size 1 1)
					(thickness 0.15)
				)
			)
		)
		(property "MPN" "BSS138-7-F"
			(at 389.635 -126.615 0)
			(layer "F.Fab")
			(hide yes)
			(effects
				(font
					(size 1 1)
					(thickness 0.15)
				)
			)
		)
		(property "Manufacturer" "Diodes Incorporated"
			(at 389.635 -126.615 0)
			(layer "F.Fab")
			(hide yes)
			(effects
				(font
					(size 1 1)
					(thickness 0.15)
				)
			)
		)
		(sheetname "Com Express 7 MGMT")
		(sheetfile "com_express_7_mgmt.kicad_sch")
		(attr smd)
		(fp_line
			(start 0.7 -1.5)
			(end -0.7 -1.5)
			(stroke
				(width 0.15)
				(type solid)
			)
			(layer "F.SilkS")
		)
		(fp_line
			(start -0.85 -1.35)
			(end -0.7 -1.5)
			(stroke
				(width 0.15)
				(type solid)
			)
			(layer "F.SilkS")
		)
		(fp_line
			(start -1.45 -1.35)
			(end -0.85 -1.35)
			(stroke
				(width 0.15)
				(type solid)
			)
			(layer "F.SilkS")
		)
		(fp_line
			(start 0.7 -0.4)
			(end 0.7 -1.5)
			(stroke
				(width 0.15)
				(type solid)
			)
			(layer "F.SilkS")
		)
		(fp_line
			(start 0.7 0.4)
			(end 0.7 1.5)
			(stroke
				(width 0.15)
				(type solid)
			)
			(layer "F.SilkS")
		)
		(fp_line
			(start 0.7 1.5)
			(end -0.7 1.5)
			(stroke
				(width 0.15)
				(type solid)
			)
			(layer "F.SilkS")
		)
		(fp_line
			(start -0.7 1.5)
			(end -0.7 1.35)
			(stroke
				(width 0.15)
				(type solid)
			)
			(layer "F.SilkS")
		)
		(fp_line
			(start 0.825 -1.6)
			(end 0.825 -0.45)
			(stroke
				(width 0.05)
				(type solid)
			)
			(layer "F.CrtYd")
		)
		(fp_line
			(start -0.9 -1.6)
			(end 0.825 -1.6)
			(stroke
				(width 0.05)
				(type solid)
			)
			(layer "F.CrtYd")
		)
		(fp_line
			(start -0.9 -1.6)
			(end -0.9 -1.4)
			(stroke
				(width 0.05)
				(type solid)
			)
			(layer "F.CrtYd")
		)
		(fp_line
			(start -0.9 -1.4)
			(end -1.75 -1.4)
			(stroke
				(width 0.05)
				(type solid)
			)
			(layer "F.CrtYd")
		)
		(fp_line
			(start -0.85 -0.5)
			(end -1.75 -0.5)
			(stroke
				(width 0.05)
				(type solid)
			)
			(layer "F.CrtYd")
		)
		(fp_line
			(start -1.75 -0.5)
			(end -1.75 -1.4)
			(stroke
				(width 0.05)
				(type solid)
			)
			(layer "F.CrtYd")
		)
		(fp_line
			(start 1.75 -0.45)
			(end 1.75 0.45)
			(stroke
				(width 0.05)
				(type solid)
			)
			(layer "F.CrtYd")
		)
		(fp_line
			(start 0.825 -0.45)
			(end 1.75 -0.45)
			(stroke
				(width 0.05)
				(type solid)
			)
			(layer "F.CrtYd")
		)
		(fp_line
			(start 1.75 0.45)
			(end 0.85 0.45)
			(stroke
				(width 0.05)
				(type solid)
			)
			(layer "F.CrtYd")
		)
		(fp_line
			(start 0.85 0.45)
			(end 0.85 1.65)
			(stroke
				(width 0.05)
				(type solid)
			)
			(layer "F.CrtYd")
		)
		(fp_line
			(start -0.85 0.5)
			(end -0.85 -0.5)
			(stroke
				(width 0.05)
				(type solid)
			)
			(layer "F.CrtYd")
		)
		(fp_line
			(start -1.75 0.5)
			(end -0.85 0.5)
			(stroke
				(width 0.05)
				(type solid)
			)
			(layer "F.CrtYd")
		)
		(fp_line
			(start -0.85 1.4)
			(end -1.75 1.4)
			(stroke
				(width 0.05)
				(type solid)
			)
			(layer "F.CrtYd")
		)
		(fp_line
			(start -1.75 1.4)
			(end -1.75 0.5)
			(stroke
				(width 0.05)
				(type solid)
			)
			(layer "F.CrtYd")
		)
		(fp_line
			(start 0.85 1.65)
			(end -0.85 1.65)
			(stroke
				(width 0.05)
				(type solid)
			)
			(layer "F.CrtYd")
		)
		(fp_line
			(start -0.85 1.65)
			(end -0.85 1.4)
			(stroke
				(width 0.05)
				(type solid)
			)
			(layer "F.CrtYd")
		)
		(fp_line
			(start -0.437 -1.526)
			(end 0.688 -1.526)
			(stroke
				(width 0.15)
				(type solid)
			)
			(layer "F.Fab")
		)
		(fp_line
			(start -0.437 -1.526)
			(end -0.712 -1.325)
			(stroke
				(width 0.15)
				(type solid)
			)
			(layer "F.Fab")
		)
		(fp_line
			(start -0.712 -1.325)
			(end -0.712 1.523)
			(stroke
				(width 0.15)
				(type solid)
			)
			(layer "F.Fab")
		)
		(fp_line
			(start 0.688 1.519)
			(end 0.688 -1.52)
			(stroke
				(width 0.15)
				(type solid)
			)
			(layer "F.Fab")
		)
		(fp_line
			(start -0.712 1.519)
			(end 0.688 1.519)
			(stroke
				(width 0.15)
				(type solid)
			)
			(layer "F.Fab")
		)
		(pad "1" smd roundrect
			(at -1.1 -0.951 90)
			(size 1 0.6)
			(layers "F.Cu" "F.Mask" "F.Paste")
			(roundrect_rratio 0.15)
			(net 546 "/Com Express 7 MGMT/~{COM7}")
			(pinfunction "G")
			(pintype "bidirectional")
			(teardrops
				(best_length_ratio 0.2)
				(max_length 1)
				(best_width_ratio 0.9)
				(max_width 2)
				(curved_edges yes)
				(filter_ratio 0.9)
				(enabled yes)
				(allow_two_segments yes)
				(prefer_zone_connections yes)
			)
		)
		(pad "2" smd roundrect
			(at -1.1 0.949 90)
			(size 1 0.6)
			(layers "F.Cu" "F.Mask" "F.Paste")
			(roundrect_rratio 0.15)
			(net 1 "GND")
			(pinfunction "S")
			(pintype "bidirectional")
			(teardrops
				(best_length_ratio 0.2)
				(max_length 1)
				(best_width_ratio 0.9)
				(max_width 2)
				(curved_edges yes)
				(filter_ratio 0.9)
				(enabled yes)
				(allow_two_segments yes)
				(prefer_zone_connections yes)
			)
		)
		(pad "3" smd roundrect
			(at 1.1 -0.0005 90)
			(size 1 0.6)
			(layers "F.Cu" "F.Mask" "F.Paste")
			(roundrect_rratio 0.15)
			(net 533 "/Com Express 7 MGMT/PSON")
			(pinfunction "D")
			(pintype "bidirectional")
			(teardrops
				(best_length_ratio 0.2)
				(max_length 1)
				(best_width_ratio 0.9)
				(max_width 2)
				(curved_edges yes)
				(filter_ratio 0.9)
				(enabled yes)
				(allow_two_segments yes)
				(prefer_zone_connections yes)
			)
		)
	)
	(footprint "antmicro-footprints:SOT-23-8"
		(layer "F.Cu")
		(at 305.5 149.11 -90)
		(descr "http://www.ti.com/lit/ds/symlink/ina219.pdf")
		(property "Reference" "U48"
			(at -1.1 1.8 90)
			(layer "F.SilkS")
			(effects
				(font
					(size 0.7 0.7)
					(thickness 0.15)
				)
				(justify right bottom)
			)
		)
		(property "Value" "INA219AIDCNR"
			(at 0 2.8 90)
			(layer "F.Fab")
			(effects
				(font
					(size 0.7 0.7)
					(thickness 0.15)
				)
				(justify right bottom)
			)
		)
		(property "Datasheet" "https://www.ti.com/lit/ds/symlink/ina219.pdf?ts=1713856455637&ref_url=https%253A%252F%252Fwww.mouser.es%252F"
			(at 0 0 270)
			(layer "F.Fab")
			(hide yes)
			(effects
				(font
					(size 1.27 1.27)
					(thickness 0.15)
				)
			)
		)
		(property "Author" "Antmicro"
			(at 156.39 454.61 0)
			(layer "F.Fab")
			(hide yes)
			(effects
				(font
					(size 1 1)
					(thickness 0.15)
				)
			)
		)
		(property "License" "Apache-2.0"
			(at 156.39 454.61 0)
			(layer "F.Fab")
			(hide yes)
			(effects
				(font
					(size 1 1)
					(thickness 0.15)
				)
			)
		)
		(property "MPN" "INA219AIDCNR"
			(at 156.39 454.61 0)
			(layer "F.Fab")
			(hide yes)
			(effects
				(font
					(size 1 1)
					(thickness 0.15)
				)
			)
		)
		(property "Manufacturer" "Texas Instruments"
			(at 156.39 454.61 0)
			(layer "F.Fab")
			(hide yes)
			(effects
				(font
					(size 1 1)
					(thickness 0.15)
				)
			)
		)
		(sheetname "Power")
		(sheetfile "power.kicad_sch")
		(attr smd)
		(fp_line
			(start -0.987 1.6)
			(end -0.987 1.324)
			(stroke
				(width 0.15)
				(type solid)
			)
			(layer "F.SilkS")
		)
		(fp_line
			(start -0.613 1.6)
			(end -0.987 1.6)
			(stroke
				(width 0.15)
				(type solid)
			)
			(layer "F.SilkS")
		)
		(fp_line
			(start 1 1.6)
			(end 0.6 1.6)
			(stroke
				(width 0.15)
				(type solid)
			)
			(layer "F.SilkS")
		)
		(fp_line
			(start 1 1.3)
			(end 1 1.6)
			(stroke
				(width 0.15)
				(type solid)
			)
			(layer "F.SilkS")
		)
		(fp_line
			(start -1 -1.3)
			(end -1 -1.6)
			(stroke
				(width 0.15)
				(type solid)
			)
			(layer "F.SilkS")
		)
		(fp_line
			(start 1 -1.3)
			(end 1 -1.6)
			(stroke
				(width 0.15)
				(type solid)
			)
			(layer "F.SilkS")
		)
		(fp_line
			(start -1 -1.6)
			(end -0.6 -1.6)
			(stroke
				(width 0.15)
				(type solid)
			)
			(layer "F.SilkS")
		)
		(fp_line
			(start 1 -1.6)
			(end 0.625 -1.6)
			(stroke
				(width 0.15)
				(type solid)
			)
			(layer "F.SilkS")
		)
		(fp_circle
			(center -1.3 -1.4)
			(end -1.25 -1.4)
			(stroke
				(width 0.15)
				(type solid)
			)
			(fill yes)
			(layer "F.SilkS")
		)
		(fp_rect
			(start -1.9 -1.75)
			(end 1.898 1.75)
			(stroke
				(width 0.05)
				(type solid)
			)
			(fill no)
			(layer "F.CrtYd")
		)
		(fp_line
			(start -1.4 -1.25)
			(end -1.2 -1.45)
			(stroke
				(width 0.15)
				(type solid)
			)
			(layer "F.Fab")
		)
		(fp_rect
			(start -1.401 -1.45)
			(end 1.398 1.449)
			(stroke
				(width 0.15)
				(type solid)
			)
			(fill no)
			(layer "F.Fab")
		)
		(pad "1" smd roundrect
			(at -1.3 -0.975 180)
			(size 0.45 1.1)
			(layers "F.Cu" "F.Mask" "F.Paste")
			(roundrect_rratio 0.25)
			(net 145 "Net-(D24-C)")
			(pinfunction "IN+")
			(pintype "passive")
			(teardrops
				(best_length_ratio 0.2)
				(max_length 1)
				(best_width_ratio 0.9)
				(max_width 2)
				(curved_edges yes)
				(filter_ratio 0.9)
				(enabled yes)
				(allow_two_segments yes)
				(prefer_zone_connections yes)
			)
		)
		(pad "2" smd roundrect
			(at -1.3 -0.325 180)
			(size 0.45 1.1)
			(layers "F.Cu" "F.Mask" "F.Paste")
			(roundrect_rratio 0.25)
			(net 62 "+12V_AON")
			(pinfunction "IN-")
			(pintype "passive")
			(teardrops
				(best_length_ratio 0.2)
				(max_length 1)
				(best_width_ratio 0.9)
				(max_width 2)
				(curved_edges yes)
				(filter_ratio 0.9)
				(enabled yes)
				(allow_two_segments yes)
				(prefer_zone_connections yes)
			)
		)
		(pad "3" smd roundrect
			(at -1.3 0.325 180)
			(size 0.45 1.1)
			(layers "F.Cu" "F.Mask" "F.Paste")
			(roundrect_rratio 0.25)
			(net 1 "GND")
			(pinfunction "GND")
			(pintype "power_in")
			(teardrops
				(best_length_ratio 0.2)
				(max_length 1)
				(best_width_ratio 0.9)
				(max_width 2)
				(curved_edges yes)
				(filter_ratio 0.9)
				(enabled yes)
				(allow_two_segments yes)
				(prefer_zone_connections yes)
			)
		)
		(pad "4" smd roundrect
			(at -1.3 0.975 180)
			(size 0.45 1.1)
			(layers "F.Cu" "F.Mask" "F.Paste")
			(roundrect_rratio 0.25)
			(net 73 "+3V3_AON")
			(pinfunction "V_{S}")
			(pintype "power_in")
			(teardrops
				(best_length_ratio 0.2)
				(max_length 1)
				(best_width_ratio 0.9)
				(max_width 2)
				(curved_edges yes)
				(filter_ratio 0.9)
				(enabled yes)
				(allow_two_segments yes)
				(prefer_zone_connections yes)
			)
		)
		(pad "5" smd roundrect
			(at 1.3 0.975 180)
			(size 0.45 1.1)
			(layers "F.Cu" "F.Mask" "F.Paste")
			(roundrect_rratio 0.25)
			(net 371 "/Com Express 7 MGMT/I2C.SCL")
			(pinfunction "SCL")
			(pintype "open_collector")
			(teardrops
				(best_length_ratio 0.2)
				(max_length 1)
				(best_width_ratio 0.9)
				(max_width 2)
				(curved_edges yes)
				(filter_ratio 0.9)
				(enabled yes)
				(allow_two_segments yes)
				(prefer_zone_connections yes)
			)
		)
		(pad "6" smd roundrect
			(at 1.3 0.325 180)
			(size 0.45 1.1)
			(layers "F.Cu" "F.Mask" "F.Paste")
			(roundrect_rratio 0.25)
			(net 372 "/Com Express 7 MGMT/I2C.SDA")
			(pinfunction "SDA")
			(pintype "open_collector")
			(teardrops
				(best_length_ratio 0.2)
				(max_length 1)
				(best_width_ratio 0.9)
				(max_width 2)
				(curved_edges yes)
				(filter_ratio 0.9)
				(enabled yes)
				(allow_two_segments yes)
				(prefer_zone_connections yes)
			)
		)
		(pad "7" smd roundrect
			(at 1.3 -0.325 180)
			(size 0.45 1.1)
			(layers "F.Cu" "F.Mask" "F.Paste")
			(roundrect_rratio 0.25)
			(net 1 "GND")
			(pinfunction "A0")
			(pintype "passive")
			(teardrops
				(best_length_ratio 0.2)
				(max_length 1)
				(best_width_ratio 0.9)
				(max_width 2)
				(curved_edges yes)
				(filter_ratio 0.9)
				(enabled yes)
				(allow_two_segments yes)
				(prefer_zone_connections yes)
			)
		)
		(pad "8" smd roundrect
			(at 1.3 -0.975 180)
			(size 0.45 1.1)
			(layers "F.Cu" "F.Mask" "F.Paste")
			(roundrect_rratio 0.25)
			(net 1 "GND")
			(pinfunction "A1")
			(pintype "passive")
			(teardrops
				(best_length_ratio 0.2)
				(max_length 1)
				(best_width_ratio 0.9)
				(max_width 2)
				(curved_edges yes)
				(filter_ratio 0.9)
				(enabled yes)
				(allow_two_segments yes)
				(prefer_zone_connections yes)
			)
		)
	)
	(footprint "antmicro-footprints:C_0201"
		(layer "F.Cu")
		(at 155.572 147.31 90)
		(descr "Capacitor SMD 0201")
		(tags "capacitor SMD 0201")
		(property "Reference" "C153"
			(at -4.125 0.278 90)
			(layer "F.SilkS")
			(effects
				(font
					(size 0.7 0.7)
					(thickness 0.15)
				)
				(justify left bottom)
			)
		)
		(property "Value" "C_100n_0201_25V"
			(at 0 1.4 90)
			(layer "F.Fab")
			(effects
				(font
					(size 0.7 0.7)
					(thickness 0.15)
				)
				(justify left bottom)
			)
		)
		(property "Datasheet" "https://product.tdk.com/en/search/capacitor/ceramic/mlcc/info?part_no=C0603X5R1E104K030BB"
			(at 0 0 90)
			(layer "F.Fab")
			(hide yes)
			(effects
				(font
					(size 1.27 1.27)
					(thickness 0.15)
				)
			)
		)
		(property "Author" "Antmicro"
			(at 302.882 -8.262 0)
			(layer "F.Fab")
			(hide yes)
			(effects
				(font
					(size 1 1)
					(thickness 0.15)
				)
			)
		)
		(property "Dielectric" ""
			(at 302.882 -8.262 0)
			(layer "F.Fab")
			(hide yes)
			(effects
				(font
					(size 1 1)
					(thickness 0.15)
				)
			)
		)
		(property "License" "Apache-2.0"
			(at 302.882 -8.262 0)
			(layer "F.Fab")
			(hide yes)
			(effects
				(font
					(size 1 1)
					(thickness 0.15)
				)
			)
		)
		(property "MPN" "C0603X5R1E104K030BB"
			(at 302.882 -8.262 0)
			(layer "F.Fab")
			(hide yes)
			(effects
				(font
					(size 1 1)
					(thickness 0.15)
				)
			)
		)
		(property "Manufacturer" "TDK"
			(at 302.882 -8.262 0)
			(layer "F.Fab")
			(hide yes)
			(effects
				(font
					(size 1 1)
					(thickness 0.15)
				)
			)
		)
		(property "Public" "False"
			(at 302.882 -8.262 0)
			(layer "F.Fab")
			(hide yes)
			(effects
				(font
					(size 1 1)
					(thickness 0.15)
				)
			)
		)
		(property "Val" "100n"
			(at 302.882 -8.262 0)
			(layer "F.Fab")
			(hide yes)
			(effects
				(font
					(size 1 1)
					(thickness 0.15)
				)
			)
		)
		(property "Voltage" "25V"
			(at 302.882 -8.262 0)
			(layer "F.Fab")
			(hide yes)
			(effects
				(font
					(size 1 1)
					(thickness 0.15)
				)
			)
		)
		(sheetname "KR to SFI #1")
		(sheetfile "kr_sfi.kicad_sch")
		(attr smd)
		(fp_rect
			(start -0.7 -0.35)
			(end 0.7 0.35)
			(stroke
				(width 0.05)
				(type default)
			)
			(fill no)
			(layer "F.CrtYd")
		)
		(fp_rect
			(start 0.3 0.15)
			(end -0.301 -0.149)
			(stroke
				(width 0.15)
				(type solid)
			)
			(fill no)
			(layer "F.Fab")
		)
		(pad "" smd roundrect
			(at -0.349 -0.002 90)
			(size 0.318 0.36)
			(layers "F.Paste")
			(roundrect_rratio 0.25)
			(teardrops
				(best_length_ratio 0.2)
				(max_length 1)
				(best_width_ratio 0.9)
				(max_width 2)
				(curved_edges yes)
				(filter_ratio 0.9)
				(enabled yes)
				(allow_two_segments yes)
				(prefer_zone_connections yes)
			)
		)
		(pad "" smd roundrect
			(at 0.341 -0.002 90)
			(size 0.318 0.36)
			(layers "F.Paste")
			(roundrect_rratio 0.25)
			(teardrops
				(best_length_ratio 0.2)
				(max_length 1)
				(best_width_ratio 0.9)
				(max_width 2)
				(curved_edges yes)
				(filter_ratio 0.9)
				(enabled yes)
				(allow_two_segments yes)
				(prefer_zone_connections yes)
			)
		)
		(pad "1" smd roundrect
			(at -0.321 -0.002 90)
			(size 0.46 0.4)
			(layers "F.Cu" "F.Mask")
			(roundrect_rratio 0.25)
			(net 111 "/2xSFP+/10GKR_SFP0.TX+")
			(pintype "passive")
			(teardrops
				(best_length_ratio 0.2)
				(max_length 1)
				(best_width_ratio 0.9)
				(max_width 2)
				(curved_edges yes)
				(filter_ratio 0.9)
				(enabled yes)
				(allow_two_segments yes)
				(prefer_zone_connections yes)
			)
		)
		(pad "2" smd roundrect
			(at 0.32 -0.002 90)
			(size 0.46 0.4)
			(layers "F.Cu" "F.Mask")
			(roundrect_rratio 0.25)
			(net 112 "/2xSFP+/KR to SFI #1/KR_C.TX+")
			(pintype "passive")
			(teardrops
				(best_length_ratio 0.2)
				(max_length 1)
				(best_width_ratio 0.9)
				(max_width 2)
				(curved_edges yes)
				(filter_ratio 0.9)
				(enabled yes)
				(allow_two_segments yes)
				(prefer_zone_connections yes)
			)
		)
	)
	(footprint "antmicro-footprints:R_0402_1005Metric"
		(layer "F.Cu")
		(at 215.98 133.12 -90)
		(descr "Resistor SMD 0402")
		(tags "resistor SMD 0402")
		(property "Reference" "R198"
			(at 2.44 -5.32 90)
			(layer "F.SilkS")
			(effects
				(font
					(size 0.7 0.7)
					(thickness 0.15)
				)
				(justify right bottom)
			)
		)
		(property "Value" "R_0R_0402"
			(at -1.011843 1.772047 90)
			(layer "F.Fab")
			(effects
				(font
					(size 0.7 0.7)
					(thickness 0.15)
				)
				(justify right bottom)
			)
		)
		(property "Datasheet" "https://industrial.panasonic.com/cdbs/www-data/pdf/RDA0000/AOA0000C301.pdf"
			(at 0 0 270)
			(layer "F.Fab")
			(hide yes)
			(effects
				(font
					(size 1.27 1.27)
					(thickness 0.15)
				)
			)
		)
		(property "Author" "Antmicro"
			(at 82.86 349.1 0)
			(layer "F.Fab")
			(hide yes)
			(effects
				(font
					(size 1 1)
					(thickness 0.15)
				)
			)
		)
		(property "Current" "1A"
			(at 82.86 349.1 0)
			(layer "F.Fab")
			(hide yes)
			(effects
				(font
					(size 1 1)
					(thickness 0.15)
				)
			)
		)
		(property "License" "Apache-2.0"
			(at 82.86 349.1 0)
			(layer "F.Fab")
			(hide yes)
			(effects
				(font
					(size 1 1)
					(thickness 0.15)
				)
			)
		)
		(property "MPN" "ERJ2GE0R00X"
			(at 82.86 349.1 0)
			(layer "F.Fab")
			(hide yes)
			(effects
				(font
					(size 1 1)
					(thickness 0.15)
				)
			)
		)
		(property "Manufacturer" "Panasonic"
			(at 82.86 349.1 0)
			(layer "F.Fab")
			(hide yes)
			(effects
				(font
					(size 1 1)
					(thickness 0.15)
				)
			)
		)
		(property "Public" "False"
			(at 82.86 349.1 0)
			(layer "F.Fab")
			(hide yes)
			(effects
				(font
					(size 1 1)
					(thickness 0.15)
				)
			)
		)
		(property "Tolerance" ""
			(at 82.86 349.1 0)
			(layer "F.Fab")
			(hide yes)
			(effects
				(font
					(size 1 1)
					(thickness 0.15)
				)
			)
		)
		(property "Val" "0R"
			(at 82.86 349.1 0)
			(layer "F.Fab")
			(hide yes)
			(effects
				(font
					(size 1 1)
					(thickness 0.15)
				)
			)
		)
		(sheetname "PCIe misc")
		(sheetfile "pcie_misc.kicad_sch")
		(attr smd)
		(fp_rect
			(start -0.925 -0.47)
			(end 0.925 0.47)
			(stroke
				(width 0.05)
				(type default)
			)
			(fill no)
			(layer "F.CrtYd")
		)
		(fp_rect
			(start -0.5 -0.25)
			(end 0.5 0.25)
			(stroke
				(width 0.15)
				(type solid)
			)
			(fill no)
			(layer "F.Fab")
		)
		(pad "1" smd roundrect
			(at -0.48 0 270)
			(size 0.59 0.64)
			(layers "F.Cu" "F.Mask" "F.Paste")
			(roundrect_rratio 0.25)
			(net 617 "/PCIe misc/DIF3+")
			(pintype "passive")
			(teardrops
				(best_length_ratio 0.2)
				(max_length 1)
				(best_width_ratio 0.9)
				(max_width 2)
				(curved_edges yes)
				(filter_ratio 0.9)
				(enabled yes)
				(allow_two_segments yes)
				(prefer_zone_connections yes)
			)
		)
		(pad "2" smd roundrect
			(at 0.48 0 270)
			(size 0.59 0.64)
			(layers "F.Cu" "F.Mask" "F.Paste")
			(roundrect_rratio 0.25)
			(net 203 "/Backplane/PCIe_{REF}.CK+")
			(pintype "passive")
			(teardrops
				(best_length_ratio 0.2)
				(max_length 1)
				(best_width_ratio 0.9)
				(max_width 2)
				(curved_edges yes)
				(filter_ratio 0.9)
				(enabled yes)
				(allow_two_segments yes)
				(prefer_zone_connections yes)
			)
		)
	)
	(footprint "antmicro-footprints:R_0402_1005Metric"
		(layer "F.Cu")
		(at 120.2 91.26 -90)
		(descr "Resistor SMD 0402")
		(tags "resistor SMD 0402")
		(property "Reference" "R13"
			(at 0.8 -0.4 90)
			(layer "F.SilkS")
			(effects
				(font
					(size 0.7 0.7)
					(thickness 0.15)
				)
				(justify right bottom)
			)
		)
		(property "Value" "R_2k2_0402"
			(at -1.011843 1.772047 90)
			(layer "F.Fab")
			(effects
				(font
					(size 0.7 0.7)
					(thickness 0.15)
				)
				(justify right bottom)
			)
		)
		(property "Datasheet" "https://www.bourns.com/docs/product-datasheets/cr.pdf"
			(at 0 0 270)
			(layer "F.Fab")
			(hide yes)
			(effects
				(font
					(size 1.27 1.27)
					(thickness 0.15)
				)
			)
		)
		(property "Author" "Antmicro"
			(at 28.94 211.46 0)
			(layer "F.Fab")
			(hide yes)
			(effects
				(font
					(size 1 1)
					(thickness 0.15)
				)
			)
		)
		(property "License" "Apache-2.0"
			(at 28.94 211.46 0)
			(layer "F.Fab")
			(hide yes)
			(effects
				(font
					(size 1 1)
					(thickness 0.15)
				)
			)
		)
		(property "MPN" "CR0402-FX-2201GLF"
			(at 28.94 211.46 0)
			(layer "F.Fab")
			(hide yes)
			(effects
				(font
					(size 1 1)
					(thickness 0.15)
				)
			)
		)
		(property "Manufacturer" "Bourns"
			(at 28.94 211.46 0)
			(layer "F.Fab")
			(hide yes)
			(effects
				(font
					(size 1 1)
					(thickness 0.15)
				)
			)
		)
		(property "Public" "False"
			(at 28.94 211.46 0)
			(layer "F.Fab")
			(hide yes)
			(effects
				(font
					(size 1 1)
					(thickness 0.15)
				)
			)
		)
		(property "Tolerance" "1%"
			(at 28.94 211.46 0)
			(layer "F.Fab")
			(hide yes)
			(effects
				(font
					(size 1 1)
					(thickness 0.15)
				)
			)
		)
		(property "Val" "2k2"
			(at 28.94 211.46 0)
			(layer "F.Fab")
			(hide yes)
			(effects
				(font
					(size 1 1)
					(thickness 0.15)
				)
			)
		)
		(sheetname "2xUSB3.0+RJ45")
		(sheetfile "usb3+rj45.kicad_sch")
		(attr smd)
		(fp_rect
			(start -0.925 -0.47)
			(end 0.925 0.47)
			(stroke
				(width 0.05)
				(type default)
			)
			(fill no)
			(layer "F.CrtYd")
		)
		(fp_rect
			(start -0.5 -0.25)
			(end 0.5 0.25)
			(stroke
				(width 0.15)
				(type solid)
			)
			(fill no)
			(layer "F.Fab")
		)
		(pad "1" smd roundrect
			(at -0.48 0 270)
			(size 0.59 0.64)
			(layers "F.Cu" "F.Mask" "F.Paste")
			(roundrect_rratio 0.25)
			(net 1 "GND")
			(pintype "passive")
			(teardrops
				(best_length_ratio 0.2)
				(max_length 1)
				(best_width_ratio 0.9)
				(max_width 2)
				(curved_edges yes)
				(filter_ratio 0.9)
				(enabled yes)
				(allow_two_segments yes)
				(prefer_zone_connections yes)
			)
		)
		(pad "2" smd roundrect
			(at 0.48 0 270)
			(size 0.59 0.64)
			(layers "F.Cu" "F.Mask" "F.Paste")
			(roundrect_rratio 0.25)
			(net 548 "/2xUSB3.0+RJ45/P2_ISET")
			(pintype "passive")
			(teardrops
				(best_length_ratio 0.2)
				(max_length 1)
				(best_width_ratio 0.9)
				(max_width 2)
				(curved_edges yes)
				(filter_ratio 0.9)
				(enabled yes)
				(allow_two_segments yes)
				(prefer_zone_connections yes)
			)
		)
	)
	(footprint "antmicro-footprints:R_0402_1005Metric"
		(layer "F.Cu")
		(at 155.299 168.36 180)
		(descr "Resistor SMD 0402")
		(tags "resistor SMD 0402")
		(property "Reference" "R64"
			(at -4.551 18.1 0)
			(layer "F.SilkS")
			(effects
				(font
					(size 0.7 0.7)
					(thickness 0.15)
				)
				(justify left bottom)
			)
		)
		(property "Value" "R_220R_0402"
			(at -1.011843 1.772047 0)
			(layer "F.Fab")
			(effects
				(font
					(size 0.7 0.7)
					(thickness 0.15)
				)
				(justify right bottom)
			)
		)
		(property "Datasheet" "https://www.bourns.com/docs/product-datasheets/cr.pdf"
			(at 0 0 180)
			(layer "F.Fab")
			(hide yes)
			(effects
				(font
					(size 1.27 1.27)
					(thickness 0.15)
				)
			)
		)
		(property "Author" "Antmicro"
			(at 310.598 336.72 0)
			(layer "F.Fab")
			(hide yes)
			(effects
				(font
					(size 1 1)
					(thickness 0.15)
				)
			)
		)
		(property "License" "Apache-2.0"
			(at 310.598 336.72 0)
			(layer "F.Fab")
			(hide yes)
			(effects
				(font
					(size 1 1)
					(thickness 0.15)
				)
			)
		)
		(property "MPN" "CR0402-FX-2200GLF"
			(at 310.598 336.72 0)
			(layer "F.Fab")
			(hide yes)
			(effects
				(font
					(size 1 1)
					(thickness 0.15)
				)
			)
		)
		(property "Manufacturer" "Bourns"
			(at 310.598 336.72 0)
			(layer "F.Fab")
			(hide yes)
			(effects
				(font
					(size 1 1)
					(thickness 0.15)
				)
			)
		)
		(property "Public" "False"
			(at 310.598 336.72 0)
			(layer "F.Fab")
			(hide yes)
			(effects
				(font
					(size 1 1)
					(thickness 0.15)
				)
			)
		)
		(property "Tolerance" "1%"
			(at 310.598 336.72 0)
			(layer "F.Fab")
			(hide yes)
			(effects
				(font
					(size 1 1)
					(thickness 0.15)
				)
			)
		)
		(property "Val" "220R"
			(at 310.598 336.72 0)
			(layer "F.Fab")
			(hide yes)
			(effects
				(font
					(size 1 1)
					(thickness 0.15)
				)
			)
		)
		(sheetname "2xSFP+")
		(sheetfile "2xSFP+.kicad_sch")
		(attr smd)
		(fp_rect
			(start -0.925 -0.47)
			(end 0.925 0.47)
			(stroke
				(width 0.05)
				(type default)
			)
			(fill no)
			(layer "F.CrtYd")
		)
		(fp_rect
			(start -0.5 -0.25)
			(end 0.5 0.25)
			(stroke
				(width 0.15)
				(type solid)
			)
			(fill no)
			(layer "F.Fab")
		)
		(pad "1" smd roundrect
			(at -0.48 0 180)
			(size 0.59 0.64)
			(layers "F.Cu" "F.Mask" "F.Paste")
			(roundrect_rratio 0.25)
			(net 929 "/2xSFP+/SFP1_LEDG")
			(pintype "passive")
			(teardrops
				(best_length_ratio 0.2)
				(max_length 1)
				(best_width_ratio 0.9)
				(max_width 2)
				(curved_edges yes)
				(filter_ratio 0.9)
				(enabled yes)
				(allow_two_segments yes)
				(prefer_zone_connections yes)
			)
		)
		(pad "2" smd roundrect
			(at 0.48 0 180)
			(size 0.59 0.64)
			(layers "F.Cu" "F.Mask" "F.Paste")
			(roundrect_rratio 0.25)
			(net 932 "Net-(D7-C)")
			(pintype "passive")
			(teardrops
				(best_length_ratio 0.2)
				(max_length 1)
				(best_width_ratio 0.9)
				(max_width 2)
				(curved_edges yes)
				(filter_ratio 0.9)
				(enabled yes)
				(allow_two_segments yes)
				(prefer_zone_connections yes)
			)
		)
	)
	(footprint "antmicro-footprints:R_0402_1005Metric"
		(layer "F.Cu")
		(at 178.4 145.999999 180)
		(descr "Resistor SMD 0402")
		(tags "resistor SMD 0402")
		(property "Reference" "R42"
			(at -2.95 -0.45 0)
			(layer "F.SilkS")
			(effects
				(font
					(size 0.7 0.7)
					(thickness 0.15)
				)
				(justify right bottom)
			)
		)
		(property "Value" "R_0R_0402"
			(at -1.011843 1.772046 0)
			(layer "F.Fab")
			(effects
				(font
					(size 0.7 0.7)
					(thickness 0.15)
				)
				(justify right bottom)
			)
		)
		(property "Datasheet" "https://industrial.panasonic.com/cdbs/www-data/pdf/RDA0000/AOA0000C301.pdf"
			(at 0 0 0)
			(layer "F.Fab")
			(hide yes)
			(effects
				(font
					(size 1.27 1.27)
					(thickness 0.15)
				)
			)
		)
		(property "Author" "Antmicro"
			(at 337.9 334.52 0)
			(layer "F.Fab")
			(hide yes)
			(effects
				(font
					(size 1 1)
					(thickness 0.15)
				)
			)
		)
		(property "Current" "1A"
			(at 337.9 334.52 0)
			(layer "F.Fab")
			(hide yes)
			(effects
				(font
					(size 1 1)
					(thickness 0.15)
				)
			)
		)
		(property "License" "Apache-2.0"
			(at 337.9 334.52 0)
			(layer "F.Fab")
			(hide yes)
			(effects
				(font
					(size 1 1)
					(thickness 0.15)
				)
			)
		)
		(property "MPN" "ERJ2GE0R00X"
			(at 337.9 334.52 0)
			(layer "F.Fab")
			(hide yes)
			(effects
				(font
					(size 1 1)
					(thickness 0.15)
				)
			)
		)
		(property "Manufacturer" "Panasonic"
			(at 337.9 334.52 0)
			(layer "F.Fab")
			(hide yes)
			(effects
				(font
					(size 1 1)
					(thickness 0.15)
				)
			)
		)
		(property "Public" "False"
			(at 337.9 334.52 0)
			(layer "F.Fab")
			(hide yes)
			(effects
				(font
					(size 1 1)
					(thickness 0.15)
				)
			)
		)
		(property "Tolerance" ""
			(at 337.9 334.52 0)
			(layer "F.Fab")
			(hide yes)
			(effects
				(font
					(size 1 1)
					(thickness 0.15)
				)
			)
		)
		(property "Val" "0R"
			(at 337.9 334.52 0)
			(layer "F.Fab")
			(hide yes)
			(effects
				(font
					(size 1 1)
					(thickness 0.15)
				)
			)
		)
		(sheetname "2xSFP+")
		(sheetfile "2xSFP+.kicad_sch")
		(attr smd)
		(fp_rect
			(start -0.925 -0.47)
			(end 0.925 0.47)
			(stroke
				(width 0.05)
				(type default)
			)
			(fill no)
			(layer "F.CrtYd")
		)
		(fp_rect
			(start -0.5 -0.25)
			(end 0.5 0.25)
			(stroke
				(width 0.15)
				(type solid)
			)
			(fill no)
			(layer "F.Fab")
		)
		(pad "1" smd roundrect
			(at -0.48 0 180)
			(size 0.59 0.64)
			(layers "F.Cu" "F.Mask" "F.Paste")
			(roundrect_rratio 0.25)
			(net 492 "/2xSFP+/MOD1_ABS")
			(pintype "passive")
			(teardrops
				(best_length_ratio 0.2)
				(max_length 1)
				(best_width_ratio 0.9)
				(max_width 2)
				(curved_edges yes)
				(filter_ratio 0.9)
				(enabled yes)
				(allow_two_segments yes)
				(prefer_zone_connections yes)
			)
		)
		(pad "2" smd roundrect
			(at 0.48 0 180)
			(size 0.59 0.64)
			(layers "F.Cu" "F.Mask" "F.Paste")
			(roundrect_rratio 0.25)
			(net 894 "Net-(J2B-MOD_{ABS})")
			(pintype "passive")
			(teardrops
				(best_length_ratio 0.2)
				(max_length 1)
				(best_width_ratio 0.9)
				(max_width 2)
				(curved_edges yes)
				(filter_ratio 0.9)
				(enabled yes)
				(allow_two_segments yes)
				(prefer_zone_connections yes)
			)
		)
	)
	(footprint "antmicro-footprints:R_0402_1005Metric"
		(layer "F.Cu")
		(at 311.765499 97.4365 -90)
		(descr "Resistor SMD 0402")
		(tags "resistor SMD 0402")
		(property "Reference" "R108"
			(at -10.1265 -4.734501 90)
			(layer "F.SilkS")
			(effects
				(font
					(size 0.7 0.7)
					(thickness 0.15)
				)
				(justify right bottom)
			)
		)
		(property "Value" "R_10k_0402"
			(at -1.011843 1.772047 90)
			(layer "F.Fab")
			(effects
				(font
					(size 0.7 0.7)
					(thickness 0.15)
				)
				(justify right bottom)
			)
		)
		(property "Datasheet" "https://www.bourns.com/docs/product-datasheets/cr.pdf"
			(at 0 0 270)
			(layer "F.Fab")
			(hide yes)
			(effects
				(font
					(size 1.27 1.27)
					(thickness 0.15)
				)
			)
		)
		(property "Author" "Antmicro"
			(at 214.328999 409.201999 0)
			(layer "F.Fab")
			(hide yes)
			(effects
				(font
					(size 1 1)
					(thickness 0.15)
				)
			)
		)
		(property "License" "Apache-2.0"
			(at 214.328999 409.201999 0)
			(layer "F.Fab")
			(hide yes)
			(effects
				(font
					(size 1 1)
					(thickness 0.15)
				)
			)
		)
		(property "MPN" "CR0402-FX-1002GLF"
			(at 214.328999 409.201999 0)
			(layer "F.Fab")
			(hide yes)
			(effects
				(font
					(size 1 1)
					(thickness 0.15)
				)
			)
		)
		(property "Manufacturer" "Bourns"
			(at 214.328999 409.201999 0)
			(layer "F.Fab")
			(hide yes)
			(effects
				(font
					(size 1 1)
					(thickness 0.15)
				)
			)
		)
		(property "Public" "False"
			(at 214.328999 409.201999 0)
			(layer "F.Fab")
			(hide yes)
			(effects
				(font
					(size 1 1)
					(thickness 0.15)
				)
			)
		)
		(property "Tolerance" "1%"
			(at 214.328999 409.201999 0)
			(layer "F.Fab")
			(hide yes)
			(effects
				(font
					(size 1 1)
					(thickness 0.15)
				)
			)
		)
		(property "Val" "10k"
			(at 214.328999 409.201999 0)
			(layer "F.Fab")
			(hide yes)
			(effects
				(font
					(size 1 1)
					(thickness 0.15)
				)
			)
		)
		(sheetname "Power")
		(sheetfile "power.kicad_sch")
		(attr smd)
		(fp_rect
			(start -0.925 -0.47)
			(end 0.925 0.47)
			(stroke
				(width 0.05)
				(type default)
			)
			(fill no)
			(layer "F.CrtYd")
		)
		(fp_rect
			(start -0.5 -0.25)
			(end 0.5 0.25)
			(stroke
				(width 0.15)
				(type solid)
			)
			(fill no)
			(layer "F.Fab")
		)
		(pad "1" smd roundrect
			(at -0.48 0 270)
			(size 0.59 0.64)
			(layers "F.Cu" "F.Mask" "F.Paste")
			(roundrect_rratio 0.25)
			(net 1 "GND")
			(pintype "passive")
			(teardrops
				(best_length_ratio 0.2)
				(max_length 1)
				(best_width_ratio 0.9)
				(max_width 2)
				(curved_edges yes)
				(filter_ratio 0.9)
				(enabled yes)
				(allow_two_segments yes)
				(prefer_zone_connections yes)
			)
		)
		(pad "2" smd roundrect
			(at 0.48 0 270)
			(size 0.59 0.64)
			(layers "F.Cu" "F.Mask" "F.Paste")
			(roundrect_rratio 0.25)
			(net 584 "Net-(U21-EN)")
			(pintype "passive")
			(teardrops
				(best_length_ratio 0.2)
				(max_length 1)
				(best_width_ratio 0.9)
				(max_width 2)
				(curved_edges yes)
				(filter_ratio 0.9)
				(enabled yes)
				(allow_two_segments yes)
				(prefer_zone_connections yes)
			)
		)
	)
	(footprint "antmicro-footprints:R_0402_1005Metric"
		(layer "F.Cu")
		(at 129.9 81.760001 -90)
		(descr "Resistor SMD 0402")
		(tags "resistor SMD 0402")
		(property "Reference" "R235"
			(at -3.650001 -0.45 90)
			(layer "F.SilkS")
			(effects
				(font
					(size 0.7 0.7)
					(thickness 0.15)
				)
				(justify right bottom)
			)
		)
		(property "Value" "R_0R_0402"
			(at -1.011843 1.772047 90)
			(layer "F.Fab")
			(effects
				(font
					(size 0.7 0.7)
					(thickness 0.15)
				)
				(justify right bottom)
			)
		)
		(property "Datasheet" "https://industrial.panasonic.com/cdbs/www-data/pdf/RDA0000/AOA0000C301.pdf"
			(at 0 0 270)
			(layer "F.Fab")
			(hide yes)
			(effects
				(font
					(size 1.27 1.27)
					(thickness 0.15)
				)
			)
		)
		(property "Author" "Antmicro"
			(at 48.139999 211.660001 0)
			(layer "F.Fab")
			(hide yes)
			(effects
				(font
					(size 1 1)
					(thickness 0.15)
				)
			)
		)
		(property "Current" "1A"
			(at 48.139999 211.660001 0)
			(layer "F.Fab")
			(hide yes)
			(effects
				(font
					(size 1 1)
					(thickness 0.15)
				)
			)
		)
		(property "License" "Apache-2.0"
			(at 48.139999 211.660001 0)
			(layer "F.Fab")
			(hide yes)
			(effects
				(font
					(size 1 1)
					(thickness 0.15)
				)
			)
		)
		(property "MPN" "ERJ2GE0R00X"
			(at 48.139999 211.660001 0)
			(layer "F.Fab")
			(hide yes)
			(effects
				(font
					(size 1 1)
					(thickness 0.15)
				)
			)
		)
		(property "Manufacturer" "Panasonic"
			(at 48.139999 211.660001 0)
			(layer "F.Fab")
			(hide yes)
			(effects
				(font
					(size 1 1)
					(thickness 0.15)
				)
			)
		)
		(property "Public" "False"
			(at 48.139999 211.660001 0)
			(layer "F.Fab")
			(hide yes)
			(effects
				(font
					(size 1 1)
					(thickness 0.15)
				)
			)
		)
		(property "Tolerance" ""
			(at 48.139999 211.660001 0)
			(layer "F.Fab")
			(hide yes)
			(effects
				(font
					(size 1 1)
					(thickness 0.15)
				)
			)
		)
		(property "Val" "0R"
			(at 48.139999 211.660001 0)
			(layer "F.Fab")
			(hide yes)
			(effects
				(font
					(size 1 1)
					(thickness 0.15)
				)
			)
		)
		(sheetname "GPIO expander")
		(sheetfile "gpio_exp.kicad_sch")
		(attr smd)
		(fp_rect
			(start -0.925 -0.47)
			(end 0.925 0.47)
			(stroke
				(width 0.05)
				(type default)
			)
			(fill no)
			(layer "F.CrtYd")
		)
		(fp_rect
			(start -0.5 -0.25)
			(end 0.5 0.25)
			(stroke
				(width 0.15)
				(type solid)
			)
			(fill no)
			(layer "F.Fab")
		)
		(pad "1" smd roundrect
			(at -0.48 0 270)
			(size 0.59 0.64)
			(layers "F.Cu" "F.Mask" "F.Paste")
			(roundrect_rratio 0.25)
			(net 359 "/Com Express 7 MGMT/SMBus.~{INT}")
			(pintype "passive")
			(teardrops
				(best_length_ratio 0.2)
				(max_length 1)
				(best_width_ratio 0.9)
				(max_width 2)
				(curved_edges yes)
				(filter_ratio 0.9)
				(enabled yes)
				(allow_two_segments yes)
				(prefer_zone_connections yes)
			)
		)
		(pad "2" smd roundrect
			(at 0.48 0 270)
			(size 0.59 0.64)
			(layers "F.Cu" "F.Mask" "F.Paste")
			(roundrect_rratio 0.25)
			(net 636 "Net-(U41-~{INT})")
			(pintype "passive")
			(teardrops
				(best_length_ratio 0.2)
				(max_length 1)
				(best_width_ratio 0.9)
				(max_width 2)
				(curved_edges yes)
				(filter_ratio 0.9)
				(enabled yes)
				(allow_two_segments yes)
				(prefer_zone_connections yes)
			)
		)
	)
	(footprint "antmicro-footprints:TSSOP-8_3x3mm_P0.65mm"
		(layer "F.Cu")
		(at 248.700709 78.085)
		(property "Reference" "U28"
			(at -1.950709 2.735 0)
			(layer "F.SilkS")
			(effects
				(font
					(size 0.7 0.7)
					(thickness 0.15)
				)
				(justify left bottom)
			)
		)
		(property "Value" "NTS0102_TSSOP"
			(at 0 2.8 0)
			(layer "F.Fab")
			(effects
				(font
					(size 0.7 0.7)
					(thickness 0.15)
				)
				(justify left bottom)
			)
		)
		(property "Datasheet" "https://www.mouser.com/datasheet/2/302/NTS0102-1127324.pdf"
			(at 0 0 0)
			(layer "F.Fab")
			(hide yes)
			(effects
				(font
					(size 1.27 1.27)
					(thickness 0.15)
				)
			)
		)
		(property "Author" "Antmicro"
			(at 0 0 0)
			(layer "F.Fab")
			(hide yes)
			(effects
				(font
					(size 1 1)
					(thickness 0.15)
				)
			)
		)
		(property "License" "Apache-2.0"
			(at 0 0 0)
			(layer "F.Fab")
			(hide yes)
			(effects
				(font
					(size 1 1)
					(thickness 0.15)
				)
			)
		)
		(property "MPN" "NTS0102DP"
			(at 0 0 0)
			(layer "F.Fab")
			(hide yes)
			(effects
				(font
					(size 1 1)
					(thickness 0.15)
				)
			)
		)
		(property "Manufacturer" "NXP"
			(at 0 0 0)
			(layer "F.Fab")
			(hide yes)
			(effects
				(font
					(size 1 1)
					(thickness 0.15)
				)
			)
		)
		(sheetname "Misc")
		(sheetfile "misc.kicad_sch")
		(attr smd)
		(fp_line
			(start -1.55 1.561)
			(end 1.552 1.561)
			(stroke
				(width 0.15)
				(type solid)
			)
			(layer "F.SilkS")
		)
		(fp_line
			(start -1.525 -1.537)
			(end 1.552 -1.539)
			(stroke
				(width 0.15)
				(type solid)
			)
			(layer "F.SilkS")
		)
		(fp_circle
			(center -1.87 -1.4)
			(end -1.82 -1.4)
			(stroke
				(width 0.15)
				(type solid)
			)
			(fill yes)
			(layer "F.SilkS")
		)
		(fp_rect
			(start -3.15 -1.789)
			(end 3.15 1.811)
			(stroke
				(width 0.05)
				(type solid)
			)
			(fill no)
			(layer "F.CrtYd")
		)
		(fp_line
			(start -1.55 -0.937)
			(end -1.55 1.561)
			(stroke
				(width 0.15)
				(type solid)
			)
			(layer "F.Fab")
		)
		(fp_line
			(start -1.55 -0.937)
			(end -0.949 -1.539)
			(stroke
				(width 0.15)
				(type solid)
			)
			(layer "F.Fab")
		)
		(fp_line
			(start -1.55 1.561)
			(end 1.552 1.561)
			(stroke
				(width 0.15)
				(type solid)
			)
			(layer "F.Fab")
		)
		(fp_line
			(start -0.949 -1.539)
			(end 1.552 -1.539)
			(stroke
				(width 0.15)
				(type solid)
			)
			(layer "F.Fab")
		)
		(fp_line
			(start 1.552 -1.539)
			(end 1.552 1.561)
			(stroke
				(width 0.15)
				(type solid)
			)
			(layer "F.Fab")
		)
		(pad "1" smd roundrect
			(at -2.148 -0.962)
			(size 1.47 0.4)
			(layers "F.Cu" "F.Mask" "F.Paste")
			(roundrect_rratio 0.25)
			(net 282 "/Misc/PWM_{B5V}")
			(pinfunction "B_{2}")
			(pintype "bidirectional")
			(teardrops
				(best_length_ratio 0.2)
				(max_length 1)
				(best_width_ratio 0.9)
				(max_width 2)
				(curved_edges yes)
				(filter_ratio 0.9)
				(enabled yes)
				(allow_two_segments yes)
				(prefer_zone_connections yes)
			)
		)
		(pad "2" smd roundrect
			(at -2.148 -0.313)
			(size 1.47 0.4)
			(layers "F.Cu" "F.Mask" "F.Paste")
			(roundrect_rratio 0.25)
			(net 1 "GND")
			(pinfunction "GND")
			(pintype "power_in")
			(teardrops
				(best_length_ratio 0.2)
				(max_length 1)
				(best_width_ratio 0.9)
				(max_width 2)
				(curved_edges yes)
				(filter_ratio 0.9)
				(enabled yes)
				(allow_two_segments yes)
				(prefer_zone_connections yes)
			)
		)
		(pad "3" smd roundrect
			(at -2.148 0.338)
			(size 1.47 0.4)
			(layers "F.Cu" "F.Mask" "F.Paste")
			(roundrect_rratio 0.25)
			(net 2 "+3V3")
			(pinfunction "VCC_{A}")
			(pintype "power_in")
			(teardrops
				(best_length_ratio 0.2)
				(max_length 1)
				(best_width_ratio 0.9)
				(max_width 2)
				(curved_edges yes)
				(filter_ratio 0.9)
				(enabled yes)
				(allow_two_segments yes)
				(prefer_zone_connections yes)
			)
		)
		(pad "4" smd roundrect
			(at -2.148 0.987)
			(size 1.47 0.4)
			(layers "F.Cu" "F.Mask" "F.Paste")
			(roundrect_rratio 0.25)
			(net 783 "/Misc/PWM_{B3V3}")
			(pinfunction "A_{2}")
			(pintype "bidirectional")
			(teardrops
				(best_length_ratio 0.2)
				(max_length 1)
				(best_width_ratio 0.9)
				(max_width 2)
				(curved_edges yes)
				(filter_ratio 0.9)
				(enabled yes)
				(allow_two_segments yes)
				(prefer_zone_connections yes)
			)
		)
		(pad "5" smd roundrect
			(at 2.151 0.987)
			(size 1.47 0.4)
			(layers "F.Cu" "F.Mask" "F.Paste")
			(roundrect_rratio 0.25)
			(net 781 "/Misc/TACH_{B3V3}")
			(pinfunction "A_{1}")
			(pintype "bidirectional")
			(teardrops
				(best_length_ratio 0.2)
				(max_length 1)
				(best_width_ratio 0.9)
				(max_width 2)
				(curved_edges yes)
				(filter_ratio 0.9)
				(enabled yes)
				(allow_two_segments yes)
				(prefer_zone_connections yes)
			)
		)
		(pad "6" smd roundrect
			(at 2.151 0.338)
			(size 1.47 0.4)
			(layers "F.Cu" "F.Mask" "F.Paste")
			(roundrect_rratio 0.25)
			(net 2 "+3V3")
			(pinfunction "OE")
			(pintype "input")
			(teardrops
				(best_length_ratio 0.2)
				(max_length 1)
				(best_width_ratio 0.9)
				(max_width 2)
				(curved_edges yes)
				(filter_ratio 0.9)
				(enabled yes)
				(allow_two_segments yes)
				(prefer_zone_connections yes)
			)
		)
		(pad "7" smd roundrect
			(at 2.151 -0.313)
			(size 1.47 0.4)
			(layers "F.Cu" "F.Mask" "F.Paste")
			(roundrect_rratio 0.25)
			(net 52 "+5V")
			(pinfunction "VCC_{B}")
			(pintype "power_in")
			(teardrops
				(best_length_ratio 0.2)
				(max_length 1)
				(best_width_ratio 0.9)
				(max_width 2)
				(curved_edges yes)
				(filter_ratio 0.9)
				(enabled yes)
				(allow_two_segments yes)
				(prefer_zone_connections yes)
			)
		)
		(pad "8" smd roundrect
			(at 2.151 -0.962)
			(size 1.47 0.4)
			(layers "F.Cu" "F.Mask" "F.Paste")
			(roundrect_rratio 0.25)
			(net 281 "/Misc/TACH_{B5V}")
			(pinfunction "B_{1}")
			(pintype "bidirectional")
			(teardrops
				(best_length_ratio 0.2)
				(max_length 1)
				(best_width_ratio 0.9)
				(max_width 2)
				(curved_edges yes)
				(filter_ratio 0.9)
				(enabled yes)
				(allow_two_segments yes)
				(prefer_zone_connections yes)
			)
		)
	)
	(footprint "antmicro-footprints:R_0402_1005Metric"
		(layer "F.Cu")
		(at 155.299 166.36 180)
		(descr "Resistor SMD 0402")
		(tags "resistor SMD 0402")
		(property "Reference" "R65"
			(at -4.551 18.05 0)
			(layer "F.SilkS")
			(effects
				(font
					(size 0.7 0.7)
					(thickness 0.15)
				)
				(justify left bottom)
			)
		)
		(property "Value" "R_220R_0402"
			(at -1.011843 1.772047 0)
			(layer "F.Fab")
			(effects
				(font
					(size 0.7 0.7)
					(thickness 0.15)
				)
				(justify right bottom)
			)
		)
		(property "Datasheet" "https://www.bourns.com/docs/product-datasheets/cr.pdf"
			(at 0 0 180)
			(layer "F.Fab")
			(hide yes)
			(effects
				(font
					(size 1.27 1.27)
					(thickness 0.15)
				)
			)
		)
		(property "Author" "Antmicro"
			(at 310.598 332.72 0)
			(layer "F.Fab")
			(hide yes)
			(effects
				(font
					(size 1 1)
					(thickness 0.15)
				)
			)
		)
		(property "License" "Apache-2.0"
			(at 310.598 332.72 0)
			(layer "F.Fab")
			(hide yes)
			(effects
				(font
					(size 1 1)
					(thickness 0.15)
				)
			)
		)
		(property "MPN" "CR0402-FX-2200GLF"
			(at 310.598 332.72 0)
			(layer "F.Fab")
			(hide yes)
			(effects
				(font
					(size 1 1)
					(thickness 0.15)
				)
			)
		)
		(property "Manufacturer" "Bourns"
			(at 310.598 332.72 0)
			(layer "F.Fab")
			(hide yes)
			(effects
				(font
					(size 1 1)
					(thickness 0.15)
				)
			)
		)
		(property "Public" "False"
			(at 310.598 332.72 0)
			(layer "F.Fab")
			(hide yes)
			(effects
				(font
					(size 1 1)
					(thickness 0.15)
				)
			)
		)
		(property "Tolerance" "1%"
			(at 310.598 332.72 0)
			(layer "F.Fab")
			(hide yes)
			(effects
				(font
					(size 1 1)
					(thickness 0.15)
				)
			)
		)
		(property "Val" "220R"
			(at 310.598 332.72 0)
			(layer "F.Fab")
			(hide yes)
			(effects
				(font
					(size 1 1)
					(thickness 0.15)
				)
			)
		)
		(sheetname "2xSFP+")
		(sheetfile "2xSFP+.kicad_sch")
		(attr smd)
		(fp_rect
			(start -0.925 -0.47)
			(end 0.925 0.47)
			(stroke
				(width 0.05)
				(type default)
			)
			(fill no)
			(layer "F.CrtYd")
		)
		(fp_rect
			(start -0.5 -0.25)
			(end 0.5 0.25)
			(stroke
				(width 0.15)
				(type solid)
			)
			(fill no)
			(layer "F.Fab")
		)
		(pad "1" smd roundrect
			(at -0.48 0 180)
			(size 0.59 0.64)
			(layers "F.Cu" "F.Mask" "F.Paste")
			(roundrect_rratio 0.25)
			(net 931 "/2xSFP+/SFP0_LEDG")
			(pintype "passive")
			(teardrops
				(best_length_ratio 0.2)
				(max_length 1)
				(best_width_ratio 0.9)
				(max_width 2)
				(curved_edges yes)
				(filter_ratio 0.9)
				(enabled yes)
				(allow_two_segments yes)
				(prefer_zone_connections yes)
			)
		)
		(pad "2" smd roundrect
			(at 0.48 0 180)
			(size 0.59 0.64)
			(layers "F.Cu" "F.Mask" "F.Paste")
			(roundrect_rratio 0.25)
			(net 940 "Net-(D8-C)")
			(pintype "passive")
			(teardrops
				(best_length_ratio 0.2)
				(max_length 1)
				(best_width_ratio 0.9)
				(max_width 2)
				(curved_edges yes)
				(filter_ratio 0.9)
				(enabled yes)
				(allow_two_segments yes)
				(prefer_zone_connections yes)
			)
		)
	)
	(footprint "antmicro-footprints:R_0402_1005Metric"
		(layer "F.Cu")
		(at 193.05 130.2 -135)
		(descr "Resistor SMD 0402")
		(tags "resistor SMD 0402")
		(property "Reference" "R225"
			(at -3.65 -0.4 45)
			(layer "F.SilkS")
			(effects
				(font
					(size 0.7 0.7)
					(thickness 0.15)
				)
				(justify right bottom)
			)
		)
		(property "Value" "R_1k_0402"
			(at -1.011843 1.772046 45)
			(layer "F.Fab")
			(effects
				(font
					(size 0.7 0.7)
					(thickness 0.15)
				)
				(justify right bottom)
			)
		)
		(property "Datasheet" "https://www.bourns.com/docs/product-datasheets/cr.pdf"
			(at 0 0 45)
			(layer "F.Fab")
			(hide yes)
			(effects
				(font
					(size 1.27 1.27)
					(thickness 0.15)
				)
			)
		)
		(property "Author" "Antmicro"
			(at 389.100001 263.22 45)
			(layer "F.Fab")
			(hide yes)
			(effects
				(font
					(size 1 1)
					(thickness 0.15)
				)
			)
		)
		(property "License" "Apache-2.0"
			(at 389.100001 263.22 45)
			(layer "F.Fab")
			(hide yes)
			(effects
				(font
					(size 1 1)
					(thickness 0.15)
				)
			)
		)
		(property "MPN" "CR0402-FX-1001GLF"
			(at 389.100001 263.22 45)
			(layer "F.Fab")
			(hide yes)
			(effects
				(font
					(size 1 1)
					(thickness 0.15)
				)
			)
		)
		(property "Manufacturer" "Bourns"
			(at 389.100001 263.22 45)
			(layer "F.Fab")
			(hide yes)
			(effects
				(font
					(size 1 1)
					(thickness 0.15)
				)
			)
		)
		(property "Public" "False"
			(at 389.100001 263.22 45)
			(layer "F.Fab")
			(hide yes)
			(effects
				(font
					(size 1 1)
					(thickness 0.15)
				)
			)
		)
		(property "Tolerance" "1%"
			(at 389.100001 263.22 45)
			(layer "F.Fab")
			(hide yes)
			(effects
				(font
					(size 1 1)
					(thickness 0.15)
				)
			)
		)
		(property "Val" "1k"
			(at 389.100001 263.22 45)
			(layer "F.Fab")
			(hide yes)
			(effects
				(font
					(size 1 1)
					(thickness 0.15)
				)
			)
		)
		(sheetname "PCIe redriver")
		(sheetfile "pcie_redriver.kicad_sch")
		(attr smd)
		(fp_poly
			(pts
				(xy -0.925 -0.47) (xy 0.925 -0.47) (xy 0.925 0.47) (xy -0.925 0.47)
			)
			(stroke
				(width 0.05)
				(type default)
			)
			(fill no)
			(layer "F.CrtYd")
		)
		(fp_poly
			(pts
				(xy -0.5 -0.25) (xy 0.5 -0.25) (xy 0.5 0.25) (xy -0.5 0.25)
			)
			(stroke
				(width 0.15)
				(type solid)
			)
			(fill no)
			(layer "F.Fab")
		)
		(pad "1" smd roundrect
			(at -0.48 0 225)
			(size 0.59 0.64)
			(layers "F.Cu" "F.Mask" "F.Paste")
			(roundrect_rratio 0.25)
			(net 2 "+3V3")
			(pintype "passive")
			(teardrops
				(best_length_ratio 0.2)
				(max_length 1)
				(best_width_ratio 0.9)
				(max_width 2)
				(curved_edges yes)
				(filter_ratio 0.9)
				(enabled yes)
				(allow_two_segments yes)
				(prefer_zone_connections yes)
			)
		)
		(pad "2" smd roundrect
			(at 0.48 0 225)
			(size 0.59 0.64)
			(layers "F.Cu" "F.Mask" "F.Paste")
			(roundrect_rratio 0.25)
			(net 976 "/PCIe redriver/RX_EQ2")
			(pintype "passive")
			(teardrops
				(best_length_ratio 0.2)
				(max_length 1)
				(best_width_ratio 0.9)
				(max_width 2)
				(curved_edges yes)
				(filter_ratio 0.9)
				(enabled yes)
				(allow_two_segments yes)
				(prefer_zone_connections yes)
			)
		)
	)
	(footprint "antmicro-footprints:R_0402_1005Metric"
		(layer "F.Cu")
		(at 136.6 113.11 180)
		(descr "Resistor SMD 0402")
		(tags "resistor SMD 0402")
		(property "Reference" "R14"
			(at -1.15 -1.4 0)
			(layer "F.SilkS")
			(effects
				(font
					(size 0.7 0.7)
					(thickness 0.15)
				)
				(justify right bottom)
			)
		)
		(property "Value" "R_75R_0402"
			(at -1.011843 1.772047 0)
			(layer "F.Fab")
			(effects
				(font
					(size 0.7 0.7)
					(thickness 0.15)
				)
				(justify right bottom)
			)
		)
		(property "Datasheet" "https://www.bourns.com/docs/product-datasheets/cr.pdf"
			(at 0 0 180)
			(layer "F.Fab")
			(hide yes)
			(effects
				(font
					(size 1.27 1.27)
					(thickness 0.15)
				)
			)
		)
		(property "Author" "Antmicro"
			(at 273.2 226.22 0)
			(layer "F.Fab")
			(hide yes)
			(effects
				(font
					(size 1 1)
					(thickness 0.15)
				)
			)
		)
		(property "License" "Apache-2.0"
			(at 273.2 226.22 0)
			(layer "F.Fab")
			(hide yes)
			(effects
				(font
					(size 1 1)
					(thickness 0.15)
				)
			)
		)
		(property "MPN" "CR0402-FX-75R0GLF"
			(at 273.2 226.22 0)
			(layer "F.Fab")
			(hide yes)
			(effects
				(font
					(size 1 1)
					(thickness 0.15)
				)
			)
		)
		(property "Manufacturer" "Bourns"
			(at 273.2 226.22 0)
			(layer "F.Fab")
			(hide yes)
			(effects
				(font
					(size 1 1)
					(thickness 0.15)
				)
			)
		)
		(property "Public" "False"
			(at 273.2 226.22 0)
			(layer "F.Fab")
			(hide yes)
			(effects
				(font
					(size 1 1)
					(thickness 0.15)
				)
			)
		)
		(property "Tolerance" "1%"
			(at 273.2 226.22 0)
			(layer "F.Fab")
			(hide yes)
			(effects
				(font
					(size 1 1)
					(thickness 0.15)
				)
			)
		)
		(property "Val" "75R"
			(at 273.2 226.22 0)
			(layer "F.Fab")
			(hide yes)
			(effects
				(font
					(size 1 1)
					(thickness 0.15)
				)
			)
		)
		(sheetname "2xUSB3.0+RJ45")
		(sheetfile "usb3+rj45.kicad_sch")
		(attr smd)
		(fp_rect
			(start -0.925 -0.47)
			(end 0.925 0.47)
			(stroke
				(width 0.05)
				(type default)
			)
			(fill no)
			(layer "F.CrtYd")
		)
		(fp_rect
			(start -0.5 -0.25)
			(end 0.5 0.25)
			(stroke
				(width 0.15)
				(type solid)
			)
			(fill no)
			(layer "F.Fab")
		)
		(pad "1" smd roundrect
			(at -0.48 0 180)
			(size 0.59 0.64)
			(layers "F.Cu" "F.Mask" "F.Paste")
			(roundrect_rratio 0.25)
			(net 50 "Net-(C12-Pad2)")
			(pintype "passive")
			(teardrops
				(best_length_ratio 0.2)
				(max_length 1)
				(best_width_ratio 0.9)
				(max_width 2)
				(curved_edges yes)
				(filter_ratio 0.9)
				(enabled yes)
				(allow_two_segments yes)
				(prefer_zone_connections yes)
			)
		)
		(pad "2" smd roundrect
			(at 0.48 0 180)
			(size 0.59 0.64)
			(layers "F.Cu" "F.Mask" "F.Paste")
			(roundrect_rratio 0.25)
			(net 549 "Net-(R14-Pad2)")
			(pintype "passive")
			(teardrops
				(best_length_ratio 0.2)
				(max_length 1)
				(best_width_ratio 0.9)
				(max_width 2)
				(curved_edges yes)
				(filter_ratio 0.9)
				(enabled yes)
				(allow_two_segments yes)
				(prefer_zone_connections yes)
			)
		)
	)
	(footprint "antmicro-footprints:R_0402_1005Metric"
		(layer "F.Cu")
		(at 252.665 84.449999 180)
		(descr "Resistor SMD 0402")
		(tags "resistor SMD 0402")
		(property "Reference" "R157"
			(at 0.865 -0.440001 0)
			(layer "F.SilkS")
			(effects
				(font
					(size 0.7 0.7)
					(thickness 0.15)
				)
				(justify right bottom)
			)
		)
		(property "Value" "R_10k_0402"
			(at -1.011843 1.772047 0)
			(layer "F.Fab")
			(effects
				(font
					(size 0.7 0.7)
					(thickness 0.15)
				)
				(justify right bottom)
			)
		)
		(property "Datasheet" "https://www.bourns.com/docs/product-datasheets/cr.pdf"
			(at 0 0 180)
			(layer "F.Fab")
			(hide yes)
			(effects
				(font
					(size 1.27 1.27)
					(thickness 0.15)
				)
			)
		)
		(property "Author" "Antmicro"
			(at 505.33 168.899998 0)
			(layer "F.Fab")
			(hide yes)
			(effects
				(font
					(size 1 1)
					(thickness 0.15)
				)
			)
		)
		(property "License" "Apache-2.0"
			(at 505.33 168.899998 0)
			(layer "F.Fab")
			(hide yes)
			(effects
				(font
					(size 1 1)
					(thickness 0.15)
				)
			)
		)
		(property "MPN" "CR0402-FX-1002GLF"
			(at 505.33 168.899998 0)
			(layer "F.Fab")
			(hide yes)
			(effects
				(font
					(size 1 1)
					(thickness 0.15)
				)
			)
		)
		(property "Manufacturer" "Bourns"
			(at 505.33 168.899998 0)
			(layer "F.Fab")
			(hide yes)
			(effects
				(font
					(size 1 1)
					(thickness 0.15)
				)
			)
		)
		(property "Public" "False"
			(at 505.33 168.899998 0)
			(layer "F.Fab")
			(hide yes)
			(effects
				(font
					(size 1 1)
					(thickness 0.15)
				)
			)
		)
		(property "Tolerance" "1%"
			(at 505.33 168.899998 0)
			(layer "F.Fab")
			(hide yes)
			(effects
				(font
					(size 1 1)
					(thickness 0.15)
				)
			)
		)
		(property "Val" "10k"
			(at 505.33 168.899998 0)
			(layer "F.Fab")
			(hide yes)
			(effects
				(font
					(size 1 1)
					(thickness 0.15)
				)
			)
		)
		(sheetname "Misc")
		(sheetfile "misc.kicad_sch")
		(attr smd)
		(fp_rect
			(start -0.925 -0.47)
			(end 0.925 0.47)
			(stroke
				(width 0.05)
				(type default)
			)
			(fill no)
			(layer "F.CrtYd")
		)
		(fp_rect
			(start -0.5 -0.25)
			(end 0.5 0.25)
			(stroke
				(width 0.15)
				(type solid)
			)
			(fill no)
			(layer "F.Fab")
		)
		(pad "1" smd roundrect
			(at -0.48 0 180)
			(size 0.59 0.64)
			(layers "F.Cu" "F.Mask" "F.Paste")
			(roundrect_rratio 0.25)
			(net 595 "/Misc/PWM_{SRCSEL}")
			(pintype "passive")
			(teardrops
				(best_length_ratio 0.2)
				(max_length 1)
				(best_width_ratio 0.9)
				(max_width 2)
				(curved_edges yes)
				(filter_ratio 0.9)
				(enabled yes)
				(allow_two_segments yes)
				(prefer_zone_connections yes)
			)
		)
		(pad "2" smd roundrect
			(at 0.48 0 180)
			(size 0.59 0.64)
			(layers "F.Cu" "F.Mask" "F.Paste")
			(roundrect_rratio 0.25)
			(net 2 "+3V3")
			(pintype "passive")
			(teardrops
				(best_length_ratio 0.2)
				(max_length 1)
				(best_width_ratio 0.9)
				(max_width 2)
				(curved_edges yes)
				(filter_ratio 0.9)
				(enabled yes)
				(allow_two_segments yes)
				(prefer_zone_connections yes)
			)
		)
	)
	(footprint "antmicro-footprints:PinHeader_1x3_P2.54mm_Drill1.1mm"
		(layer "F.Cu")
		(at 175.631 70.61)
		(property "Reference" "J7"
			(at -1.641 1.44 90)
			(layer "F.SilkS")
			(effects
				(font
					(size 0.7 0.7)
					(thickness 0.15)
				)
				(justify left bottom)
			)
		)
		(property "Value" "PinHeader_1x3_P2.54mm_Drill1.1mm"
			(at -1.6 2.7 0)
			(layer "F.Fab")
			(effects
				(font
					(size 0.7 0.7)
					(thickness 0.15)
				)
				(justify left bottom)
			)
		)
		(property "Datasheet" "https://katalog.we-online.de/em/datasheet/6130xx11121.pdf"
			(at 0 0 0)
			(layer "F.Fab")
			(hide yes)
			(effects
				(font
					(size 1.27 1.27)
					(thickness 0.15)
				)
			)
		)
		(property "MPN" "61300311121"
			(at 0 0 0)
			(unlocked yes)
			(layer "F.Fab")
			(hide yes)
			(effects
				(font
					(size 1 1)
					(thickness 0.15)
				)
			)
		)
		(property "Manufacturer" "Würth Elektronik"
			(at 0 0 0)
			(unlocked yes)
			(layer "F.Fab")
			(hide yes)
			(effects
				(font
					(size 1 1)
					(thickness 0.15)
				)
			)
		)
		(property "Author" "Antmicro"
			(at 0 0 0)
			(unlocked yes)
			(layer "F.Fab")
			(hide yes)
			(effects
				(font
					(size 1 1)
					(thickness 0.15)
				)
			)
		)
		(property "License" "Apache-2.0"
			(at 0 0 0)
			(unlocked yes)
			(layer "F.Fab")
			(hide yes)
			(effects
				(font
					(size 1 1)
					(thickness 0.15)
				)
			)
		)
		(sheetname "Com Express 7 MGMT")
		(sheetfile "com_express_7_mgmt.kicad_sch")
		(attr through_hole)
		(fp_line
			(start -1.401 -1.401)
			(end -1.401 -0.902)
			(stroke
				(width 0.15)
				(type solid)
			)
			(layer "F.SilkS")
		)
		(fp_line
			(start -1.401 -1.401)
			(end -0.902 -1.401)
			(stroke
				(width 0.15)
				(type solid)
			)
			(layer "F.SilkS")
		)
		(fp_line
			(start -1.401 1.398)
			(end -1.401 0.9)
			(stroke
				(width 0.15)
				(type solid)
			)
			(layer "F.SilkS")
		)
		(fp_line
			(start -1.401 1.398)
			(end -0.902 1.398)
			(stroke
				(width 0.15)
				(type solid)
			)
			(layer "F.SilkS")
		)
		(fp_line
			(start 6.499 -1.401)
			(end 5.999 -1.401)
			(stroke
				(width 0.15)
				(type solid)
			)
			(layer "F.SilkS")
		)
		(fp_line
			(start 6.499 -1.401)
			(end 6.499 -0.902)
			(stroke
				(width 0.15)
				(type solid)
			)
			(layer "F.SilkS")
		)
		(fp_line
			(start 6.499 1.398)
			(end 5.999 1.398)
			(stroke
				(width 0.15)
				(type solid)
			)
			(layer "F.SilkS")
		)
		(fp_line
			(start 6.499 1.398)
			(end 6.499 0.9)
			(stroke
				(width 0.15)
				(type solid)
			)
			(layer "F.SilkS")
		)
		(fp_line
			(start -1.52 -1.52)
			(end -1.52 1.5)
			(stroke
				(width 0.05)
				(type solid)
			)
			(layer "F.CrtYd")
		)
		(fp_line
			(start -1.52 -1.52)
			(end 6.58 -1.52)
			(stroke
				(width 0.05)
				(type solid)
			)
			(layer "F.CrtYd")
		)
		(fp_line
			(start -1.52 1.5)
			(end 6.58 1.5)
			(stroke
				(width 0.05)
				(type solid)
			)
			(layer "F.CrtYd")
		)
		(fp_line
			(start 6.58 -1.52)
			(end 6.58 1.5)
			(stroke
				(width 0.05)
				(type solid)
			)
			(layer "F.CrtYd")
		)
		(fp_line
			(start -1.27 -1.27)
			(end -1.27 1.269)
			(stroke
				(width 0.15)
				(type solid)
			)
			(layer "F.Fab")
		)
		(fp_line
			(start -1.27 -1.27)
			(end 6.349 -1.27)
			(stroke
				(width 0.15)
				(type solid)
			)
			(layer "F.Fab")
		)
		(fp_line
			(start -1.27 1.269)
			(end 6.349 1.269)
			(stroke
				(width 0.15)
				(type solid)
			)
			(layer "F.Fab")
		)
		(fp_line
			(start 6.349 -1.27)
			(end 6.349 1.269)
			(stroke
				(width 0.15)
				(type solid)
			)
			(layer "F.Fab")
		)
		(pad "1" thru_hole rect
			(at 0 0)
			(size 1.7 1.7)
			(drill 1.1)
			(layers "*.Cu" "*.Mask")
			(remove_unused_layers no)
			(net 1000 "unconnected-(J7-Pad1)")
			(pintype "passive+no_connect")
			(teardrops
				(best_length_ratio 0.2)
				(max_length 1)
				(best_width_ratio 0.9)
				(max_width 2)
				(curved_edges yes)
				(filter_ratio 0.9)
				(enabled yes)
				(allow_two_segments yes)
				(prefer_zone_connections yes)
			)
		)
		(pad "2" thru_hole circle
			(at 2.539 0)
			(size 1.7 1.7)
			(drill 1.1)
			(layers "*.Cu" "*.Mask")
			(remove_unused_layers no)
			(net 999 "Net-(C101-Pad1)")
			(pintype "passive")
			(teardrops
				(best_length_ratio 0.4)
				(max_length 1)
				(best_width_ratio 0.9)
				(max_width 2)
				(curved_edges yes)
				(filter_ratio 0.9)
				(enabled yes)
				(allow_two_segments yes)
				(prefer_zone_connections yes)
			)
		)
		(pad "3" thru_hole circle
			(at 5.078 0)
			(size 1.7 1.7)
			(drill 1.1)
			(layers "*.Cu" "*.Mask")
			(remove_unused_layers no)
			(net 83 "Net-(Q11-D)")
			(pintype "passive")
			(teardrops
				(best_length_ratio 0.4)
				(max_length 1)
				(best_width_ratio 0.9)
				(max_width 2)
				(curved_edges yes)
				(filter_ratio 0.9)
				(enabled yes)
				(allow_two_segments yes)
				(prefer_zone_connections yes)
			)
		)
	)
	(footprint "antmicro-footprints:R_0402_1005Metric"
		(layer "F.Cu")
		(at 252.665 86.449999)
		(descr "Resistor SMD 0402")
		(tags "resistor SMD 0402")
		(property "Reference" "R150"
			(at -0.865 0.440001 0)
			(layer "F.SilkS")
			(effects
				(font
					(size 0.7 0.7)
					(thickness 0.15)
				)
				(justify right bottom)
			)
		)
		(property "Value" "R_0R_0402"
			(at -1.011843 1.772047 0)
			(layer "F.Fab")
			(effects
				(font
					(size 0.7 0.7)
					(thickness 0.15)
				)
				(justify left bottom)
			)
		)
		(property "Datasheet" "https://industrial.panasonic.com/cdbs/www-data/pdf/RDA0000/AOA0000C301.pdf"
			(at 0 0 0)
			(layer "F.Fab")
			(hide yes)
			(effects
				(font
					(size 1.27 1.27)
					(thickness 0.15)
				)
			)
		)
		(property "Author" "Antmicro"
			(at 0 0 0)
			(layer "F.Fab")
			(hide yes)
			(effects
				(font
					(size 1 1)
					(thickness 0.15)
				)
			)
		)
		(property "Current" "1A"
			(at 0 0 0)
			(layer "F.Fab")
			(hide yes)
			(effects
				(font
					(size 1 1)
					(thickness 0.15)
				)
			)
		)
		(property "License" "Apache-2.0"
			(at 0 0 0)
			(layer "F.Fab")
			(hide yes)
			(effects
				(font
					(size 1 1)
					(thickness 0.15)
				)
			)
		)
		(property "MPN" "ERJ2GE0R00X"
			(at 0 0 0)
			(layer "F.Fab")
			(hide yes)
			(effects
				(font
					(size 1 1)
					(thickness 0.15)
				)
			)
		)
		(property "Manufacturer" "Panasonic"
			(at 0 0 0)
			(layer "F.Fab")
			(hide yes)
			(effects
				(font
					(size 1 1)
					(thickness 0.15)
				)
			)
		)
		(property "Public" "False"
			(at 0 0 0)
			(layer "F.Fab")
			(hide yes)
			(effects
				(font
					(size 1 1)
					(thickness 0.15)
				)
			)
		)
		(property "Tolerance" ""
			(at 0 0 0)
			(layer "F.Fab")
			(hide yes)
			(effects
				(font
					(size 1 1)
					(thickness 0.15)
				)
			)
		)
		(property "Val" "0R"
			(at 0 0 0)
			(layer "F.Fab")
			(hide yes)
			(effects
				(font
					(size 1 1)
					(thickness 0.15)
				)
			)
		)
		(sheetname "Misc")
		(sheetfile "misc.kicad_sch")
		(attr smd)
		(fp_rect
			(start -0.925 -0.47)
			(end 0.925 0.47)
			(stroke
				(width 0.05)
				(type default)
			)
			(fill no)
			(layer "F.CrtYd")
		)
		(fp_rect
			(start -0.5 -0.25)
			(end 0.5 0.25)
			(stroke
				(width 0.15)
				(type solid)
			)
			(fill no)
			(layer "F.Fab")
		)
		(pad "1" smd roundrect
			(at -0.48 0)
			(size 0.59 0.64)
			(layers "F.Cu" "F.Mask" "F.Paste")
			(roundrect_rratio 0.25)
			(net 52 "+5V")
			(pintype "passive")
			(teardrops
				(best_length_ratio 0.2)
				(max_length 1)
				(best_width_ratio 0.9)
				(max_width 2)
				(curved_edges yes)
				(filter_ratio 0.9)
				(enabled yes)
				(allow_two_segments yes)
				(prefer_zone_connections yes)
			)
		)
		(pad "2" smd roundrect
			(at 0.48 0)
			(size 0.59 0.64)
			(layers "F.Cu" "F.Mask" "F.Paste")
			(roundrect_rratio 0.25)
			(net 592 "Net-(U24-+5V_{IN})")
			(pintype "passive")
			(teardrops
				(best_length_ratio 0.2)
				(max_length 1)
				(best_width_ratio 0.9)
				(max_width 2)
				(curved_edges yes)
				(filter_ratio 0.9)
				(enabled yes)
				(allow_two_segments yes)
				(prefer_zone_connections yes)
			)
		)
	)
	(footprint "antmicro-footprints:R_0402_1005Metric"
		(layer "F.Cu")
		(at 161.55 156.81 -90)
		(descr "Resistor SMD 0402")
		(tags "resistor SMD 0402")
		(property "Reference" "R34"
			(at -3.013 -0.449 90)
			(layer "F.SilkS")
			(effects
				(font
					(size 0.7 0.7)
					(thickness 0.15)
				)
				(justify right bottom)
			)
		)
		(property "Value" "R_0R_0402"
			(at -1.011843 1.772047 90)
			(layer "F.Fab")
			(effects
				(font
					(size 0.7 0.7)
					(thickness 0.15)
				)
				(justify right bottom)
			)
		)
		(property "Datasheet" "https://industrial.panasonic.com/cdbs/www-data/pdf/RDA0000/AOA0000C301.pdf"
			(at 0 0 270)
			(layer "F.Fab")
			(hide yes)
			(effects
				(font
					(size 1.27 1.27)
					(thickness 0.15)
				)
			)
		)
		(property "Author" "Antmicro"
			(at 4.74 318.36 0)
			(layer "F.Fab")
			(hide yes)
			(effects
				(font
					(size 1 1)
					(thickness 0.15)
				)
			)
		)
		(property "Current" "1A"
			(at 4.74 318.36 0)
			(layer "F.Fab")
			(hide yes)
			(effects
				(font
					(size 1 1)
					(thickness 0.15)
				)
			)
		)
		(property "License" "Apache-2.0"
			(at 4.74 318.36 0)
			(layer "F.Fab")
			(hide yes)
			(effects
				(font
					(size 1 1)
					(thickness 0.15)
				)
			)
		)
		(property "MPN" "ERJ2GE0R00X"
			(at 4.74 318.36 0)
			(layer "F.Fab")
			(hide yes)
			(effects
				(font
					(size 1 1)
					(thickness 0.15)
				)
			)
		)
		(property "Manufacturer" "Panasonic"
			(at 4.74 318.36 0)
			(layer "F.Fab")
			(hide yes)
			(effects
				(font
					(size 1 1)
					(thickness 0.15)
				)
			)
		)
		(property "Public" "False"
			(at 4.74 318.36 0)
			(layer "F.Fab")
			(hide yes)
			(effects
				(font
					(size 1 1)
					(thickness 0.15)
				)
			)
		)
		(property "Tolerance" ""
			(at 4.74 318.36 0)
			(layer "F.Fab")
			(hide yes)
			(effects
				(font
					(size 1 1)
					(thickness 0.15)
				)
			)
		)
		(property "Val" "0R"
			(at 4.74 318.36 0)
			(layer "F.Fab")
			(hide yes)
			(effects
				(font
					(size 1 1)
					(thickness 0.15)
				)
			)
		)
		(sheetname "2xSFP+")
		(sheetfile "2xSFP+.kicad_sch")
		(attr smd)
		(fp_rect
			(start -0.925 -0.47)
			(end 0.925 0.47)
			(stroke
				(width 0.05)
				(type default)
			)
			(fill no)
			(layer "F.CrtYd")
		)
		(fp_rect
			(start -0.5 -0.25)
			(end 0.5 0.25)
			(stroke
				(width 0.15)
				(type solid)
			)
			(fill no)
			(layer "F.Fab")
		)
		(pad "1" smd roundrect
			(at -0.48 0 270)
			(size 0.59 0.64)
			(layers "F.Cu" "F.Mask" "F.Paste")
			(roundrect_rratio 0.25)
			(net 423 "/2xSFP+/I2C_{LED}.SCL")
			(pintype "passive")
			(teardrops
				(best_length_ratio 0.2)
				(max_length 1)
				(best_width_ratio 0.9)
				(max_width 2)
				(curved_edges yes)
				(filter_ratio 0.9)
				(enabled yes)
				(allow_two_segments yes)
				(prefer_zone_connections yes)
			)
		)
		(pad "2" smd roundrect
			(at 0.48 0 270)
			(size 0.59 0.64)
			(layers "F.Cu" "F.Mask" "F.Paste")
			(roundrect_rratio 0.25)
			(net 559 "Net-(U5-SCL)")
			(pintype "passive")
			(teardrops
				(best_length_ratio 0.2)
				(max_length 1)
				(best_width_ratio 0.9)
				(max_width 2)
				(curved_edges yes)
				(filter_ratio 0.9)
				(enabled yes)
				(allow_two_segments yes)
				(prefer_zone_connections yes)
			)
		)
	)
	(footprint "antmicro-footprints:SOD-523"
		(layer "F.Cu")
		(at 112.15 135.71)
		(property "Reference" "D29"
			(at 1 0.45 0)
			(layer "F.SilkS")
			(effects
				(font
					(size 0.7 0.7)
					(thickness 0.15)
				)
				(justify left bottom)
			)
		)
		(property "Value" "PESD5Z5_0F"
			(at 0 1.499 0)
			(layer "F.Fab")
			(effects
				(font
					(size 0.7 0.7)
					(thickness 0.15)
				)
				(justify left bottom)
			)
		)
		(property "Datasheet" "https://assets.nexperia.com/documents/data-sheet/PESD5Z5_0.pdf"
			(at 0 0 0)
			(layer "F.Fab")
			(hide yes)
			(effects
				(font
					(size 1.27 1.27)
					(thickness 0.15)
				)
			)
		)
		(property "Author" "Antmicro"
			(at 0 0 0)
			(layer "F.Fab")
			(hide yes)
			(effects
				(font
					(size 1 1)
					(thickness 0.15)
				)
			)
		)
		(property "License" "Apache-2.0"
			(at 0 0 0)
			(layer "F.Fab")
			(hide yes)
			(effects
				(font
					(size 1 1)
					(thickness 0.15)
				)
			)
		)
		(property "MPN" "PESD5Z5.0F"
			(at 0 0 0)
			(layer "F.Fab")
			(hide yes)
			(effects
				(font
					(size 1 1)
					(thickness 0.15)
				)
			)
		)
		(property "Manufacturer" "Nexperia"
			(at 0 0 0)
			(layer "F.Fab")
			(hide yes)
			(effects
				(font
					(size 1 1)
					(thickness 0.15)
				)
			)
		)
		(property "Public" "False"
			(at 0 0 0)
			(layer "F.Fab")
			(hide yes)
			(effects
				(font
					(size 1 1)
					(thickness 0.15)
				)
			)
		)
		(sheetname "SD card")
		(sheetfile "sd_card.kicad_sch")
		(attr smd)
		(fp_line
			(start -0.35 -0.5)
			(end -0.35 0.5)
			(stroke
				(width 0.15)
				(type solid)
			)
			(layer "F.SilkS")
		)
		(fp_rect
			(start -1 -0.6)
			(end 1 0.6)
			(stroke
				(width 0.05)
				(type solid)
			)
			(fill no)
			(layer "F.CrtYd")
		)
		(fp_line
			(start -0.652 -0.425)
			(end 0.65 -0.425)
			(stroke
				(width 0.15)
				(type solid)
			)
			(layer "F.Fab")
		)
		(fp_line
			(start -0.652 0.423)
			(end -0.652 -0.425)
			(stroke
				(width 0.15)
				(type solid)
			)
			(layer "F.Fab")
		)
		(fp_line
			(start -0.652 0.423)
			(end 0.65 0.423)
			(stroke
				(width 0.15)
				(type solid)
			)
			(layer "F.Fab")
		)
		(fp_line
			(start -0.35 -0.4)
			(end -0.35 0.4)
			(stroke
				(width 0.15)
				(type solid)
			)
			(layer "F.Fab")
		)
		(fp_line
			(start 0.65 -0.425)
			(end 0.65 0.423)
			(stroke
				(width 0.15)
				(type solid)
			)
			(layer "F.Fab")
		)
		(pad "1" smd roundrect
			(at -0.701 0)
			(size 0.5 0.6)
			(layers "F.Cu" "F.Mask" "F.Paste")
			(roundrect_rratio 0.25)
			(net 2 "+3V3")
			(pinfunction "C")
			(pintype "passive")
			(teardrops
				(best_length_ratio 0.2)
				(max_length 1)
				(best_width_ratio 0.9)
				(max_width 2)
				(curved_edges yes)
				(filter_ratio 0.9)
				(enabled yes)
				(allow_two_segments yes)
				(prefer_zone_connections yes)
			)
		)
		(pad "2" smd roundrect
			(at 0.699 0)
			(size 0.5 0.6)
			(layers "F.Cu" "F.Mask" "F.Paste")
			(roundrect_rratio 0.25)
			(net 1 "GND")
			(pinfunction "A")
			(pintype "passive")
			(teardrops
				(best_length_ratio 0.2)
				(max_length 1)
				(best_width_ratio 0.9)
				(max_width 2)
				(curved_edges yes)
				(filter_ratio 0.9)
				(enabled yes)
				(allow_two_segments yes)
				(prefer_zone_connections yes)
			)
		)
	)
	(footprint "antmicro-footprints:C_0402_1005Metric"
		(layer "F.Cu")
		(at 109.756999 74.876 -90)
		(descr "Capacitor SMD 0402")
		(tags "capacitor SMD 0402")
		(property "Reference" "C30"
			(at -1.316 0.456999 90)
			(layer "F.SilkS")
			(effects
				(font
					(size 0.7 0.7)
					(thickness 0.15)
				)
				(justify right bottom)
			)
		)
		(property "Value" "C_47p_0402"
			(at -1.022927 2.155213 90)
			(layer "F.Fab")
			(effects
				(font
					(size 0.7 0.7)
					(thickness 0.15)
				)
				(justify right bottom)
			)
		)
		(property "Datasheet" "https://www.kemet.com/en/us/capacitors/product/C0402C470J5GACTU.html"
			(at 0 0 270)
			(layer "F.Fab")
			(hide yes)
			(effects
				(font
					(size 1.27 1.27)
					(thickness 0.15)
				)
			)
		)
		(property "Author" "Antmicro"
			(at 34.880999 184.632999 0)
			(layer "F.Fab")
			(hide yes)
			(effects
				(font
					(size 1 1)
					(thickness 0.15)
				)
			)
		)
		(property "Dielectric" "C0G"
			(at 34.880999 184.632999 0)
			(layer "F.Fab")
			(hide yes)
			(effects
				(font
					(size 1 1)
					(thickness 0.15)
				)
			)
		)
		(property "License" "Apache-2.0"
			(at 34.880999 184.632999 0)
			(layer "F.Fab")
			(hide yes)
			(effects
				(font
					(size 1 1)
					(thickness 0.15)
				)
			)
		)
		(property "MPN" "C0402C470J5GACTU"
			(at 34.880999 184.632999 0)
			(layer "F.Fab")
			(hide yes)
			(effects
				(font
					(size 1 1)
					(thickness 0.15)
				)
			)
		)
		(property "Manufacturer" "KEMET"
			(at 34.880999 184.632999 0)
			(layer "F.Fab")
			(hide yes)
			(effects
				(font
					(size 1 1)
					(thickness 0.15)
				)
			)
		)
		(property "Public" "False"
			(at 34.880999 184.632999 0)
			(layer "F.Fab")
			(hide yes)
			(effects
				(font
					(size 1 1)
					(thickness 0.15)
				)
			)
		)
		(property "Val" "47p"
			(at 34.880999 184.632999 0)
			(layer "F.Fab")
			(hide yes)
			(effects
				(font
					(size 1 1)
					(thickness 0.15)
				)
			)
		)
		(property "Voltage" ""
			(at 34.880999 184.632999 0)
			(layer "F.Fab")
			(hide yes)
			(effects
				(font
					(size 1 1)
					(thickness 0.15)
				)
			)
		)
		(sheetname "USB-C console")
		(sheetfile "usb-c_console.kicad_sch")
		(attr smd)
		(fp_rect
			(start -0.925 -0.47)
			(end 0.925 0.47)
			(stroke
				(width 0.05)
				(type default)
			)
			(fill no)
			(layer "F.CrtYd")
		)
		(fp_line
			(start -0.494 0.248)
			(end -0.494 -0.25)
			(stroke
				(width 0.15)
				(type solid)
			)
			(layer "F.Fab")
		)
		(fp_line
			(start 0.504 0.248)
			(end -0.494 0.248)
			(stroke
				(width 0.15)
				(type solid)
			)
			(layer "F.Fab")
		)
		(fp_line
			(start -0.494 -0.25)
			(end 0.504 -0.25)
			(stroke
				(width 0.15)
				(type solid)
			)
			(layer "F.Fab")
		)
		(fp_line
			(start 0.504 -0.25)
			(end 0.504 0.248)
			(stroke
				(width 0.15)
				(type solid)
			)
			(layer "F.Fab")
		)
		(pad "1" smd roundrect
			(at -0.48 0 270)
			(size 0.59 0.64)
			(layers "F.Cu" "F.Mask" "F.Paste")
			(roundrect_rratio 0.25)
			(net 1 "GND")
			(pintype "passive")
			(teardrops
				(best_length_ratio 0.2)
				(max_length 1)
				(best_width_ratio 0.9)
				(max_width 2)
				(curved_edges yes)
				(filter_ratio 0.9)
				(enabled yes)
				(allow_two_segments yes)
				(prefer_zone_connections yes)
			)
		)
		(pad "2" smd roundrect
			(at 0.48 0 270)
			(size 0.59 0.64)
			(layers "F.Cu" "F.Mask" "F.Paste")
			(roundrect_rratio 0.25)
			(net 55 "/USB-C console/USB_D+")
			(pintype "passive")
			(teardrops
				(best_length_ratio 0.2)
				(max_length 1)
				(best_width_ratio 0.9)
				(max_width 2)
				(curved_edges yes)
				(filter_ratio 0.9)
				(enabled yes)
				(allow_two_segments yes)
				(prefer_zone_connections yes)
			)
		)
	)
	(footprint "antmicro-footprints:QFN-20-1EP_3x3mm_P0.45mm_TPS56xxxx"
		(layer "F.Cu")
		(at 311.714999 120.558999 180)
		(property "Reference" "U18"
			(at -1.835001 1.798999 0)
			(layer "F.SilkS")
			(effects
				(font
					(size 0.7 0.7)
					(thickness 0.15)
				)
				(justify right bottom)
			)
		)
		(property "Value" "TPS56C230"
			(at 0 2.898 0)
			(layer "F.Fab")
			(effects
				(font
					(size 0.7 0.7)
					(thickness 0.15)
				)
				(justify right bottom)
			)
		)
		(property "Datasheet" "https://www.ti.com/lit/ds/symlink/tps56c230.pdf?ts=1672843259715&ref_url=https%253A%252F%252Fwww.ti.com%252Fproduct%252FTPS56C230"
			(at 0 0 180)
			(layer "F.Fab")
			(hide yes)
			(effects
				(font
					(size 1.27 1.27)
					(thickness 0.15)
				)
			)
		)
		(property "Author" "Antmicro"
			(at 623.429998 241.117998 0)
			(layer "F.Fab")
			(hide yes)
			(effects
				(font
					(size 1 1)
					(thickness 0.15)
				)
			)
		)
		(property "License" "Apache-2.0"
			(at 623.429998 241.117998 0)
			(layer "F.Fab")
			(hide yes)
			(effects
				(font
					(size 1 1)
					(thickness 0.15)
				)
			)
		)
		(property "MPN" "TPS56C230RJER"
			(at 623.429998 241.117998 0)
			(layer "F.Fab")
			(hide yes)
			(effects
				(font
					(size 1 1)
					(thickness 0.15)
				)
			)
		)
		(property "Manufacturer" "Texas Instruments"
			(at 623.429998 241.117998 0)
			(layer "F.Fab")
			(hide yes)
			(effects
				(font
					(size 1 1)
					(thickness 0.15)
				)
			)
		)
		(sheetname "Power")
		(sheetfile "power.kicad_sch")
		(attr smd)
		(fp_line
			(start 1.5 -1.5)
			(end 1.5 -1.2)
			(stroke
				(width 0.15)
				(type solid)
			)
			(layer "F.SilkS")
		)
		(fp_line
			(start 1.499 1.5)
			(end 1.499 1.202)
			(stroke
				(width 0.15)
				(type solid)
			)
			(layer "F.SilkS")
		)
		(fp_line
			(start 1.202 -1.5)
			(end 1.5 -1.5)
			(stroke
				(width 0.15)
				(type solid)
			)
			(layer "F.SilkS")
		)
		(fp_line
			(start 1.201 1.5)
			(end 1.499 1.5)
			(stroke
				(width 0.15)
				(type solid)
			)
			(layer "F.SilkS")
		)
		(fp_line
			(start -1.2 1.498)
			(end -1.5 1.498)
			(stroke
				(width 0.15)
				(type solid)
			)
			(layer "F.SilkS")
		)
		(fp_line
			(start -1.5 1.498)
			(end -1.5 1.2)
			(stroke
				(width 0.15)
				(type solid)
			)
			(layer "F.SilkS")
		)
		(fp_line
			(start -1.5 -1.201)
			(end -1.5 -1.499)
			(stroke
				(width 0.15)
				(type solid)
			)
			(layer "F.SilkS")
		)
		(fp_line
			(start -1.5 -1.499)
			(end -1.2 -1.499)
			(stroke
				(width 0.15)
				(type solid)
			)
			(layer "F.SilkS")
		)
		(fp_circle
			(center -1.8 -1.15)
			(end -1.75 -1.15)
			(stroke
				(width 0.15)
				(type solid)
			)
			(fill yes)
			(layer "F.SilkS")
		)
		(fp_rect
			(start -1.8 -1.8)
			(end 1.8 1.8)
			(stroke
				(width 0.05)
				(type solid)
			)
			(fill no)
			(layer "F.CrtYd")
		)
		(fp_line
			(start 1.499 1.499)
			(end 1.499 -1.5)
			(stroke
				(width 0.15)
				(type solid)
			)
			(layer "F.Fab")
		)
		(fp_line
			(start 1.499 -1.5)
			(end -0.5 -1.5)
			(stroke
				(width 0.15)
				(type solid)
			)
			(layer "F.Fab")
		)
		(fp_line
			(start -0.5 -1.5)
			(end -1.5 -0.5)
			(stroke
				(width 0.15)
				(type solid)
			)
			(layer "F.Fab")
		)
		(fp_line
			(start -1.5 1.499)
			(end 1.499 1.499)
			(stroke
				(width 0.15)
				(type solid)
			)
			(layer "F.Fab")
		)
		(fp_line
			(start -1.5 -0.5)
			(end -1.5 1.499)
			(stroke
				(width 0.15)
				(type solid)
			)
			(layer "F.Fab")
		)
		(pad "1" smd oval
			(at -1.4 -0.905 270)
			(size 0.2 0.6)
			(layers "F.Cu" "F.Mask" "F.Paste")
			(net 66 "Net-(U18-BST)")
			(pinfunction "BST")
			(pintype "passive")
			(teardrops
				(best_length_ratio 0.2)
				(max_length 1)
				(best_width_ratio 0.9)
				(max_width 2)
				(curved_edges yes)
				(filter_ratio 0.9)
				(enabled yes)
				(allow_two_segments yes)
				(prefer_zone_connections yes)
			)
		)
		(pad "2" smd oval
			(at -1.4 -0.455 270)
			(size 0.2 0.6)
			(layers "F.Cu" "F.Mask" "F.Paste")
			(net 62 "+12V_AON")
			(pinfunction "V_{IN}")
			(pintype "power_in")
			(teardrops
				(best_length_ratio 0.2)
				(max_length 1)
				(best_width_ratio 0.9)
				(max_width 2)
				(curved_edges yes)
				(filter_ratio 0.9)
				(enabled yes)
				(allow_two_segments yes)
				(prefer_zone_connections yes)
			)
		)
		(pad "3" smd oval
			(at -1.4 0 270)
			(size 0.2 0.6)
			(layers "F.Cu" "F.Mask" "F.Paste")
			(net 62 "+12V_AON")
			(pinfunction "V_{IN}")
			(pintype "passive")
			(teardrops
				(best_length_ratio 0.2)
				(max_length 1)
				(best_width_ratio 0.9)
				(max_width 2)
				(curved_edges yes)
				(filter_ratio 0.9)
				(enabled yes)
				(allow_two_segments yes)
				(prefer_zone_connections yes)
			)
		)
		(pad "4" smd oval
			(at -1.4 0.45 270)
			(size 0.2 0.6)
			(layers "F.Cu" "F.Mask" "F.Paste")
			(net 62 "+12V_AON")
			(pinfunction "V_{IN}")
			(pintype "passive")
			(teardrops
				(best_length_ratio 0.2)
				(max_length 1)
				(best_width_ratio 0.9)
				(max_width 2)
				(curved_edges yes)
				(filter_ratio 0.9)
				(enabled yes)
				(allow_two_segments yes)
				(prefer_zone_connections yes)
			)
		)
		(pad "5" smd oval
			(at -1.4 0.9 270)
			(size 0.2 0.6)
			(layers "F.Cu" "F.Mask" "F.Paste")
			(net 62 "+12V_AON")
			(pinfunction "V_{IN}")
			(pintype "passive")
			(teardrops
				(best_length_ratio 0.2)
				(max_length 1)
				(best_width_ratio 0.9)
				(max_width 2)
				(curved_edges yes)
				(filter_ratio 0.9)
				(enabled yes)
				(allow_two_segments yes)
				(prefer_zone_connections yes)
			)
		)
		(pad "6" smd oval
			(at -0.905 1.4 180)
			(size 0.2 0.6)
			(layers "F.Cu" "F.Mask" "F.Paste")
			(net 67 "Net-(C47-Pad2)")
			(pinfunction "SW")
			(pintype "passive")
			(teardrops
				(best_length_ratio 0.2)
				(max_length 1)
				(best_width_ratio 0.9)
				(max_width 2)
				(curved_edges yes)
				(filter_ratio 0.9)
				(enabled yes)
				(allow_two_segments yes)
				(prefer_zone_connections yes)
			)
		)
		(pad "7" smd oval
			(at -0.455 1.4 180)
			(size 0.2 0.6)
			(layers "F.Cu" "F.Mask" "F.Paste")
			(net 1 "GND")
			(pinfunction "PGND")
			(pintype "passive")
			(teardrops
				(best_length_ratio 0.2)
				(max_length 1)
				(best_width_ratio 0.9)
				(max_width 2)
				(curved_edges yes)
				(filter_ratio 0.9)
				(enabled yes)
				(allow_two_segments yes)
				(prefer_zone_connections yes)
			)
		)
		(pad "8" smd oval
			(at 0 1.4 180)
			(size 0.2 0.6)
			(layers "F.Cu" "F.Mask" "F.Paste")
			(net 1 "GND")
			(pinfunction "PGND")
			(pintype "passive")
			(teardrops
				(best_length_ratio 0.2)
				(max_length 1)
				(best_width_ratio 0.9)
				(max_width 2)
				(curved_edges yes)
				(filter_ratio 0.9)
				(enabled yes)
				(allow_two_segments yes)
				(prefer_zone_connections yes)
			)
		)
		(pad "9" smd oval
			(at 0.45 1.4 180)
			(size 0.2 0.6)
			(layers "F.Cu" "F.Mask" "F.Paste")
			(net 578 "/Power/PG_{1V0}")
			(pinfunction "PG")
			(pintype "passive")
			(teardrops
				(best_length_ratio 0.2)
				(max_length 1)
				(best_width_ratio 0.9)
				(max_width 2)
				(curved_edges yes)
				(filter_ratio 0.9)
				(enabled yes)
				(allow_two_segments yes)
				(prefer_zone_connections yes)
			)
		)
		(pad "10" smd oval
			(at 0.9 1.4 180)
			(size 0.2 0.6)
			(layers "F.Cu" "F.Mask" "F.Paste")
			(net 773 "unconnected-(U18-NC-Pad10)")
			(pinfunction "NC")
			(pintype "no_connect")
			(teardrops
				(best_length_ratio 0.2)
				(max_length 1)
				(best_width_ratio 0.9)
				(max_width 2)
				(curved_edges yes)
				(filter_ratio 0.9)
				(enabled yes)
				(allow_two_segments yes)
				(prefer_zone_connections yes)
			)
		)
		(pad "11" smd oval
			(at 1.4 0.9 270)
			(size 0.2 0.6)
			(layers "F.Cu" "F.Mask" "F.Paste")
			(net 774 "unconnected-(U18-SS-Pad11)")
			(pinfunction "SS")
			(pintype "passive+no_connect")
			(teardrops
				(best_length_ratio 0.2)
				(max_length 1)
				(best_width_ratio 0.9)
				(max_width 2)
				(curved_edges yes)
				(filter_ratio 0.9)
				(enabled yes)
				(allow_two_segments yes)
				(prefer_zone_connections yes)
			)
		)
		(pad "12" smd oval
			(at 1.4 0.45 270)
			(size 0.2 0.6)
			(layers "F.Cu" "F.Mask" "F.Paste")
			(net 577 "Net-(U18-EN)")
			(pinfunction "EN")
			(pintype "passive")
			(teardrops
				(best_length_ratio 0.2)
				(max_length 1)
				(best_width_ratio 0.9)
				(max_width 2)
				(curved_edges yes)
				(filter_ratio 0.9)
				(enabled yes)
				(allow_two_segments yes)
				(prefer_zone_connections yes)
			)
		)
		(pad "13" smd oval
			(at 1.4 0 270)
			(size 0.2 0.6)
			(layers "F.Cu" "F.Mask" "F.Paste")
			(net 1 "GND")
			(pinfunction "AGND")
			(pintype "passive")
			(teardrops
				(best_length_ratio 0.2)
				(max_length 1)
				(best_width_ratio 0.9)
				(max_width 2)
				(curved_edges yes)
				(filter_ratio 0.9)
				(enabled yes)
				(allow_two_segments yes)
				(prefer_zone_connections yes)
			)
		)
		(pad "14" smd oval
			(at 1.4 -0.455 270)
			(size 0.2 0.6)
			(layers "F.Cu" "F.Mask" "F.Paste")
			(net 580 "Net-(U18-FB)")
			(pinfunction "FB")
			(pintype "passive")
			(teardrops
				(best_length_ratio 0.2)
				(max_length 1)
				(best_width_ratio 0.9)
				(max_width 2)
				(curved_edges yes)
				(filter_ratio 0.9)
				(enabled yes)
				(allow_two_segments yes)
				(prefer_zone_connections yes)
			)
		)
		(pad "15" smd oval
			(at 1.4 -0.905 270)
			(size 0.2 0.6)
			(layers "F.Cu" "F.Mask" "F.Paste")
			(net 575 "Net-(U18-MODE)")
			(pinfunction "MODE")
			(pintype "passive")
			(teardrops
				(best_length_ratio 0.2)
				(max_length 1)
				(best_width_ratio 0.9)
				(max_width 2)
				(curved_edges yes)
				(filter_ratio 0.9)
				(enabled yes)
				(allow_two_segments yes)
				(prefer_zone_connections yes)
			)
		)
		(pad "16" smd oval
			(at 0.9 -1.4 180)
			(size 0.2 0.6)
			(layers "F.Cu" "F.Mask" "F.Paste")
			(net 775 "unconnected-(U18-NC-Pad16)")
			(pinfunction "NC")
			(pintype "no_connect")
			(teardrops
				(best_length_ratio 0.2)
				(max_length 1)
				(best_width_ratio 0.9)
				(max_width 2)
				(curved_edges yes)
				(filter_ratio 0.9)
				(enabled yes)
				(allow_two_segments yes)
				(prefer_zone_connections yes)
			)
		)
		(pad "17" smd oval
			(at 0.45 -1.4 180)
			(size 0.2 0.6)
			(layers "F.Cu" "F.Mask" "F.Paste")
			(net 63 "Net-(U18-V_{CC})")
			(pinfunction "V_{CC}")
			(pintype "passive")
			(teardrops
				(best_length_ratio 0.2)
				(max_length 1)
				(best_width_ratio 0.9)
				(max_width 2)
				(curved_edges yes)
				(filter_ratio 0.9)
				(enabled yes)
				(allow_two_segments yes)
				(prefer_zone_connections yes)
			)
		)
		(pad "18" smd oval
			(at 0 -1.4 180)
			(size 0.2 0.6)
			(layers "F.Cu" "F.Mask" "F.Paste")
			(net 1 "GND")
			(pinfunction "PGND")
			(pintype "passive")
			(teardrops
				(best_length_ratio 0.2)
				(max_length 1)
				(best_width_ratio 0.9)
				(max_width 2)
				(curved_edges yes)
				(filter_ratio 0.9)
				(enabled yes)
				(allow_two_segments yes)
				(prefer_zone_connections yes)
			)
		)
		(pad "19" smd oval
			(at -0.455 -1.4 180)
			(size 0.2 0.6)
			(layers "F.Cu" "F.Mask" "F.Paste")
			(net 67 "Net-(C47-Pad2)")
			(pinfunction "SW")
			(pintype "passive")
			(teardrops
				(best_length_ratio 0.2)
				(max_length 1)
				(best_width_ratio 0.9)
				(max_width 2)
				(curved_edges yes)
				(filter_ratio 0.9)
				(enabled yes)
				(allow_two_segments yes)
				(prefer_zone_connections yes)
			)
		)
		(pad "20" smd oval
			(at -0.905 -1.4 180)
			(size 0.2 0.6)
			(layers "F.Cu" "F.Mask" "F.Paste")
			(net 67 "Net-(C47-Pad2)")
			(pinfunction "SW")
			(pintype "passive")
			(teardrops
				(best_length_ratio 0.2)
				(max_length 1)
				(best_width_ratio 0.9)
				(max_width 2)
				(curved_edges yes)
				(filter_ratio 0.9)
				(enabled yes)
				(allow_two_segments yes)
				(prefer_zone_connections yes)
			)
		)
		(pad "21" smd roundrect
			(at -0.06 0.018 180)
			(size 0.775 0.86)
			(layers "F.Cu" "F.Mask" "F.Paste")
			(roundrect_rratio 0.1)
			(net 1 "GND")
			(pinfunction "PGND")
			(pintype "passive")
			(solder_mask_margin -0.05)
			(solder_paste_margin -0.05)
			(teardrops
				(best_length_ratio 0.2)
				(max_length 1)
				(best_width_ratio 0.9)
				(max_width 2)
				(curved_edges yes)
				(filter_ratio 0.9)
				(enabled yes)
				(allow_two_segments yes)
				(prefer_zone_connections yes)
			)
		)
	)
	(footprint "antmicro-footprints:R_0201"
		(layer "F.Cu")
		(at 149.57 147.961 -90)
		(descr "Resistor SMD 0201")
		(tags "resistor SMD 0201")
		(property "Reference" "R277"
			(at 3.619 -0.28 90)
			(layer "F.SilkS")
			(effects
				(font
					(size 0.7 0.7)
					(thickness 0.15)
				)
				(justify right bottom)
			)
		)
		(property "Value" "R_0R_0201"
			(at 0 1.25 90)
			(layer "F.Fab")
			(effects
				(font
					(size 0.7 0.7)
					(thickness 0.15)
				)
				(justify right bottom)
			)
		)
		(property "Datasheet" "https://www.bourns.com/docs/product-datasheets/cr.pdf"
			(at 0 0 270)
			(layer "F.Fab")
			(hide yes)
			(effects
				(font
					(size 1.27 1.27)
					(thickness 0.15)
				)
			)
		)
		(property "Author" "Antmicro"
			(at 1.609 297.531 0)
			(layer "F.Fab")
			(hide yes)
			(effects
				(font
					(size 1 1)
					(thickness 0.15)
				)
			)
		)
		(property "License" "Apache-2.0"
			(at 1.609 297.531 0)
			(layer "F.Fab")
			(hide yes)
			(effects
				(font
					(size 1 1)
					(thickness 0.15)
				)
			)
		)
		(property "MPN" "CR0201-FX-0R00GLF"
			(at 1.609 297.531 0)
			(layer "F.Fab")
			(hide yes)
			(effects
				(font
					(size 1 1)
					(thickness 0.15)
				)
			)
		)
		(property "Manufacturer" "Bourns"
			(at 1.609 297.531 0)
			(layer "F.Fab")
			(hide yes)
			(effects
				(font
					(size 1 1)
					(thickness 0.15)
				)
			)
		)
		(property "Tolerance" "1%"
			(at 1.609 297.531 0)
			(layer "F.Fab")
			(hide yes)
			(effects
				(font
					(size 1 1)
					(thickness 0.15)
				)
			)
		)
		(property "Val" "0R"
			(at 1.609 297.531 0)
			(layer "F.Fab")
			(hide yes)
			(effects
				(font
					(size 1 1)
					(thickness 0.15)
				)
			)
		)
		(sheetname "KR to SFI #1")
		(sheetfile "kr_sfi.kicad_sch")
		(attr smd dnp)
		(fp_rect
			(start -0.7 -0.35)
			(end 0.7 0.35)
			(stroke
				(width 0.05)
				(type default)
			)
			(fill no)
			(layer "F.CrtYd")
		)
		(fp_rect
			(start -0.3 -0.15)
			(end 0.298 0.148)
			(stroke
				(width 0.15)
				(type solid)
			)
			(fill no)
			(layer "F.Fab")
		)
		(pad "" smd roundrect
			(at -0.346 0 270)
			(size 0.318 0.36)
			(layers "F.Paste")
			(roundrect_rratio 0.25)
			(teardrops
				(best_length_ratio 0.2)
				(max_length 1)
				(best_width_ratio 0.9)
				(max_width 2)
				(curved_edges yes)
				(filter_ratio 0.9)
				(enabled yes)
				(allow_two_segments yes)
				(prefer_zone_connections yes)
			)
		)
		(pad "" smd roundrect
			(at 0.344 0 270)
			(size 0.318 0.36)
			(layers "F.Paste")
			(roundrect_rratio 0.25)
			(teardrops
				(best_length_ratio 0.2)
				(max_length 1)
				(best_width_ratio 0.9)
				(max_width 2)
				(curved_edges yes)
				(filter_ratio 0.9)
				(enabled yes)
				(allow_two_segments yes)
				(prefer_zone_connections yes)
			)
		)
		(pad "1" smd roundrect
			(at -0.32 0 270)
			(size 0.46 0.4)
			(layers "F.Cu" "F.Mask")
			(roundrect_rratio 0.25)
			(net 171 "/2xSFP+/SFI0.RX+")
			(pintype "passive")
			(teardrops
				(best_length_ratio 0.2)
				(max_length 1)
				(best_width_ratio 0.9)
				(max_width 2)
				(curved_edges yes)
				(filter_ratio 0.9)
				(enabled yes)
				(allow_two_segments yes)
				(prefer_zone_connections yes)
			)
		)
		(pad "2" smd roundrect
			(at 0.32 0 270)
			(size 0.46 0.4)
			(layers "F.Cu" "F.Mask")
			(roundrect_rratio 0.25)
			(net 946 "/2xSFP+/KR to SFI #1/BYP_RX+")
			(pintype "passive")
			(teardrops
				(best_length_ratio 0.2)
				(max_length 1)
				(best_width_ratio 0.9)
				(max_width 2)
				(curved_edges yes)
				(filter_ratio 0.9)
				(enabled yes)
				(allow_two_segments yes)
				(prefer_zone_connections yes)
			)
		)
	)
	(footprint "antmicro-footprints:R_0402_1005Metric"
		(layer "F.Cu")
		(at 195.70861 77.152163 90)
		(descr "Resistor SMD 0402")
		(tags "resistor SMD 0402")
		(property "Reference" "R327"
			(at -1.9 -0.5 90)
			(layer "F.SilkS")
			(effects
				(font
					(size 0.7 0.7)
					(thickness 0.15)
				)
				(justify left bottom)
			)
		)
		(property "Value" "R_470R_0402"
			(at -1.011843 1.772047 90)
			(layer "F.Fab")
			(effects
				(font
					(size 0.7 0.7)
					(thickness 0.15)
				)
				(justify left bottom)
			)
		)
		(property "Datasheet" "https://www.bourns.com/docs/product-datasheets/cr.pdf"
			(at 0 0 90)
			(layer "F.Fab")
			(hide yes)
			(effects
				(font
					(size 1.27 1.27)
					(thickness 0.15)
				)
			)
		)
		(property "Author" "Antmicro"
			(at 272.860773 -118.556447 0)
			(layer "F.Fab")
			(hide yes)
			(effects
				(font
					(size 1 1)
					(thickness 0.15)
				)
			)
		)
		(property "License" "Apache-2.0"
			(at 272.860773 -118.556447 0)
			(layer "F.Fab")
			(hide yes)
			(effects
				(font
					(size 1 1)
					(thickness 0.15)
				)
			)
		)
		(property "MPN" "CR0402-FX-4700GLF"
			(at 272.860773 -118.556447 0)
			(layer "F.Fab")
			(hide yes)
			(effects
				(font
					(size 1 1)
					(thickness 0.15)
				)
			)
		)
		(property "Manufacturer" "Bourns"
			(at 272.860773 -118.556447 0)
			(layer "F.Fab")
			(hide yes)
			(effects
				(font
					(size 1 1)
					(thickness 0.15)
				)
			)
		)
		(property "Tolerance" "1%"
			(at 272.860773 -118.556447 0)
			(layer "F.Fab")
			(hide yes)
			(effects
				(font
					(size 1 1)
					(thickness 0.15)
				)
			)
		)
		(property "Val" "470R"
			(at 272.860773 -118.556447 0)
			(layer "F.Fab")
			(hide yes)
			(effects
				(font
					(size 1 1)
					(thickness 0.15)
				)
			)
		)
		(sheetname "Power")
		(sheetfile "power.kicad_sch")
		(attr smd)
		(fp_rect
			(start -0.925 -0.47)
			(end 0.925 0.47)
			(stroke
				(width 0.05)
				(type default)
			)
			(fill no)
			(layer "F.CrtYd")
		)
		(fp_rect
			(start -0.5 -0.25)
			(end 0.5 0.25)
			(stroke
				(width 0.15)
				(type solid)
			)
			(fill no)
			(layer "F.Fab")
		)
		(pad "1" smd roundrect
			(at -0.48 0 90)
			(size 0.59 0.64)
			(layers "F.Cu" "F.Mask" "F.Paste")
			(roundrect_rratio 0.25)
			(net 1 "GND")
			(pintype "passive")
			(teardrops
				(best_length_ratio 0.2)
				(max_length 1)
				(best_width_ratio 0.9)
				(max_width 2)
				(curved_edges yes)
				(filter_ratio 0.9)
				(enabled yes)
				(allow_two_segments yes)
				(prefer_zone_connections yes)
			)
		)
		(pad "2" smd roundrect
			(at 0.48 0 90)
			(size 0.59 0.64)
			(layers "F.Cu" "F.Mask" "F.Paste")
			(roundrect_rratio 0.25)
			(net 986 "Net-(D34-C)")
			(pintype "passive")
			(teardrops
				(best_length_ratio 0.2)
				(max_length 1)
				(best_width_ratio 0.9)
				(max_width 2)
				(curved_edges yes)
				(filter_ratio 0.9)
				(enabled yes)
				(allow_two_segments yes)
				(prefer_zone_connections yes)
			)
		)
	)
	(footprint "antmicro-footprints:SOT-23-3"
		(layer "F.Cu")
		(at 119.45 141.86 180)
		(property "Reference" "Q9"
			(at 1 2.1 90)
			(layer "F.SilkS")
			(effects
				(font
					(size 0.7 0.7)
					(thickness 0.15)
				)
				(justify right bottom)
			)
		)
		(property "Value" "MMBT3904LT1G"
			(at -1.9 2.7 0)
			(layer "F.Fab")
			(effects
				(font
					(size 0.7 0.7)
					(thickness 0.15)
				)
				(justify right bottom)
			)
		)
		(property "Datasheet" "https://eu.mouser.com/datasheet/2/308/1/MMBT3904LT1_D-2316262.pdf"
			(at 0 0 180)
			(layer "F.Fab")
			(hide yes)
			(effects
				(font
					(size 1.27 1.27)
					(thickness 0.15)
				)
			)
		)
		(property "Author" "Antmicro"
			(at 238.9 283.72 0)
			(layer "F.Fab")
			(hide yes)
			(effects
				(font
					(size 1 1)
					(thickness 0.15)
				)
			)
		)
		(property "License" "Apache-2.0"
			(at 238.9 283.72 0)
			(layer "F.Fab")
			(hide yes)
			(effects
				(font
					(size 1 1)
					(thickness 0.15)
				)
			)
		)
		(property "MPN" "MMBT3904LT1G"
			(at 238.9 283.72 0)
			(layer "F.Fab")
			(hide yes)
			(effects
				(font
					(size 1 1)
					(thickness 0.15)
				)
			)
		)
		(property "Manufacturer" "Onsemi"
			(at 238.9 283.72 0)
			(layer "F.Fab")
			(hide yes)
			(effects
				(font
					(size 1 1)
					(thickness 0.15)
				)
			)
		)
		(property "Public" "False"
			(at 238.9 283.72 0)
			(layer "F.Fab")
			(hide yes)
			(effects
				(font
					(size 1 1)
					(thickness 0.15)
				)
			)
		)
		(property ki_fp_filters "SOT?323*")
		(sheetname "Misc")
		(sheetfile "misc.kicad_sch")
		(attr smd)
		(fp_line
			(start 0.7 1.5)
			(end -0.7 1.5)
			(stroke
				(width 0.15)
				(type solid)
			)
			(layer "F.SilkS")
		)
		(fp_line
			(start 0.7 0.4)
			(end 0.7 1.5)
			(stroke
				(width 0.15)
				(type solid)
			)
			(layer "F.SilkS")
		)
		(fp_line
			(start 0.7 -0.4)
			(end 0.7 -1.5)
			(stroke
				(width 0.15)
				(type solid)
			)
			(layer "F.SilkS")
		)
		(fp_line
			(start 0.7 -1.5)
			(end -0.7 -1.5)
			(stroke
				(width 0.15)
				(type solid)
			)
			(layer "F.SilkS")
		)
		(fp_line
			(start -0.7 1.5)
			(end -0.7 1.35)
			(stroke
				(width 0.15)
				(type solid)
			)
			(layer "F.SilkS")
		)
		(fp_line
			(start -0.85 -1.35)
			(end -0.7 -1.5)
			(stroke
				(width 0.15)
				(type solid)
			)
			(layer "F.SilkS")
		)
		(fp_line
			(start -1.45 -1.35)
			(end -0.85 -1.35)
			(stroke
				(width 0.15)
				(type solid)
			)
			(layer "F.SilkS")
		)
		(fp_line
			(start 1.75 0.45)
			(end 0.85 0.45)
			(stroke
				(width 0.05)
				(type solid)
			)
			(layer "F.CrtYd")
		)
		(fp_line
			(start 1.75 -0.45)
			(end 1.75 0.45)
			(stroke
				(width 0.05)
				(type solid)
			)
			(layer "F.CrtYd")
		)
		(fp_line
			(start 0.85 1.65)
			(end -0.85 1.65)
			(stroke
				(width 0.05)
				(type solid)
			)
			(layer "F.CrtYd")
		)
		(fp_line
			(start 0.85 0.45)
			(end 0.85 1.65)
			(stroke
				(width 0.05)
				(type solid)
			)
			(layer "F.CrtYd")
		)
		(fp_line
			(start 0.825 -0.45)
			(end 1.75 -0.45)
			(stroke
				(width 0.05)
				(type solid)
			)
			(layer "F.CrtYd")
		)
		(fp_line
			(start 0.825 -1.6)
			(end 0.825 -0.45)
			(stroke
				(width 0.05)
				(type solid)
			)
			(layer "F.CrtYd")
		)
		(fp_line
			(start -0.85 1.65)
			(end -0.85 1.4)
			(stroke
				(width 0.05)
				(type solid)
			)
			(layer "F.CrtYd")
		)
		(fp_line
			(start -0.85 1.4)
			(end -1.75 1.4)
			(stroke
				(width 0.05)
				(type solid)
			)
			(layer "F.CrtYd")
		)
		(fp_line
			(start -0.85 0.5)
			(end -0.85 -0.5)
			(stroke
				(width 0.05)
				(type solid)
			)
			(layer "F.CrtYd")
		)
		(fp_line
			(start -0.85 -0.5)
			(end -1.75 -0.5)
			(stroke
				(width 0.05)
				(type solid)
			)
			(layer "F.CrtYd")
		)
		(fp_line
			(start -0.9 -1.4)
			(end -1.75 -1.4)
			(stroke
				(width 0.05)
				(type solid)
			)
			(layer "F.CrtYd")
		)
		(fp_line
			(start -0.9 -1.6)
			(end 0.825 -1.6)
			(stroke
				(width 0.05)
				(type solid)
			)
			(layer "F.CrtYd")
		)
		(fp_line
			(start -0.9 -1.6)
			(end -0.9 -1.4)
			(stroke
				(width 0.05)
				(type solid)
			)
			(layer "F.CrtYd")
		)
		(fp_line
			(start -1.75 1.4)
			(end -1.75 0.5)
			(stroke
				(width 0.05)
				(type solid)
			)
			(layer "F.CrtYd")
		)
		(fp_line
			(start -1.75 0.5)
			(end -0.85 0.5)
			(stroke
				(width 0.05)
				(type solid)
			)
			(layer "F.CrtYd")
		)
		(fp_line
			(start -1.75 -0.5)
			(end -1.75 -1.4)
			(stroke
				(width 0.05)
				(type solid)
			)
			(layer "F.CrtYd")
		)
		(fp_line
			(start 0.688 1.519)
			(end 0.688 -1.52)
			(stroke
				(width 0.15)
				(type solid)
			)
			(layer "F.Fab")
		)
		(fp_line
			(start -0.437 -1.526)
			(end 0.688 -1.526)
			(stroke
				(width 0.15)
				(type solid)
			)
			(layer "F.Fab")
		)
		(fp_line
			(start -0.437 -1.526)
			(end -0.712 -1.325)
			(stroke
				(width 0.15)
				(type solid)
			)
			(layer "F.Fab")
		)
		(fp_line
			(start -0.712 1.519)
			(end 0.688 1.519)
			(stroke
				(width 0.15)
				(type solid)
			)
			(layer "F.Fab")
		)
		(fp_line
			(start -0.712 -1.325)
			(end -0.712 1.523)
			(stroke
				(width 0.15)
				(type solid)
			)
			(layer "F.Fab")
		)
		(pad "1" smd roundrect
			(at -1.1 -0.951 180)
			(size 1 0.6)
			(layers "F.Cu" "F.Mask" "F.Paste")
			(roundrect_rratio 0.15)
			(net 541 "Net-(Q9-B)")
			(pinfunction "B")
			(pintype "input")
			(teardrops
				(best_length_ratio 0.2)
				(max_length 1)
				(best_width_ratio 0.9)
				(max_width 2)
				(curved_edges yes)
				(filter_ratio 0.9)
				(enabled yes)
				(allow_two_segments yes)
				(prefer_zone_connections yes)
			)
		)
		(pad "2" smd roundrect
			(at -1.1 0.949 180)
			(size 1 0.6)
			(layers "F.Cu" "F.Mask" "F.Paste")
			(roundrect_rratio 0.15)
			(net 542 "Net-(Q9-E)")
			(pinfunction "E")
			(pintype "passive")
			(teardrops
				(best_length_ratio 0.2)
				(max_length 1)
				(best_width_ratio 0.9)
				(max_width 2)
				(curved_edges yes)
				(filter_ratio 0.9)
				(enabled yes)
				(allow_two_segments yes)
				(prefer_zone_connections yes)
			)
		)
		(pad "3" smd roundrect
			(at 1.1 -0.0005 180)
			(size 1 0.6)
			(layers "F.Cu" "F.Mask" "F.Paste")
			(roundrect_rratio 0.15)
			(net 541 "Net-(Q9-B)")
			(pinfunction "C")
			(pintype "passive")
			(teardrops
				(best_length_ratio 0.2)
				(max_length 1)
				(best_width_ratio 0.9)
				(max_width 2)
				(curved_edges yes)
				(filter_ratio 0.9)
				(enabled yes)
				(allow_two_segments yes)
				(prefer_zone_connections yes)
			)
		)
	)
	(footprint "antmicro-footprints:R_0402_1005Metric"
		(layer "F.Cu")
		(at 241.8 132.36 -90)
		(descr "Resistor SMD 0402")
		(tags "resistor SMD 0402")
		(property "Reference" "R177"
			(at 0.85 -0.45 90)
			(layer "F.SilkS")
			(effects
				(font
					(size 0.7 0.7)
					(thickness 0.15)
				)
				(justify right bottom)
			)
		)
		(property "Value" "R_0R_0402"
			(at -1.011843 1.772047 90)
			(layer "F.Fab")
			(effects
				(font
					(size 0.7 0.7)
					(thickness 0.15)
				)
				(justify right bottom)
			)
		)
		(property "Datasheet" "https://industrial.panasonic.com/cdbs/www-data/pdf/RDA0000/AOA0000C301.pdf"
			(at 0 0 270)
			(layer "F.Fab")
			(hide yes)
			(effects
				(font
					(size 1.27 1.27)
					(thickness 0.15)
				)
			)
		)
		(property "Author" "Antmicro"
			(at 109.44 374.16 0)
			(layer "F.Fab")
			(hide yes)
			(effects
				(font
					(size 1 1)
					(thickness 0.15)
				)
			)
		)
		(property "Current" "1A"
			(at 109.44 374.16 0)
			(layer "F.Fab")
			(hide yes)
			(effects
				(font
					(size 1 1)
					(thickness 0.15)
				)
			)
		)
		(property "License" "Apache-2.0"
			(at 109.44 374.16 0)
			(layer "F.Fab")
			(hide yes)
			(effects
				(font
					(size 1 1)
					(thickness 0.15)
				)
			)
		)
		(property "MPN" "ERJ2GE0R00X"
			(at 109.44 374.16 0)
			(layer "F.Fab")
			(hide yes)
			(effects
				(font
					(size 1 1)
					(thickness 0.15)
				)
			)
		)
		(property "Manufacturer" "Panasonic"
			(at 109.44 374.16 0)
			(layer "F.Fab")
			(hide yes)
			(effects
				(font
					(size 1 1)
					(thickness 0.15)
				)
			)
		)
		(property "Public" "False"
			(at 109.44 374.16 0)
			(layer "F.Fab")
			(hide yes)
			(effects
				(font
					(size 1 1)
					(thickness 0.15)
				)
			)
		)
		(property "Tolerance" ""
			(at 109.44 374.16 0)
			(layer "F.Fab")
			(hide yes)
			(effects
				(font
					(size 1 1)
					(thickness 0.15)
				)
			)
		)
		(property "Val" "0R"
			(at 109.44 374.16 0)
			(layer "F.Fab")
			(hide yes)
			(effects
				(font
					(size 1 1)
					(thickness 0.15)
				)
			)
		)
		(sheetname "Com Express 7 MGMT")
		(sheetfile "com_express_7_mgmt.kicad_sch")
		(attr smd)
		(fp_rect
			(start -0.925 -0.47)
			(end 0.925 0.47)
			(stroke
				(width 0.05)
				(type default)
			)
			(fill no)
			(layer "F.CrtYd")
		)
		(fp_rect
			(start -0.5 -0.25)
			(end 0.5 0.25)
			(stroke
				(width 0.15)
				(type solid)
			)
			(fill no)
			(layer "F.Fab")
		)
		(pad "1" smd roundrect
			(at -0.48 0 270)
			(size 0.59 0.64)
			(layers "F.Cu" "F.Mask" "F.Paste")
			(roundrect_rratio 0.25)
			(net 599 "Net-(U34-~{INT})")
			(pintype "passive")
			(teardrops
				(best_length_ratio 0.2)
				(max_length 1)
				(best_width_ratio 0.9)
				(max_width 2)
				(curved_edges yes)
				(filter_ratio 0.9)
				(enabled yes)
				(allow_two_segments yes)
				(prefer_zone_connections yes)
			)
		)
		(pad "2" smd roundrect
			(at 0.48 0 270)
			(size 0.59 0.64)
			(layers "F.Cu" "F.Mask" "F.Paste")
			(roundrect_rratio 0.25)
			(net 356 "/Com Express 7 MGMT/~{CW_PWRBTN}")
			(pintype "passive")
			(teardrops
				(best_length_ratio 0.2)
				(max_length 1)
				(best_width_ratio 0.9)
				(max_width 2)
				(curved_edges yes)
				(filter_ratio 0.9)
				(enabled yes)
				(allow_two_segments yes)
				(prefer_zone_connections yes)
			)
		)
	)
	(footprint "antmicro-footprints:C_0402_1005Metric"
		(layer "F.Cu")
		(at 196.462003 134.572605 -45)
		(descr "Capacitor SMD 0402")
		(tags "capacitor SMD 0402")
		(property "Reference" "C137"
			(at 3.864616 -0.431761 135)
			(layer "F.SilkS")
			(effects
				(font
					(size 0.7 0.7)
					(thickness 0.15)
				)
				(justify right top)
			)
		)
		(property "Value" "C_100n_0402"
			(at -1.022927 2.155213 135)
			(layer "F.Fab")
			(effects
				(font
					(size 0.7 0.7)
					(thickness 0.15)
				)
				(justify right top)
			)
		)
		(property "Datasheet" "https://www.murata.com/products/productdetail?partno=GRM155R61H104KE14%23"
			(at 0 0 135)
			(layer "B.Fab")
			(hide yes)
			(effects
				(font
					(size 1.27 1.27)
					(thickness 0.15)
				)
				(justify mirror)
			)
		)
		(property "Author" "Antmicro"
			(at 49.668 -322.634 45)
			(layer "F.Fab")
			(hide yes)
			(effects
				(font
					(size 1 1)
					(thickness 0.15)
				)
			)
		)
		(property "Dielectric" "X5R"
			(at 49.668 -322.634 45)
			(layer "F.Fab")
			(hide yes)
			(effects
				(font
					(size 1 1)
					(thickness 0.15)
				)
			)
		)
		(property "License" "Apache-2.0"
			(at 49.668 -322.634 45)
			(layer "F.Fab")
			(hide yes)
			(effects
				(font
					(size 1 1)
					(thickness 0.15)
				)
			)
		)
		(property "MPN" "GRM155R61H104KE14D"
			(at 49.668 -322.634 45)
			(layer "F.Fab")
			(hide yes)
			(effects
				(font
					(size 1 1)
					(thickness 0.15)
				)
			)
		)
		(property "Manufacturer" "Murata"
			(at 49.668 -322.634 45)
			(layer "F.Fab")
			(hide yes)
			(effects
				(font
					(size 1 1)
					(thickness 0.15)
				)
			)
		)
		(property "Public" "False"
			(at 49.668 -322.634 45)
			(layer "F.Fab")
			(hide yes)
			(effects
				(font
					(size 1 1)
					(thickness 0.15)
				)
			)
		)
		(property "Val" "100n"
			(at 49.668 -322.634 45)
			(layer "F.Fab")
			(hide yes)
			(effects
				(font
					(size 1 1)
					(thickness 0.15)
				)
			)
		)
		(property "Voltage" "50V"
			(at 49.668 -322.634 45)
			(layer "F.Fab")
			(hide yes)
			(effects
				(font
					(size 1 1)
					(thickness 0.15)
				)
			)
		)
		(sheetname "PCIe redriver")
		(sheetfile "pcie_redriver.kicad_sch")
		(attr smd)
		(fp_poly
			(pts
				(xy -0.925 -0.47) (xy 0.925 -0.47) (xy 0.925 0.47) (xy -0.925 0.47)
			)
			(stroke
				(width 0.05)
				(type default)
			)
			(fill no)
			(layer "F.CrtYd")
		)
		(fp_line
			(start -0.494 0.248)
			(end -0.494 -0.25)
			(stroke
				(width 0.15)
				(type solid)
			)
			(layer "F.Fab")
		)
		(fp_line
			(start -0.494 -0.25)
			(end 0.504 -0.25)
			(stroke
				(width 0.15)
				(type solid)
			)
			(layer "F.Fab")
		)
		(fp_line
			(start 0.504 0.248)
			(end -0.494 0.248)
			(stroke
				(width 0.15)
				(type solid)
			)
			(layer "F.Fab")
		)
		(fp_line
			(start 0.504 -0.25)
			(end 0.504 0.248)
			(stroke
				(width 0.15)
				(type solid)
			)
			(layer "F.Fab")
		)
		(pad "1" smd roundrect
			(at -0.48 0 315)
			(size 0.59 0.64)
			(layers "F.Cu" "F.Mask" "F.Paste")
			(roundrect_rratio 0.25)
			(net 1 "GND")
			(pintype "passive")
			(teardrops
				(best_length_ratio 0.2)
				(max_length 1)
				(best_width_ratio 0.9)
				(max_width 2)
				(curved_edges yes)
				(filter_ratio 0.9)
				(enabled yes)
				(allow_two_segments yes)
				(prefer_zone_connections yes)
			)
		)
		(pad "2" smd roundrect
			(at 0.48 0 315)
			(size 0.59 0.64)
			(layers "F.Cu" "F.Mask" "F.Paste")
			(roundrect_rratio 0.25)
			(net 2 "+3V3")
			(pintype "passive")
			(teardrops
				(best_length_ratio 0.2)
				(max_length 1)
				(best_width_ratio 0.9)
				(max_width 2)
				(curved_edges yes)
				(filter_ratio 0.9)
				(enabled yes)
				(allow_two_segments yes)
				(prefer_zone_connections yes)
			)
		)
	)
	(footprint "antmicro-footprints:TSSOP-8_3x3mm_P0.65mm"
		(layer "F.Cu")
		(at 262.430708 78.085)
		(property "Reference" "U27"
			(at -0.96 2.725 0)
			(layer "F.SilkS")
			(effects
				(font
					(size 0.7 0.7)
					(thickness 0.15)
				)
				(justify left bottom)
			)
		)
		(property "Value" "NTS0102_TSSOP"
			(at 0 2.8 0)
			(layer "F.Fab")
			(effects
				(font
					(size 0.7 0.7)
					(thickness 0.15)
				)
				(justify left bottom)
			)
		)
		(property "Datasheet" "https://www.mouser.com/datasheet/2/302/NTS0102-1127324.pdf"
			(at 0 0 0)
			(layer "F.Fab")
			(hide yes)
			(effects
				(font
					(size 1.27 1.27)
					(thickness 0.15)
				)
			)
		)
		(property "Author" "Antmicro"
			(at 0 0 0)
			(layer "F.Fab")
			(hide yes)
			(effects
				(font
					(size 1 1)
					(thickness 0.15)
				)
			)
		)
		(property "License" "Apache-2.0"
			(at 0 0 0)
			(layer "F.Fab")
			(hide yes)
			(effects
				(font
					(size 1 1)
					(thickness 0.15)
				)
			)
		)
		(property "MPN" "NTS0102DP"
			(at 0 0 0)
			(layer "F.Fab")
			(hide yes)
			(effects
				(font
					(size 1 1)
					(thickness 0.15)
				)
			)
		)
		(property "Manufacturer" "NXP"
			(at 0 0 0)
			(layer "F.Fab")
			(hide yes)
			(effects
				(font
					(size 1 1)
					(thickness 0.15)
				)
			)
		)
		(sheetname "Misc")
		(sheetfile "misc.kicad_sch")
		(attr smd)
		(fp_line
			(start -1.55 1.561)
			(end 1.552 1.561)
			(stroke
				(width 0.15)
				(type solid)
			)
			(layer "F.SilkS")
		)
		(fp_line
			(start -1.525 -1.537)
			(end 1.552 -1.539)
			(stroke
				(width 0.15)
				(type solid)
			)
			(layer "F.SilkS")
		)
		(fp_circle
			(center -1.87 -1.4)
			(end -1.82 -1.4)
			(stroke
				(width 0.15)
				(type solid)
			)
			(fill yes)
			(layer "F.SilkS")
		)
		(fp_rect
			(start -3.15 -1.789)
			(end 3.15 1.811)
			(stroke
				(width 0.05)
				(type solid)
			)
			(fill no)
			(layer "F.CrtYd")
		)
		(fp_line
			(start -1.55 -0.937)
			(end -1.55 1.561)
			(stroke
				(width 0.15)
				(type solid)
			)
			(layer "F.Fab")
		)
		(fp_line
			(start -1.55 -0.937)
			(end -0.949 -1.539)
			(stroke
				(width 0.15)
				(type solid)
			)
			(layer "F.Fab")
		)
		(fp_line
			(start -1.55 1.561)
			(end 1.552 1.561)
			(stroke
				(width 0.15)
				(type solid)
			)
			(layer "F.Fab")
		)
		(fp_line
			(start -0.949 -1.539)
			(end 1.552 -1.539)
			(stroke
				(width 0.15)
				(type solid)
			)
			(layer "F.Fab")
		)
		(fp_line
			(start 1.552 -1.539)
			(end 1.552 1.561)
			(stroke
				(width 0.15)
				(type solid)
			)
			(layer "F.Fab")
		)
		(pad "1" smd roundrect
			(at -2.148 -0.962)
			(size 1.47 0.4)
			(layers "F.Cu" "F.Mask" "F.Paste")
			(roundrect_rratio 0.25)
			(net 280 "/Misc/PWM_{A5V}")
			(pinfunction "B_{2}")
			(pintype "bidirectional")
			(teardrops
				(best_length_ratio 0.2)
				(max_length 1)
				(best_width_ratio 0.9)
				(max_width 2)
				(curved_edges yes)
				(filter_ratio 0.9)
				(enabled yes)
				(allow_two_segments yes)
				(prefer_zone_connections yes)
			)
		)
		(pad "2" smd roundrect
			(at -2.148 -0.313)
			(size 1.47 0.4)
			(layers "F.Cu" "F.Mask" "F.Paste")
			(roundrect_rratio 0.25)
			(net 1 "GND")
			(pinfunction "GND")
			(pintype "power_in")
			(teardrops
				(best_length_ratio 0.2)
				(max_length 1)
				(best_width_ratio 0.9)
				(max_width 2)
				(curved_edges yes)
				(filter_ratio 0.9)
				(enabled yes)
				(allow_two_segments yes)
				(prefer_zone_connections yes)
			)
		)
		(pad "3" smd roundrect
			(at -2.148 0.338)
			(size 1.47 0.4)
			(layers "F.Cu" "F.Mask" "F.Paste")
			(roundrect_rratio 0.25)
			(net 2 "+3V3")
			(pinfunction "VCC_{A}")
			(pintype "power_in")
			(teardrops
				(best_length_ratio 0.2)
				(max_length 1)
				(best_width_ratio 0.9)
				(max_width 2)
				(curved_edges yes)
				(filter_ratio 0.9)
				(enabled yes)
				(allow_two_segments yes)
				(prefer_zone_connections yes)
			)
		)
		(pad "4" smd roundrect
			(at -2.148 0.987)
			(size 1.47 0.4)
			(layers "F.Cu" "F.Mask" "F.Paste")
			(roundrect_rratio 0.25)
			(net 782 "/Misc/PWM_{A3V3}")
			(pinfunction "A_{2}")
			(pintype "bidirectional")
			(teardrops
				(best_length_ratio 0.2)
				(max_length 1)
				(best_width_ratio 0.9)
				(max_width 2)
				(curved_edges yes)
				(filter_ratio 0.9)
				(enabled yes)
				(allow_two_segments yes)
				(prefer_zone_connections yes)
			)
		)
		(pad "5" smd roundrect
			(at 2.151 0.987)
			(size 1.47 0.4)
			(layers "F.Cu" "F.Mask" "F.Paste")
			(roundrect_rratio 0.25)
			(net 780 "/Misc/TACH_{A3V3}")
			(pinfunction "A_{1}")
			(pintype "bidirectional")
			(teardrops
				(best_length_ratio 0.2)
				(max_length 1)
				(best_width_ratio 0.9)
				(max_width 2)
				(curved_edges yes)
				(filter_ratio 0.9)
				(enabled yes)
				(allow_two_segments yes)
				(prefer_zone_connections yes)
			)
		)
		(pad "6" smd roundrect
			(at 2.151 0.338)
			(size 1.47 0.4)
			(layers "F.Cu" "F.Mask" "F.Paste")
			(roundrect_rratio 0.25)
			(net 2 "+3V3")
			(pinfunction "OE")
			(pintype "input")
			(teardrops
				(best_length_ratio 0.2)
				(max_length 1)
				(best_width_ratio 0.9)
				(max_width 2)
				(curved_edges yes)
				(filter_ratio 0.9)
				(enabled yes)
				(allow_two_segments yes)
				(prefer_zone_connections yes)
			)
		)
		(pad "7" smd roundrect
			(at 2.151 -0.313)
			(size 1.47 0.4)
			(layers "F.Cu" "F.Mask" "F.Paste")
			(roundrect_rratio 0.25)
			(net 52 "+5V")
			(pinfunction "VCC_{B}")
			(pintype "power_in")
			(teardrops
				(best_length_ratio 0.2)
				(max_length 1)
				(best_width_ratio 0.9)
				(max_width 2)
				(curved_edges yes)
				(filter_ratio 0.9)
				(enabled yes)
				(allow_two_segments yes)
				(prefer_zone_connections yes)
			)
		)
		(pad "8" smd roundrect
			(at 2.151 -0.962)
			(size 1.47 0.4)
			(layers "F.Cu" "F.Mask" "F.Paste")
			(roundrect_rratio 0.25)
			(net 279 "/Misc/TACH_{A5V}")
			(pinfunction "B_{1}")
			(pintype "bidirectional")
			(teardrops
				(best_length_ratio 0.2)
				(max_length 1)
				(best_width_ratio 0.9)
				(max_width 2)
				(curved_edges yes)
				(filter_ratio 0.9)
				(enabled yes)
				(allow_two_segments yes)
				(prefer_zone_connections yes)
			)
		)
	)
	(footprint "antmicro-footprints:R_0402_1005Metric"
		(layer "F.Cu")
		(at 237.77 151.931001)
		(descr "Resistor SMD 0402")
		(tags "resistor SMD 0402")
		(property "Reference" "R171"
			(at 0.83 0.428999 0)
			(layer "F.SilkS")
			(effects
				(font
					(size 0.7 0.7)
					(thickness 0.15)
				)
				(justify left bottom)
			)
		)
		(property "Value" "R_1k_0402"
			(at -1.011843 1.772047 0)
			(layer "F.Fab")
			(effects
				(font
					(size 0.7 0.7)
					(thickness 0.15)
				)
				(justify left bottom)
			)
		)
		(property "Datasheet" "https://www.bourns.com/docs/product-datasheets/cr.pdf"
			(at 0 0 0)
			(layer "F.Fab")
			(hide yes)
			(effects
				(font
					(size 1.27 1.27)
					(thickness 0.15)
				)
			)
		)
		(property "Author" "Antmicro"
			(at 0 0 0)
			(layer "F.Fab")
			(hide yes)
			(effects
				(font
					(size 1 1)
					(thickness 0.15)
				)
			)
		)
		(property "License" "Apache-2.0"
			(at 0 0 0)
			(layer "F.Fab")
			(hide yes)
			(effects
				(font
					(size 1 1)
					(thickness 0.15)
				)
			)
		)
		(property "MPN" "CR0402-FX-1001GLF"
			(at 0 0 0)
			(layer "F.Fab")
			(hide yes)
			(effects
				(font
					(size 1 1)
					(thickness 0.15)
				)
			)
		)
		(property "Manufacturer" "Bourns"
			(at 0 0 0)
			(layer "F.Fab")
			(hide yes)
			(effects
				(font
					(size 1 1)
					(thickness 0.15)
				)
			)
		)
		(property "Public" "False"
			(at 0 0 0)
			(layer "F.Fab")
			(hide yes)
			(effects
				(font
					(size 1 1)
					(thickness 0.15)
				)
			)
		)
		(property "Tolerance" "1%"
			(at 0 0 0)
			(layer "F.Fab")
			(hide yes)
			(effects
				(font
					(size 1 1)
					(thickness 0.15)
				)
			)
		)
		(property "Val" "1k"
			(at 0 0 0)
			(layer "F.Fab")
			(hide yes)
			(effects
				(font
					(size 1 1)
					(thickness 0.15)
				)
			)
		)
		(sheetname "Com Express 7 MGMT")
		(sheetfile "com_express_7_mgmt.kicad_sch")
		(attr smd)
		(fp_rect
			(start -0.925 -0.47)
			(end 0.925 0.47)
			(stroke
				(width 0.05)
				(type default)
			)
			(fill no)
			(layer "F.CrtYd")
		)
		(fp_rect
			(start -0.5 -0.25)
			(end 0.5 0.25)
			(stroke
				(width 0.15)
				(type solid)
			)
			(fill no)
			(layer "F.Fab")
		)
		(pad "1" smd roundrect
			(at -0.48 0)
			(size 0.59 0.64)
			(layers "F.Cu" "F.Mask" "F.Paste")
			(roundrect_rratio 0.25)
			(net 1 "GND")
			(pintype "passive")
			(teardrops
				(best_length_ratio 0.2)
				(max_length 1)
				(best_width_ratio 0.9)
				(max_width 2)
				(curved_edges yes)
				(filter_ratio 0.9)
				(enabled yes)
				(allow_two_segments yes)
				(prefer_zone_connections yes)
			)
		)
		(pad "2" smd roundrect
			(at 0.48 0)
			(size 0.59 0.64)
			(layers "F.Cu" "F.Mask" "F.Paste")
			(roundrect_rratio 0.25)
			(net 598 "Net-(U31-~{WC})")
			(pintype "passive")
			(teardrops
				(best_length_ratio 0.2)
				(max_length 1)
				(best_width_ratio 0.9)
				(max_width 2)
				(curved_edges yes)
				(filter_ratio 0.9)
				(enabled yes)
				(allow_two_segments yes)
				(prefer_zone_connections yes)
			)
		)
	)
	(footprint "antmicro-footprints:R_0402_1005Metric"
		(layer "F.Cu")
		(at 155.299 159.11 180)
		(descr "Resistor SMD 0402")
		(tags "resistor SMD 0402")
		(property "Reference" "R44"
			(at -6.701 17.5 0)
			(layer "F.SilkS")
			(effects
				(font
					(size 0.7 0.7)
					(thickness 0.15)
				)
				(justify right bottom)
			)
		)
		(property "Value" "R_0R_0402"
			(at -1.011843 1.772047 0)
			(layer "F.Fab")
			(effects
				(font
					(size 0.7 0.7)
					(thickness 0.15)
				)
				(justify right bottom)
			)
		)
		(property "Datasheet" "https://industrial.panasonic.com/cdbs/www-data/pdf/RDA0000/AOA0000C301.pdf"
			(at 0 0 180)
			(layer "F.Fab")
			(hide yes)
			(effects
				(font
					(size 1.27 1.27)
					(thickness 0.15)
				)
			)
		)
		(property "Author" "Antmicro"
			(at 310.598 318.22 0)
			(layer "F.Fab")
			(hide yes)
			(effects
				(font
					(size 1 1)
					(thickness 0.15)
				)
			)
		)
		(property "Current" "1A"
			(at 310.598 318.22 0)
			(layer "F.Fab")
			(hide yes)
			(effects
				(font
					(size 1 1)
					(thickness 0.15)
				)
			)
		)
		(property "License" "Apache-2.0"
			(at 310.598 318.22 0)
			(layer "F.Fab")
			(hide yes)
			(effects
				(font
					(size 1 1)
					(thickness 0.15)
				)
			)
		)
		(property "MPN" "ERJ2GE0R00X"
			(at 310.598 318.22 0)
			(layer "F.Fab")
			(hide yes)
			(effects
				(font
					(size 1 1)
					(thickness 0.15)
				)
			)
		)
		(property "Manufacturer" "Panasonic"
			(at 310.598 318.22 0)
			(layer "F.Fab")
			(hide yes)
			(effects
				(font
					(size 1 1)
					(thickness 0.15)
				)
			)
		)
		(property "Public" "False"
			(at 310.598 318.22 0)
			(layer "F.Fab")
			(hide yes)
			(effects
				(font
					(size 1 1)
					(thickness 0.15)
				)
			)
		)
		(property "Tolerance" ""
			(at 310.598 318.22 0)
			(layer "F.Fab")
			(hide yes)
			(effects
				(font
					(size 1 1)
					(thickness 0.15)
				)
			)
		)
		(property "Val" "0R"
			(at 310.598 318.22 0)
			(layer "F.Fab")
			(hide yes)
			(effects
				(font
					(size 1 1)
					(thickness 0.15)
				)
			)
		)
		(sheetname "2xSFP+")
		(sheetfile "2xSFP+.kicad_sch")
		(attr smd)
		(fp_rect
			(start -0.925 -0.47)
			(end 0.925 0.47)
			(stroke
				(width 0.05)
				(type default)
			)
			(fill no)
			(layer "F.CrtYd")
		)
		(fp_rect
			(start -0.5 -0.25)
			(end 0.5 0.25)
			(stroke
				(width 0.15)
				(type solid)
			)
			(fill no)
			(layer "F.Fab")
		)
		(pad "1" smd roundrect
			(at -0.48 0 180)
			(size 0.59 0.64)
			(layers "F.Cu" "F.Mask" "F.Paste")
			(roundrect_rratio 0.25)
			(net 563 "/2xSFP+/~{LED0_1}")
			(pintype "passive")
			(teardrops
				(best_length_ratio 0.2)
				(max_length 1)
				(best_width_ratio 0.9)
				(max_width 2)
				(curved_edges yes)
				(filter_ratio 0.9)
				(enabled yes)
				(allow_two_segments yes)
				(prefer_zone_connections yes)
			)
		)
		(pad "2" smd roundrect
			(at 0.48 0 180)
			(size 0.59 0.64)
			(layers "F.Cu" "F.Mask" "F.Paste")
			(roundrect_rratio 0.25)
			(net 931 "/2xSFP+/SFP0_LEDG")
			(pintype "passive")
			(teardrops
				(best_length_ratio 0.2)
				(max_length 1)
				(best_width_ratio 0.9)
				(max_width 2)
				(curved_edges yes)
				(filter_ratio 0.9)
				(enabled yes)
				(allow_two_segments yes)
				(prefer_zone_connections yes)
			)
		)
	)
	(footprint "antmicro-footprints:C_0402_1005Metric"
		(layer "F.Cu")
		(at 114.4 146.301 90)
		(descr "Capacitor SMD 0402")
		(tags "capacitor SMD 0402")
		(property "Reference" "C112"
			(at 10.541 2.6 90)
			(layer "F.SilkS")
			(effects
				(font
					(size 0.7 0.7)
					(thickness 0.15)
				)
				(justify left bottom)
			)
		)
		(property "Value" "C_100n_0402"
			(at -1.022927 2.155213 90)
			(layer "F.Fab")
			(effects
				(font
					(size 0.7 0.7)
					(thickness 0.15)
				)
				(justify left bottom)
			)
		)
		(property "Datasheet" "https://www.murata.com/products/productdetail?partno=GRM155R61H104KE14%23"
			(at 0 0 90)
			(layer "F.Fab")
			(hide yes)
			(effects
				(font
					(size 1.27 1.27)
					(thickness 0.15)
				)
			)
		)
		(property "Author" "Antmicro"
			(at 260.701 31.901 0)
			(layer "F.Fab")
			(hide yes)
			(effects
				(font
					(size 1 1)
					(thickness 0.15)
				)
			)
		)
		(property "Dielectric" "X5R"
			(at 260.701 31.901 0)
			(layer "F.Fab")
			(hide yes)
			(effects
				(font
					(size 1 1)
					(thickness 0.15)
				)
			)
		)
		(property "License" "Apache-2.0"
			(at 260.701 31.901 0)
			(layer "F.Fab")
			(hide yes)
			(effects
				(font
					(size 1 1)
					(thickness 0.15)
				)
			)
		)
		(property "MPN" "GRM155R61H104KE14D"
			(at 260.701 31.901 0)
			(layer "F.Fab")
			(hide yes)
			(effects
				(font
					(size 1 1)
					(thickness 0.15)
				)
			)
		)
		(property "Manufacturer" "Murata"
			(at 260.701 31.901 0)
			(layer "F.Fab")
			(hide yes)
			(effects
				(font
					(size 1 1)
					(thickness 0.15)
				)
			)
		)
		(property "Public" "False"
			(at 260.701 31.901 0)
			(layer "F.Fab")
			(hide yes)
			(effects
				(font
					(size 1 1)
					(thickness 0.15)
				)
			)
		)
		(property "Val" "100n"
			(at 260.701 31.901 0)
			(layer "F.Fab")
			(hide yes)
			(effects
				(font
					(size 1 1)
					(thickness 0.15)
				)
			)
		)
		(property "Voltage" "50V"
			(at 260.701 31.901 0)
			(layer "F.Fab")
			(hide yes)
			(effects
				(font
					(size 1 1)
					(thickness 0.15)
				)
			)
		)
		(sheetname "PCIe redriver")
		(sheetfile "pcie_redriver.kicad_sch")
		(attr smd)
		(fp_rect
			(start -0.925 -0.47)
			(end 0.925 0.47)
			(stroke
				(width 0.05)
				(type default)
			)
			(fill no)
			(layer "F.CrtYd")
		)
		(fp_line
			(start 0.504 -0.25)
			(end 0.504 0.248)
			(stroke
				(width 0.15)
				(type solid)
			)
			(layer "F.Fab")
		)
		(fp_line
			(start -0.494 -0.25)
			(end 0.504 -0.25)
			(stroke
				(width 0.15)
				(type solid)
			)
			(layer "F.Fab")
		)
		(fp_line
			(start 0.504 0.248)
			(end -0.494 0.248)
			(stroke
				(width 0.15)
				(type solid)
			)
			(layer "F.Fab")
		)
		(fp_line
			(start -0.494 0.248)
			(end -0.494 -0.25)
			(stroke
				(width 0.15)
				(type solid)
			)
			(layer "F.Fab")
		)
		(pad "1" smd roundrect
			(at -0.48 0 90)
			(size 0.59 0.64)
			(layers "F.Cu" "F.Mask" "F.Paste")
			(roundrect_rratio 0.25)
			(net 1 "GND")
			(pintype "passive")
			(teardrops
				(best_length_ratio 0.2)
				(max_length 1)
				(best_width_ratio 0.9)
				(max_width 2)
				(curved_edges yes)
				(filter_ratio 0.9)
				(enabled yes)
				(allow_two_segments yes)
				(prefer_zone_connections yes)
			)
		)
		(pad "2" smd roundrect
			(at 0.48 0 90)
			(size 0.59 0.64)
			(layers "F.Cu" "F.Mask" "F.Paste")
			(roundrect_rratio 0.25)
			(net 2 "+3V3")
			(pintype "passive")
			(teardrops
				(best_length_ratio 0.2)
				(max_length 1)
				(best_width_ratio 0.9)
				(max_width 2)
				(curved_edges yes)
				(filter_ratio 0.9)
				(enabled yes)
				(allow_two_segments yes)
				(prefer_zone_connections yes)
			)
		)
	)
	(footprint "antmicro-footprints:SOT-23-5"
		(layer "F.Cu")
		(at 296.75 101.161 -90)
		(property "Reference" "U23"
			(at 2.849 -1.1 180)
			(layer "F.SilkS")
			(effects
				(font
					(size 0.7 0.7)
					(thickness 0.15)
				)
				(justify right bottom)
			)
		)
		(property "Value" "TLV73333PDBVT"
			(at 0.002 2.799 90)
			(layer "F.Fab")
			(effects
				(font
					(size 0.7 0.7)
					(thickness 0.15)
				)
				(justify right bottom)
			)
		)
		(property "Datasheet" "https://www.ti.com/lit/ds/symlink/tlv733p.pdf?ts=1702303961350&ref_url=https%253A%252F%252Fwww.ti.com%252Fproduct%252FTLV733P%252Fpart-details%252FTLV73330PDBVR"
			(at 0 0 270)
			(layer "F.Fab")
			(hide yes)
			(effects
				(font
					(size 1.27 1.27)
					(thickness 0.15)
				)
			)
		)
		(property "Author" "Antmicro"
			(at 195.589 397.911 0)
			(layer "F.Fab")
			(hide yes)
			(effects
				(font
					(size 1 1)
					(thickness 0.15)
				)
			)
		)
		(property "License" "Apache-2.0"
			(at 195.589 397.911 0)
			(layer "F.Fab")
			(hide yes)
			(effects
				(font
					(size 1 1)
					(thickness 0.15)
				)
			)
		)
		(property "MPN" "TLV73333PDBVT"
			(at 195.589 397.911 0)
			(layer "F.Fab")
			(hide yes)
			(effects
				(font
					(size 1 1)
					(thickness 0.15)
				)
			)
		)
		(property "Manufacturer" "Texas Instruments"
			(at 195.589 397.911 0)
			(layer "F.Fab")
			(hide yes)
			(effects
				(font
					(size 1 1)
					(thickness 0.15)
				)
			)
		)
		(sheetname "Power")
		(sheetfile "power.kicad_sch")
		(attr smd)
		(fp_line
			(start -0.85 1.6)
			(end -0.85 1.301)
			(stroke
				(width 0.15)
				(type solid)
			)
			(layer "F.SilkS")
		)
		(fp_line
			(start -0.55 1.6)
			(end -0.85 1.6)
			(stroke
				(width 0.15)
				(type solid)
			)
			(layer "F.SilkS")
		)
		(fp_line
			(start 0.8 1.599)
			(end 0.549 1.599)
			(stroke
				(width 0.15)
				(type solid)
			)
			(layer "F.SilkS")
		)
		(fp_line
			(start 0.8 1.3)
			(end 0.8 1.599)
			(stroke
				(width 0.15)
				(type solid)
			)
			(layer "F.SilkS")
		)
		(fp_line
			(start 0.8 0.55)
			(end 0.8 -0.55)
			(stroke
				(width 0.15)
				(type solid)
			)
			(layer "F.SilkS")
		)
		(fp_line
			(start 0.8 -1.3)
			(end 0.8 -1.6)
			(stroke
				(width 0.15)
				(type solid)
			)
			(layer "F.SilkS")
		)
		(fp_line
			(start -0.8 -1.6)
			(end -0.8 -1.3)
			(stroke
				(width 0.15)
				(type solid)
			)
			(layer "F.SilkS")
		)
		(fp_line
			(start -0.8 -1.6)
			(end -0.5 -1.6)
			(stroke
				(width 0.15)
				(type solid)
			)
			(layer "F.SilkS")
		)
		(fp_line
			(start 0.8 -1.6)
			(end 0.5 -1.6)
			(stroke
				(width 0.15)
				(type solid)
			)
			(layer "F.SilkS")
		)
		(fp_circle
			(center -1.25 -1.5)
			(end -1.2 -1.5)
			(stroke
				(width 0.15)
				(type solid)
			)
			(fill yes)
			(layer "F.SilkS")
		)
		(fp_rect
			(start 1.9 -1.76)
			(end -1.9 1.75)
			(stroke
				(width 0.05)
				(type solid)
			)
			(fill no)
			(layer "F.CrtYd")
		)
		(fp_line
			(start -0.398 -1.526)
			(end -0.874 -1.05)
			(stroke
				(width 0.15)
				(type solid)
			)
			(layer "F.Fab")
		)
		(fp_rect
			(start 0.874 1.523)
			(end -0.873 -1.525)
			(stroke
				(width 0.15)
				(type solid)
			)
			(fill no)
			(layer "F.Fab")
		)
		(pad "1" smd rect
			(at -1.351 -0.951 180)
			(size 0.55 1)
			(layers "F.Cu" "F.Mask" "F.Paste")
			(net 77 "+5V_AON")
			(pinfunction "VIN")
			(pintype "power_in")
			(teardrops
				(best_length_ratio 0.2)
				(max_length 1)
				(best_width_ratio 0.9)
				(max_width 2)
				(curved_edges yes)
				(filter_ratio 0.9)
				(enabled yes)
				(allow_two_segments yes)
				(prefer_zone_connections yes)
			)
		)
		(pad "2" smd rect
			(at -1.351 0 180)
			(size 0.55 1)
			(layers "F.Cu" "F.Mask" "F.Paste")
			(net 1 "GND")
			(pinfunction "GND")
			(pintype "power_in")
			(teardrops
				(best_length_ratio 0.2)
				(max_length 1)
				(best_width_ratio 0.9)
				(max_width 2)
				(curved_edges yes)
				(filter_ratio 0.9)
				(enabled yes)
				(allow_two_segments yes)
				(prefer_zone_connections yes)
			)
		)
		(pad "3" smd rect
			(at -1.351 0.949 180)
			(size 0.55 1)
			(layers "F.Cu" "F.Mask" "F.Paste")
			(net 77 "+5V_AON")
			(pinfunction "EN")
			(pintype "input")
			(teardrops
				(best_length_ratio 0.2)
				(max_length 1)
				(best_width_ratio 0.9)
				(max_width 2)
				(curved_edges yes)
				(filter_ratio 0.9)
				(enabled yes)
				(allow_two_segments yes)
				(prefer_zone_connections yes)
			)
		)
		(pad "4" smd rect
			(at 1.35 0.949 180)
			(size 0.55 1)
			(layers "F.Cu" "F.Mask" "F.Paste")
			(net 779 "unconnected-(U23-NC-Pad4)")
			(pinfunction "NC")
			(pintype "no_connect")
			(teardrops
				(best_length_ratio 0.2)
				(max_length 1)
				(best_width_ratio 0.9)
				(max_width 2)
				(curved_edges yes)
				(filter_ratio 0.9)
				(enabled yes)
				(allow_two_segments yes)
				(prefer_zone_connections yes)
			)
		)
		(pad "5" smd rect
			(at 1.35 -0.951 180)
			(size 0.55 1)
			(layers "F.Cu" "F.Mask" "F.Paste")
			(net 79 "Net-(U23-VOUT)")
			(pinfunction "VOUT")
			(pintype "power_out")
			(teardrops
				(best_length_ratio 0.2)
				(max_length 1)
				(best_width_ratio 0.9)
				(max_width 2)
				(curved_edges yes)
				(filter_ratio 0.9)
				(enabled yes)
				(allow_two_segments yes)
				(prefer_zone_connections yes)
			)
		)
	)
	(footprint "antmicro-footprints:Spacer_Drill3.7mm_H5mm_9774050151R"
		(layer "F.Cu")
		(at 237.93 167.8 90)
		(descr "Spacer M=3 h=5mm fi=5.1mm")
		(property "Reference" "H8"
			(at -0.59 4.26 90)
			(layer "F.SilkS")
			(hide yes)
			(effects
				(font
					(size 0.7 0.7)
					(thickness 0.15)
				)
				(justify left bottom)
			)
		)
		(property "Value" "Spacer_Drill3.7mm_H5mm_9774050151R"
			(at 0 4 90)
			(layer "F.Fab")
			(effects
				(font
					(size 0.7 0.7)
					(thickness 0.15)
				)
				(justify left bottom)
			)
		)
		(property "Datasheet" "https://www.we-online.com/catalog/datasheet/9774050151.pdf"
			(at 0 0 90)
			(layer "F.Fab")
			(hide yes)
			(effects
				(font
					(size 1.27 1.27)
					(thickness 0.15)
				)
			)
		)
		(property "Author" "Antmicro"
			(at 405.75 -70.13 0)
			(layer "F.Fab")
			(hide yes)
			(effects
				(font
					(size 1 1)
					(thickness 0.15)
				)
			)
		)
		(property "License" "Apache-2.0"
			(at 405.75 -70.13 0)
			(layer "F.Fab")
			(hide yes)
			(effects
				(font
					(size 1 1)
					(thickness 0.15)
				)
			)
		)
		(property "MPN" "9774050151R"
			(at 405.75 -70.13 0)
			(layer "F.Fab")
			(hide yes)
			(effects
				(font
					(size 1 1)
					(thickness 0.15)
				)
			)
		)
		(property "Manufacturer" "Würth Elektronik"
			(at 405.75 -70.13 0)
			(layer "F.Fab")
			(hide yes)
			(effects
				(font
					(size 1 1)
					(thickness 0.15)
				)
			)
		)
		(sheetname "Com Express 7 Interfaces")
		(sheetfile "com_express_7_interfaces.kicad_sch")
		(solder_paste_margin_ratio -1)
		(attr smd)
		(fp_circle
			(center 0 0)
			(end 3.05 0)
			(stroke
				(width 0.05)
				(type solid)
			)
			(fill no)
			(layer "F.CrtYd")
		)
		(fp_circle
			(center 0 0)
			(end 2.6 0)
			(stroke
				(width 0.15)
				(type solid)
			)
			(fill no)
			(layer "F.Fab")
		)
		(pad "" smd custom
			(at -1.7 -1.7 90)
			(size 0.62 0.62)
			(layers "F.Paste")
			(thermal_bridge_angle 90)
			(options
				(clearance outline)
				(anchor circle)
			)
			(primitives
				(gr_arc
					(start -0.250195 1.279127)
					(mid 0.285453 0.294389)
					(end 1.266786 -0.24747)
					(width 0.2)
				)
				(gr_arc
					(start -0.34334 1.279127)
					(mid 0.218448 0.232561)
					(end 1.259603 -0.339191)
					(width 0.2)
				)
				(gr_arc
					(start -0.436309 1.279127)
					(mid 0.152481 0.169693)
					(end 1.255279 -0.431435)
					(width 0.2)
				)
				(gr_arc
					(start -0.529126 1.279127)
					(mid 0.087542 0.105784)
					(end 1.253811 -0.524161)
					(width 0.2)
				)
				(gr_arc
					(start -0.621807 1.279127)
					(mid 0.0309 0.033527)
					(end 1.275473 -0.621136)
					(width 0.2)
				)
				(gr_arc
					(start -0.71437 1.279127)
					(mid -0.037758 -0.026651)
					(end 1.263664 -0.711602)
					(width 0.2)
				)
				(gr_arc
					(start -0.806826 1.279127)
					(mid -0.105837 -0.087395)
					(end 1.253435 -0.802342)
					(width 0.2)
				)
				(gr_arc
					(start -0.899187 1.279127)
					(mid -0.165236 -0.156885)
					(end 1.267475 -0.897258)
					(width 0.2)
				)
				(gr_arc
					(start -0.991463 1.279127)
					(mid -0.228522 -0.222449)
					(end 1.270645 -0.990112)
					(width 0.2)
				)
				(gr_arc
					(start -1.083663 1.279127)
					(mid -0.294507 -0.285313)
					(end 1.266278 -1.081674)
					(width 0.2)
				)
				(gr_line
					(start 1.279127 -0.250195)
					(end 1.279127 -1.083663)
					(width 0.2)
				)
				(gr_line
					(start -0.250195 1.279127)
					(end -1.083663 1.279127)
					(width 0.2)
				)
			)
			(teardrops
				(best_length_ratio 0.2)
				(max_length 1)
				(best_width_ratio 0.9)
				(max_width 2)
				(curved_edges yes)
				(filter_ratio 0.9)
				(enabled yes)
				(allow_two_segments yes)
				(prefer_zone_connections yes)
			)
		)
		(pad "" smd custom
			(at -1.7 1.7 180)
			(size 0.62 0.62)
			(layers "F.Paste")
			(thermal_bridge_angle 90)
			(options
				(clearance outline)
				(anchor circle)
			)
			(primitives
				(gr_arc
					(start -0.250195 1.279127)
					(mid 0.285453 0.294389)
					(end 1.266786 -0.24747)
					(width 0.2)
				)
				(gr_arc
					(start -0.34334 1.279127)
					(mid 0.218448 0.232561)
					(end 1.259603 -0.339191)
					(width 0.2)
				)
				(gr_arc
					(start -0.436309 1.279127)
					(mid 0.152481 0.169693)
					(end 1.255279 -0.431435)
					(width 0.2)
				)
				(gr_arc
					(start -0.529126 1.279127)
					(mid 0.087542 0.105784)
					(end 1.253811 -0.524161)
					(width 0.2)
				)
				(gr_arc
					(start -0.621807 1.279127)
					(mid 0.0309 0.033527)
					(end 1.275473 -0.621136)
					(width 0.2)
				)
				(gr_arc
					(start -0.71437 1.279127)
					(mid -0.037758 -0.026651)
					(end 1.263664 -0.711602)
					(width 0.2)
				)
				(gr_arc
					(start -0.806826 1.279127)
					(mid -0.105837 -0.087395)
					(end 1.253435 -0.802342)
					(width 0.2)
				)
				(gr_arc
					(start -0.899187 1.279127)
					(mid -0.165236 -0.156885)
					(end 1.267475 -0.897258)
					(width 0.2)
				)
				(gr_arc
					(start -0.991463 1.279127)
					(mid -0.228522 -0.222449)
					(end 1.270645 -0.990112)
					(width 0.2)
				)
				(gr_arc
					(start -1.083663 1.279127)
					(mid -0.294507 -0.285313)
					(end 1.266278 -1.081674)
					(width 0.2)
				)
				(gr_line
					(start 1.279127 -0.250195)
					(end 1.279127 -1.083663)
					(width 0.2)
				)
				(gr_line
					(start -0.250195 1.279127)
					(end -1.083663 1.279127)
					(width 0.2)
				)
			)
			(teardrops
				(best_length_ratio 0.2)
				(max_length 1)
				(best_width_ratio 0.9)
				(max_width 2)
				(curved_edges yes)
				(filter_ratio 0.9)
				(enabled yes)
				(allow_two_segments yes)
				(prefer_zone_connections yes)
			)
		)
		(pad "" smd custom
			(at 1.7 -1.7)
			(size 0.62 0.62)
			(layers "F.Paste")
			(thermal_bridge_angle 90)
			(options
				(clearance outline)
				(anchor circle)
			)
			(primitives
				(gr_arc
					(start -0.250195 1.279127)
					(mid 0.285453 0.294389)
					(end 1.266786 -0.24747)
					(width 0.2)
				)
				(gr_arc
					(start -0.34334 1.279127)
					(mid 0.218448 0.232561)
					(end 1.259603 -0.339191)
					(width 0.2)
				)
				(gr_arc
					(start -0.436309 1.279127)
					(mid 0.152481 0.169693)
					(end 1.255279 -0.431435)
					(width 0.2)
				)
				(gr_arc
					(start -0.529126 1.279127)
					(mid 0.087542 0.105784)
					(end 1.253811 -0.524161)
					(width 0.2)
				)
				(gr_arc
					(start -0.621807 1.279127)
					(mid 0.0309 0.033527)
					(end 1.275473 -0.621136)
					(width 0.2)
				)
				(gr_arc
					(start -0.71437 1.279127)
					(mid -0.037758 -0.026651)
					(end 1.263664 -0.711602)
					(width 0.2)
				)
				(gr_arc
					(start -0.806826 1.279127)
					(mid -0.105837 -0.087395)
					(end 1.253435 -0.802342)
					(width 0.2)
				)
				(gr_arc
					(start -0.899187 1.279127)
					(mid -0.165236 -0.156885)
					(end 1.267475 -0.897258)
					(width 0.2)
				)
				(gr_arc
					(start -0.991463 1.279127)
					(mid -0.228522 -0.222449)
					(end 1.270645 -0.990112)
					(width 0.2)
				)
				(gr_arc
					(start -1.083663 1.279127)
					(mid -0.294507 -0.285313)
					(end 1.266278 -1.081674)
					(width 0.2)
				)
				(gr_line
					(start 1.279127 -0.250195)
					(end 1.279127 -1.083663)
					(width 0.2)
				)
				(gr_line
					(start -0.250195 1.279127)
					(end -1.083663 1.279127)
					(width 0.2)
				)
			)
			(teardrops
				(best_length_ratio 0.2)
				(max_length 1)
				(best_width_ratio 0.9)
				(max_width 2)
				(curved_edges yes)
				(filter_ratio 0.9)
				(enabled yes)
				(allow_two_segments yes)
				(prefer_zone_connections yes)
			)
		)
		(pad "" smd custom
			(at 1.7 1.7 270)
			(size 0.62 0.62)
			(layers "F.Paste")
			(thermal_bridge_angle 90)
			(options
				(clearance outline)
				(anchor circle)
			)
			(primitives
				(gr_arc
					(start -0.250195 1.279127)
					(mid 0.285453 0.294389)
					(end 1.266786 -0.24747)
					(width 0.2)
				)
				(gr_arc
					(start -0.34334 1.279127)
					(mid 0.218448 0.232561)
					(end 1.259603 -0.339191)
					(width 0.2)
				)
				(gr_arc
					(start -0.436309 1.279127)
					(mid 0.152481 0.169693)
					(end 1.255279 -0.431435)
					(width 0.2)
				)
				(gr_arc
					(start -0.529126 1.279127)
					(mid 0.087542 0.105784)
					(end 1.253811 -0.524161)
					(width 0.2)
				)
				(gr_arc
					(start -0.621807 1.279127)
					(mid 0.0309 0.033527)
					(end 1.275473 -0.621136)
					(width 0.2)
				)
				(gr_arc
					(start -0.71437 1.279127)
					(mid -0.037758 -0.026651)
					(end 1.263664 -0.711602)
					(width 0.2)
				)
				(gr_arc
					(start -0.806826 1.279127)
					(mid -0.105837 -0.087395)
					(end 1.253435 -0.802342)
					(width 0.2)
				)
				(gr_arc
					(start -0.899187 1.279127)
					(mid -0.165236 -0.156885)
					(end 1.267475 -0.897258)
					(width 0.2)
				)
				(gr_arc
					(start -0.991463 1.279127)
					(mid -0.228522 -0.222449)
					(end 1.270645 -0.990112)
					(width 0.2)
				)
				(gr_arc
					(start -1.083663 1.279127)
					(mid -0.294507 -0.285313)
					(end 1.266278 -1.081674)
					(width 0.2)
				)
				(gr_line
					(start 1.279127 -0.250195)
					(end 1.279127 -1.083663)
					(width 0.2)
				)
				(gr_line
					(start -0.250195 1.279127)
					(end -1.083663 1.279127)
					(width 0.2)
				)
			)
			(teardrops
				(best_length_ratio 0.2)
				(max_length 1)
				(best_width_ratio 0.9)
				(max_width 2)
				(curved_edges yes)
				(filter_ratio 0.9)
				(enabled yes)
				(allow_two_segments yes)
				(prefer_zone_connections yes)
			)
		)
		(pad "1" thru_hole circle
			(at 0 0 90)
			(size 6 6)
			(drill 3.7)
			(layers "*.Cu" "*.Mask")
			(remove_unused_layers no)
			(net 1 "GND")
			(pintype "passive")
			(teardrops
				(best_length_ratio 0.4)
				(max_length 1)
				(best_width_ratio 0.9)
				(max_width 2)
				(curved_edges yes)
				(filter_ratio 0.9)
				(enabled yes)
				(allow_two_segments yes)
				(prefer_zone_connections yes)
			)
		)
	)
	(footprint "antmicro-footprints:R_0402_1005Metric"
		(layer "F.Cu")
		(at 191.635786 128.785786 -135)
		(descr "Resistor SMD 0402")
		(tags "resistor SMD 0402")
		(property "Reference" "R220"
			(at -3.65 -0.4 45)
			(layer "F.SilkS")
			(effects
				(font
					(size 0.7 0.7)
					(thickness 0.15)
				)
				(justify right bottom)
			)
		)
		(property "Value" "R_1k_0402"
			(at -1.011843 1.772046 45)
			(layer "F.Fab")
			(effects
				(font
					(size 0.7 0.7)
					(thickness 0.15)
				)
				(justify right bottom)
			)
		)
		(property "Datasheet" "https://www.bourns.com/docs/product-datasheets/cr.pdf"
			(at 0 0 45)
			(layer "F.Fab")
			(hide yes)
			(effects
				(font
					(size 1.27 1.27)
					(thickness 0.15)
				)
			)
		)
		(property "Author" "Antmicro"
			(at 389.1 259.22 45)
			(layer "F.Fab")
			(hide yes)
			(effects
				(font
					(size 1 1)
					(thickness 0.15)
				)
			)
		)
		(property "License" "Apache-2.0"
			(at 389.1 259.22 45)
			(layer "F.Fab")
			(hide yes)
			(effects
				(font
					(size 1 1)
					(thickness 0.15)
				)
			)
		)
		(property "MPN" "CR0402-FX-1001GLF"
			(at 389.1 259.22 45)
			(layer "F.Fab")
			(hide yes)
			(effects
				(font
					(size 1 1)
					(thickness 0.15)
				)
			)
		)
		(property "Manufacturer" "Bourns"
			(at 389.1 259.22 45)
			(layer "F.Fab")
			(hide yes)
			(effects
				(font
					(size 1 1)
					(thickness 0.15)
				)
			)
		)
		(property "Public" "False"
			(at 389.1 259.22 45)
			(layer "F.Fab")
			(hide yes)
			(effects
				(font
					(size 1 1)
					(thickness 0.15)
				)
			)
		)
		(property "Tolerance" "1%"
			(at 389.1 259.22 45)
			(layer "F.Fab")
			(hide yes)
			(effects
				(font
					(size 1 1)
					(thickness 0.15)
				)
			)
		)
		(property "Val" "1k"
			(at 389.1 259.22 45)
			(layer "F.Fab")
			(hide yes)
			(effects
				(font
					(size 1 1)
					(thickness 0.15)
				)
			)
		)
		(sheetname "PCIe redriver")
		(sheetfile "pcie_redriver.kicad_sch")
		(attr smd dnp)
		(fp_poly
			(pts
				(xy -0.925 -0.47) (xy 0.925 -0.47) (xy 0.925 0.47) (xy -0.925 0.47)
			)
			(stroke
				(width 0.05)
				(type default)
			)
			(fill no)
			(layer "F.CrtYd")
		)
		(fp_poly
			(pts
				(xy -0.5 -0.25) (xy 0.5 -0.25) (xy 0.5 0.25) (xy -0.5 0.25)
			)
			(stroke
				(width 0.15)
				(type solid)
			)
			(fill no)
			(layer "F.Fab")
		)
		(pad "1" smd roundrect
			(at -0.48 0 225)
			(size 0.59 0.64)
			(layers "F.Cu" "F.Mask" "F.Paste")
			(roundrect_rratio 0.25)
			(net 1 "GND")
			(pintype "passive")
			(teardrops
				(best_length_ratio 0.2)
				(max_length 1)
				(best_width_ratio 0.9)
				(max_width 2)
				(curved_edges yes)
				(filter_ratio 0.9)
				(enabled yes)
				(allow_two_segments yes)
				(prefer_zone_connections yes)
			)
		)
		(pad "2" smd roundrect
			(at 0.48 0 225)
			(size 0.59 0.64)
			(layers "F.Cu" "F.Mask" "F.Paste")
			(roundrect_rratio 0.25)
			(net 973 "/PCIe redriver/RX_SW")
			(pintype "passive")
			(teardrops
				(best_length_ratio 0.2)
				(max_length 1)
				(best_width_ratio 0.9)
				(max_width 2)
				(curved_edges yes)
				(filter_ratio 0.9)
				(enabled yes)
				(allow_two_segments yes)
				(prefer_zone_connections yes)
			)
		)
	)
	(footprint "antmicro-footprints:R_0201"
		(layer "F.Cu")
		(at 155.572 147.935 -90)
		(descr "Resistor SMD 0201")
		(tags "resistor SMD 0201")
		(property "Reference" "R251"
			(at 6.495 -0.278 270)
			(layer "F.SilkS")
			(effects
				(font
					(size 0.7 0.7)
					(thickness 0.15)
				)
				(justify left bottom)
			)
		)
		(property "Value" "R_0R_0201"
			(at 0 1.25 270)
			(layer "F.Fab")
			(effects
				(font
					(size 0.7 0.7)
					(thickness 0.15)
				)
				(justify left bottom)
			)
		)
		(property "Datasheet" "https://www.bourns.com/docs/product-datasheets/cr.pdf"
			(at 0 0 270)
			(layer "F.Fab")
			(hide yes)
			(effects
				(font
					(size 1.27 1.27)
					(thickness 0.15)
				)
			)
		)
		(property "Author" "Antmicro"
			(at 7.637 303.507 0)
			(layer "F.Fab")
			(hide yes)
			(effects
				(font
					(size 1 1)
					(thickness 0.15)
				)
			)
		)
		(property "License" "Apache-2.0"
			(at 7.637 303.507 0)
			(layer "F.Fab")
			(hide yes)
			(effects
				(font
					(size 1 1)
					(thickness 0.15)
				)
			)
		)
		(property "MPN" "CR0201-FX-0R00GLF"
			(at 7.637 303.507 0)
			(layer "F.Fab")
			(hide yes)
			(effects
				(font
					(size 1 1)
					(thickness 0.15)
				)
			)
		)
		(property "Manufacturer" "Bourns"
			(at 7.637 303.507 0)
			(layer "F.Fab")
			(hide yes)
			(effects
				(font
					(size 1 1)
					(thickness 0.15)
				)
			)
		)
		(property "Tolerance" "1%"
			(at 7.637 303.507 0)
			(layer "F.Fab")
			(hide yes)
			(effects
				(font
					(size 1 1)
					(thickness 0.15)
				)
			)
		)
		(property "Val" "0R"
			(at 7.637 303.507 0)
			(layer "F.Fab")
			(hide yes)
			(effects
				(font
					(size 1 1)
					(thickness 0.15)
				)
			)
		)
		(sheetname "KR to SFI #1")
		(sheetfile "kr_sfi.kicad_sch")
		(attr smd dnp)
		(fp_rect
			(start -0.7 -0.35)
			(end 0.7 0.35)
			(stroke
				(width 0.05)
				(type default)
			)
			(fill no)
			(layer "F.CrtYd")
		)
		(fp_rect
			(start -0.3 -0.15)
			(end 0.298 0.148)
			(stroke
				(width 0.15)
				(type solid)
			)
			(fill no)
			(layer "F.Fab")
		)
		(pad "" smd roundrect
			(at -0.346 0 270)
			(size 0.318 0.36)
			(layers "F.Paste")
			(roundrect_rratio 0.25)
			(teardrops
				(best_length_ratio 0.2)
				(max_length 1)
				(best_width_ratio 0.9)
				(max_width 2)
				(curved_edges yes)
				(filter_ratio 0.9)
				(enabled yes)
				(allow_two_segments yes)
				(prefer_zone_connections yes)
			)
		)
		(pad "" smd roundrect
			(at 0.344 0 270)
			(size 0.318 0.36)
			(layers "F.Paste")
			(roundrect_rratio 0.25)
			(teardrops
				(best_length_ratio 0.2)
				(max_length 1)
				(best_width_ratio 0.9)
				(max_width 2)
				(curved_edges yes)
				(filter_ratio 0.9)
				(enabled yes)
				(allow_two_segments yes)
				(prefer_zone_connections yes)
			)
		)
		(pad "1" smd roundrect
			(at -0.32 0 270)
			(size 0.46 0.4)
			(layers "F.Cu" "F.Mask")
			(roundrect_rratio 0.25)
			(net 111 "/2xSFP+/10GKR_SFP0.TX+")
			(pintype "passive")
			(teardrops
				(best_length_ratio 0.2)
				(max_length 1)
				(best_width_ratio 0.9)
				(max_width 2)
				(curved_edges yes)
				(filter_ratio 0.9)
				(enabled yes)
				(allow_two_segments yes)
				(prefer_zone_connections yes)
			)
		)
		(pad "2" smd roundrect
			(at 0.32 0 270)
			(size 0.46 0.4)
			(layers "F.Cu" "F.Mask")
			(roundrect_rratio 0.25)
			(net 954 "/2xSFP+/KR to SFI #1/BYP_TX+")
			(pintype "passive")
			(teardrops
				(best_length_ratio 0.2)
				(max_length 1)
				(best_width_ratio 0.9)
				(max_width 2)
				(curved_edges yes)
				(filter_ratio 0.9)
				(enabled yes)
				(allow_two_segments yes)
				(prefer_zone_connections yes)
			)
		)
	)
	(footprint "antmicro-footprints:MicroSD_Wurth_693071020811"
		(layer "F.Cu")
		(at 101.935 136.76 -90)
		(descr "SMT MICRO SD CARD CONNECTOR")
		(property "Reference" "J15"
			(at 9.2 4.735 180)
			(layer "F.SilkS")
			(effects
				(font
					(size 0.7 0.7)
					(thickness 0.15)
				)
				(justify right bottom)
			)
		)
		(property "Value" "MicroSD_693071020811"
			(at 0 8.9 90)
			(layer "F.Fab")
			(effects
				(font
					(size 0.7 0.7)
					(thickness 0.15)
				)
				(justify right bottom)
			)
		)
		(property "Datasheet" "https://www.we-online.com/catalog/datasheet/693071020811.pdf"
			(at 0 0 270)
			(layer "F.Fab")
			(hide yes)
			(effects
				(font
					(size 1.27 1.27)
					(thickness 0.15)
				)
			)
		)
		(property "Author" "Antmicro"
			(at -34.825 238.695 0)
			(layer "F.Fab")
			(hide yes)
			(effects
				(font
					(size 1 1)
					(thickness 0.15)
				)
			)
		)
		(property "License" "Apache-2.0"
			(at -34.825 238.695 0)
			(layer "F.Fab")
			(hide yes)
			(effects
				(font
					(size 1 1)
					(thickness 0.15)
				)
			)
		)
		(property "MPN" "693071020811"
			(at -34.825 238.695 0)
			(layer "F.Fab")
			(hide yes)
			(effects
				(font
					(size 1 1)
					(thickness 0.15)
				)
			)
		)
		(property "Manufacturer" "Würth Elektronik"
			(at -34.825 238.695 0)
			(layer "F.Fab")
			(hide yes)
			(effects
				(font
					(size 1 1)
					(thickness 0.15)
				)
			)
		)
		(sheetname "SD card")
		(sheetfile "sd_card.kicad_sch")
		(attr smd)
		(fp_line
			(start -7.35 1.432)
			(end -7.35 -5.267)
			(stroke
				(width 0.15)
				(type solid)
			)
			(layer "F.SilkS")
		)
		(fp_line
			(start 7.35 1.432)
			(end 7.35 -5.267)
			(stroke
				(width 0.15)
				(type solid)
			)
			(layer "F.SilkS")
		)
		(fp_line
			(start 6.201 -7.148)
			(end 2.801 -7.148)
			(stroke
				(width 0.15)
				(type solid)
			)
			(layer "F.SilkS")
		)
		(fp_circle
			(center 2.85 -7.9)
			(end 2.9 -7.9)
			(stroke
				(width 0.15)
				(type solid)
			)
			(fill yes)
			(layer "F.SilkS")
		)
		(fp_line
			(start -7.55 7.7)
			(end -7.55 4.55)
			(stroke
				(width 0.05)
				(type solid)
			)
			(layer "F.CrtYd")
		)
		(fp_line
			(start 7.5 7.7)
			(end -7.55 7.7)
			(stroke
				(width 0.05)
				(type solid)
			)
			(layer "F.CrtYd")
		)
		(fp_line
			(start 7.5 7.7)
			(end 7.5 4.55)
			(stroke
				(width 0.05)
				(type solid)
			)
			(layer "F.CrtYd")
		)
		(fp_line
			(start -8.7 4.55)
			(end -7.55 4.55)
			(stroke
				(width 0.05)
				(type solid)
			)
			(layer "F.CrtYd")
		)
		(fp_line
			(start -8.7 4.55)
			(end -8.7 1.6)
			(stroke
				(width 0.05)
				(type solid)
			)
			(layer "F.CrtYd")
		)
		(fp_line
			(start 8.7 4.55)
			(end 7.5 4.55)
			(stroke
				(width 0.05)
				(type solid)
			)
			(layer "F.CrtYd")
		)
		(fp_line
			(start 8.7 4.55)
			(end 8.7 1.6)
			(stroke
				(width 0.05)
				(type solid)
			)
			(layer "F.CrtYd")
		)
		(fp_line
			(start -7.55 1.6)
			(end -8.7 1.6)
			(stroke
				(width 0.05)
				(type solid)
			)
			(layer "F.CrtYd")
		)
		(fp_line
			(start 7.5 1.6)
			(end 8.7 1.6)
			(stroke
				(width 0.05)
				(type solid)
			)
			(layer "F.CrtYd")
		)
		(fp_line
			(start 7.5 1.6)
			(end 7.5 -5.45)
			(stroke
				(width 0.05)
				(type solid)
			)
			(layer "F.CrtYd")
		)
		(fp_line
			(start -7.55 -5.45)
			(end -7.55 1.6)
			(stroke
				(width 0.05)
				(type solid)
			)
			(layer "F.CrtYd")
		)
		(fp_line
			(start -7.55 -5.45)
			(end -9.1 -5.45)
			(stroke
				(width 0.05)
				(type solid)
			)
			(layer "F.CrtYd")
		)
		(fp_line
			(start 7.5 -5.45)
			(end 8.4 -5.45)
			(stroke
				(width 0.05)
				(type solid)
			)
			(layer "F.CrtYd")
		)
		(fp_line
			(start -9.1 -7.6)
			(end -9.1 -5.45)
			(stroke
				(width 0.05)
				(type solid)
			)
			(layer "F.CrtYd")
		)
		(fp_line
			(start -9.1 -7.6)
			(end -7.05 -7.6)
			(stroke
				(width 0.05)
				(type solid)
			)
			(layer "F.CrtYd")
		)
		(fp_line
			(start 2.75 -7.6)
			(end 2.75 -8.7)
			(stroke
				(width 0.05)
				(type solid)
			)
			(layer "F.CrtYd")
		)
		(fp_line
			(start 8.4 -7.6)
			(end 8.4 -5.45)
			(stroke
				(width 0.05)
				(type solid)
			)
			(layer "F.CrtYd")
		)
		(fp_line
			(start 8.4 -7.6)
			(end 2.75 -7.6)
			(stroke
				(width 0.05)
				(type solid)
			)
			(layer "F.CrtYd")
		)
		(fp_line
			(start -7.05 -8.7)
			(end -7.05 -7.6)
			(stroke
				(width 0.05)
				(type solid)
			)
			(layer "F.CrtYd")
		)
		(fp_line
			(start -7.05 -8.7)
			(end 2.75 -8.7)
			(stroke
				(width 0.05)
				(type solid)
			)
			(layer "F.CrtYd")
		)
		(fp_line
			(start -7.35 7.502)
			(end 7.35 7.502)
			(stroke
				(width 0.15)
				(type solid)
			)
			(layer "F.Fab")
		)
		(fp_line
			(start 7.35 7.353)
			(end 7.35 -7.148)
			(stroke
				(width 0.15)
				(type solid)
			)
			(layer "F.Fab")
		)
		(fp_line
			(start -7.35 -7.148)
			(end -7.35 7.353)
			(stroke
				(width 0.15)
				(type solid)
			)
			(layer "F.Fab")
		)
		(fp_line
			(start 7.35 -7.148)
			(end -7.35 -7.148)
			(stroke
				(width 0.15)
				(type solid)
			)
			(layer "F.Fab")
		)
		(pad "" np_thru_hole circle
			(at -4.95 3.485 270)
			(size 1 1)
			(drill 1)
			(layers "F&B.Cu" "*.Mask")
		)
		(pad "" np_thru_hole oval
			(at 3.05 3.485 270)
			(size 1.7 1)
			(drill oval 1.7 1)
			(layers "F&B.Cu" "*.Mask")
		)
		(pad "1" smd rect
			(at 2.25 -7.57 270)
			(size 0.7 1.9)
			(layers "F.Cu" "F.Mask" "F.Paste")
			(net 323 "/Com Express 7 Interfaces/SDIO.DAT2")
			(pinfunction "DAT2")
			(pintype "bidirectional")
			(teardrops
				(best_length_ratio 0.2)
				(max_length 1)
				(best_width_ratio 0.9)
				(max_width 2)
				(curved_edges yes)
				(filter_ratio 0.9)
				(enabled yes)
				(allow_two_segments yes)
				(prefer_zone_connections yes)
			)
		)
		(pad "2" smd rect
			(at 1.15 -7.57 270)
			(size 0.7 1.9)
			(layers "F.Cu" "F.Mask" "F.Paste")
			(net 333 "/Com Express 7 Interfaces/SDIO.DAT3")
			(pinfunction "DAT3/CD")
			(pintype "bidirectional")
			(teardrops
				(best_length_ratio 0.2)
				(max_length 1)
				(best_width_ratio 0.9)
				(max_width 2)
				(curved_edges yes)
				(filter_ratio 0.9)
				(enabled yes)
				(allow_two_segments yes)
				(prefer_zone_connections yes)
			)
		)
		(pad "3" smd rect
			(at 0.05 -7.57 270)
			(size 0.7 1.9)
			(layers "F.Cu" "F.Mask" "F.Paste")
			(net 385 "/Com Express 7 Interfaces/SDIO.CMD")
			(pinfunction "CMD")
			(pintype "input")
			(teardrops
				(best_length_ratio 0.2)
				(max_length 1)
				(best_width_ratio 0.9)
				(max_width 2)
				(curved_edges yes)
				(filter_ratio 0.9)
				(enabled yes)
				(allow_two_segments yes)
				(prefer_zone_connections yes)
			)
		)
		(pad "4" smd rect
			(at -1.05 -7.57 270)
			(size 0.7 1.9)
			(layers "F.Cu" "F.Mask" "F.Paste")
			(net 2 "+3V3")
			(pinfunction "VDD")
			(pintype "power_in")
			(teardrops
				(best_length_ratio 0.2)
				(max_length 1)
				(best_width_ratio 0.9)
				(max_width 2)
				(curved_edges yes)
				(filter_ratio 0.9)
				(enabled yes)
				(allow_two_segments yes)
				(prefer_zone_connections yes)
			)
		)
		(pad "5" smd rect
			(at -2.15 -7.57 270)
			(size 0.7 1.9)
			(layers "F.Cu" "F.Mask" "F.Paste")
			(net 339 "/Com Express 7 Interfaces/SDIO.CLK")
			(pinfunction "CLK")
			(pintype "input")
			(teardrops
				(best_length_ratio 0.2)
				(max_length 1)
				(best_width_ratio 0.9)
				(max_width 2)
				(curved_edges yes)
				(filter_ratio 0.9)
				(enabled yes)
				(allow_two_segments yes)
				(prefer_zone_connections yes)
			)
		)
		(pad "6" smd rect
			(at -3.25 -7.57 270)
			(size 0.7 1.9)
			(layers "F.Cu" "F.Mask" "F.Paste")
			(net 1 "GND")
			(pinfunction "VSS")
			(pintype "passive")
			(teardrops
				(best_length_ratio 0.2)
				(max_length 1)
				(best_width_ratio 0.9)
				(max_width 2)
				(curved_edges yes)
				(filter_ratio 0.9)
				(enabled yes)
				(allow_two_segments yes)
				(prefer_zone_connections yes)
			)
		)
		(pad "7" smd rect
			(at -4.35 -7.57 270)
			(size 0.7 1.9)
			(layers "F.Cu" "F.Mask" "F.Paste")
			(net 321 "/Com Express 7 Interfaces/SDIO.DAT0")
			(pinfunction "DAT0")
			(pintype "input")
			(teardrops
				(best_length_ratio 0.2)
				(max_length 1)
				(best_width_ratio 0.9)
				(max_width 2)
				(curved_edges yes)
				(filter_ratio 0.9)
				(enabled yes)
				(allow_two_segments yes)
				(prefer_zone_connections yes)
			)
		)
		(pad "8" smd rect
			(at -5.45 -7.57 270)
			(size 0.7 1.9)
			(layers "F.Cu" "F.Mask" "F.Paste")
			(net 322 "/Com Express 7 Interfaces/SDIO.DAT1")
			(pinfunction "DAT1")
			(pintype "input")
			(teardrops
				(best_length_ratio 0.2)
				(max_length 1)
				(best_width_ratio 0.9)
				(max_width 2)
				(curved_edges yes)
				(filter_ratio 0.9)
				(enabled yes)
				(allow_two_segments yes)
				(prefer_zone_connections yes)
			)
		)
		(pad "9" smd rect
			(at -6.55 -7.57 270)
			(size 0.7 1.9)
			(layers "F.Cu" "F.Mask" "F.Paste")
			(net 531 "/Com Express 7 Interfaces/SD_CD")
			(pinfunction "CD_SW1")
			(pintype "passive")
			(teardrops
				(best_length_ratio 0.2)
				(max_length 1)
				(best_width_ratio 0.9)
				(max_width 2)
				(curved_edges yes)
				(filter_ratio 0.9)
				(enabled yes)
				(allow_two_segments yes)
				(prefer_zone_connections yes)
			)
		)
		(pad "SH" smd rect
			(at -8.1 -6.515 270)
			(size 1.7 1.8)
			(layers "F.Cu" "F.Mask" "F.Paste")
			(net 1 "GND")
			(pinfunction "SH")
			(pintype "passive")
			(teardrops
				(best_length_ratio 0.2)
				(max_length 1)
				(best_width_ratio 0.9)
				(max_width 2)
				(curved_edges yes)
				(filter_ratio 0.9)
				(enabled yes)
				(allow_two_segments yes)
				(prefer_zone_connections yes)
			)
		)
		(pad "SH" smd rect
			(at -7.85 3.08 270)
			(size 1.4 2.6)
			(layers "F.Cu" "F.Mask" "F.Paste")
			(net 1 "GND")
			(pinfunction "SH")
			(pintype "passive")
			(teardrops
				(best_length_ratio 0.2)
				(max_length 1)
				(best_width_ratio 0.9)
				(max_width 2)
				(curved_edges yes)
				(filter_ratio 0.9)
				(enabled yes)
				(allow_two_segments yes)
				(prefer_zone_connections yes)
			)
		)
		(pad "SH" smd rect
			(at 7.4 -6.515 270)
			(size 1.7 1.8)
			(layers "F.Cu" "F.Mask" "F.Paste")
			(net 1 "GND")
			(pinfunction "SH")
			(pintype "passive")
			(teardrops
				(best_length_ratio 0.2)
				(max_length 1)
				(best_width_ratio 0.9)
				(max_width 2)
				(curved_edges yes)
				(filter_ratio 0.9)
				(enabled yes)
				(allow_two_segments yes)
				(prefer_zone_connections yes)
			)
		)
		(pad "SH" smd rect
			(at 7.85 3.08 270)
			(size 1.4 2.6)
			(layers "F.Cu" "F.Mask" "F.Paste")
			(net 1 "GND")
			(pinfunction "SH")
			(pintype "passive")
			(teardrops
				(best_length_ratio 0.2)
				(max_length 1)
				(best_width_ratio 0.9)
				(max_width 2)
				(curved_edges yes)
				(filter_ratio 0.9)
				(enabled yes)
				(allow_two_segments yes)
				(prefer_zone_connections yes)
			)
		)
	)
	(footprint "antmicro-footprints:R_0402_1005Metric"
		(layer "F.Cu")
		(at 178.4 144 180)
		(descr "Resistor SMD 0402")
		(tags "resistor SMD 0402")
		(property "Reference" "R40"
			(at -2.95 -0.45 0)
			(layer "F.SilkS")
			(effects
				(font
					(size 0.7 0.7)
					(thickness 0.15)
				)
				(justify right bottom)
			)
		)
		(property "Value" "R_0R_0402"
			(at -1.011843 1.772046 0)
			(layer "F.Fab")
			(effects
				(font
					(size 0.7 0.7)
					(thickness 0.15)
				)
				(justify right bottom)
			)
		)
		(property "Datasheet" "https://industrial.panasonic.com/cdbs/www-data/pdf/RDA0000/AOA0000C301.pdf"
			(at 0 0 0)
			(layer "F.Fab")
			(hide yes)
			(effects
				(font
					(size 1.27 1.27)
					(thickness 0.15)
				)
			)
		)
		(property "Author" "Antmicro"
			(at 337.9 330.52 0)
			(layer "F.Fab")
			(hide yes)
			(effects
				(font
					(size 1 1)
					(thickness 0.15)
				)
			)
		)
		(property "Current" "1A"
			(at 337.9 330.52 0)
			(layer "F.Fab")
			(hide yes)
			(effects
				(font
					(size 1 1)
					(thickness 0.15)
				)
			)
		)
		(property "License" "Apache-2.0"
			(at 337.9 330.52 0)
			(layer "F.Fab")
			(hide yes)
			(effects
				(font
					(size 1 1)
					(thickness 0.15)
				)
			)
		)
		(property "MPN" "ERJ2GE0R00X"
			(at 337.9 330.52 0)
			(layer "F.Fab")
			(hide yes)
			(effects
				(font
					(size 1 1)
					(thickness 0.15)
				)
			)
		)
		(property "Manufacturer" "Panasonic"
			(at 337.9 330.52 0)
			(layer "F.Fab")
			(hide yes)
			(effects
				(font
					(size 1 1)
					(thickness 0.15)
				)
			)
		)
		(property "Public" "False"
			(at 337.9 330.52 0)
			(layer "F.Fab")
			(hide yes)
			(effects
				(font
					(size 1 1)
					(thickness 0.15)
				)
			)
		)
		(property "Tolerance" ""
			(at 337.9 330.52 0)
			(layer "F.Fab")
			(hide yes)
			(effects
				(font
					(size 1 1)
					(thickness 0.15)
				)
			)
		)
		(property "Val" "0R"
			(at 337.9 330.52 0)
			(layer "F.Fab")
			(hide yes)
			(effects
				(font
					(size 1 1)
					(thickness 0.15)
				)
			)
		)
		(sheetname "2xSFP+")
		(sheetfile "2xSFP+.kicad_sch")
		(attr smd)
		(fp_rect
			(start -0.925 -0.47)
			(end 0.925 0.47)
			(stroke
				(width 0.05)
				(type default)
			)
			(fill no)
			(layer "F.CrtYd")
		)
		(fp_rect
			(start -0.5 -0.25)
			(end 0.5 0.25)
			(stroke
				(width 0.15)
				(type solid)
			)
			(fill no)
			(layer "F.Fab")
		)
		(pad "1" smd roundrect
			(at -0.48 0 180)
			(size 0.59 0.64)
			(layers "F.Cu" "F.Mask" "F.Paste")
			(roundrect_rratio 0.25)
			(net 424 "/2xSFP+/I2C_{SFP1}.SDA")
			(pintype "passive")
			(teardrops
				(best_length_ratio 0.2)
				(max_length 1)
				(best_width_ratio 0.9)
				(max_width 2)
				(curved_edges yes)
				(filter_ratio 0.9)
				(enabled yes)
				(allow_two_segments yes)
				(prefer_zone_connections yes)
			)
		)
		(pad "2" smd roundrect
			(at 0.48 0 180)
			(size 0.59 0.64)
			(layers "F.Cu" "F.Mask" "F.Paste")
			(roundrect_rratio 0.25)
			(net 874 "/2xSFP+/SDA1")
			(pintype "passive")
			(teardrops
				(best_length_ratio 0.2)
				(max_length 1)
				(best_width_ratio 0.9)
				(max_width 2)
				(curved_edges yes)
				(filter_ratio 0.9)
				(enabled yes)
				(allow_two_segments yes)
				(prefer_zone_connections yes)
			)
		)
	)
	(footprint "antmicro-footprints:LED_0603_1608Metric_G"
		(layer "F.Cu")
		(at 116.45 69.86 90)
		(descr "LED SMD 0603 Green")
		(tags "LED SMD 0603 Green")
		(property "Reference" "D15"
			(at -3.35 0.4 90)
			(layer "F.SilkS")
			(effects
				(font
					(size 0.7 0.7)
					(thickness 0.15)
				)
				(justify left bottom)
			)
		)
		(property "Value" "LED_G_0603_LTST-C190GKT"
			(at -0.001 1.599 90)
			(layer "F.Fab")
			(effects
				(font
					(size 0.7 0.7)
					(thickness 0.15)
				)
				(justify left bottom)
			)
		)
		(property "Datasheet" "https://media.digikey.com/pdf/Data%20Sheets/Lite-On%20PDFs/LTST-C190GKT.pdf"
			(at 0 0 90)
			(layer "F.Fab")
			(hide yes)
			(effects
				(font
					(size 1.27 1.27)
					(thickness 0.15)
				)
			)
		)
		(property "Author" "Antmicro"
			(at 186.31 -46.59 0)
			(layer "F.Fab")
			(hide yes)
			(effects
				(font
					(size 1 1)
					(thickness 0.15)
				)
			)
		)
		(property "Color" "Green"
			(at 186.31 -46.59 0)
			(layer "F.Fab")
			(hide yes)
			(effects
				(font
					(size 1 1)
					(thickness 0.15)
				)
			)
		)
		(property "License" "Apache-2.0"
			(at 186.31 -46.59 0)
			(layer "F.Fab")
			(hide yes)
			(effects
				(font
					(size 1 1)
					(thickness 0.15)
				)
			)
		)
		(property "MPN" "LTST-C190GKT"
			(at 186.31 -46.59 0)
			(layer "F.Fab")
			(hide yes)
			(effects
				(font
					(size 1 1)
					(thickness 0.15)
				)
			)
		)
		(property "Manufacturer" "Lite-On"
			(at 186.31 -46.59 0)
			(layer "F.Fab")
			(hide yes)
			(effects
				(font
					(size 1 1)
					(thickness 0.15)
				)
			)
		)
		(property "Public" "False"
			(at 186.31 -46.59 0)
			(layer "F.Fab")
			(hide yes)
			(effects
				(font
					(size 1 1)
					(thickness 0.15)
				)
			)
		)
		(sheetname "M.2 key E")
		(sheetfile "m2keye.kicad_sch")
		(attr smd)
		(fp_line
			(start 0.22 -0.35)
			(end -0.22 -0.35)
			(stroke
				(width 0.15)
				(type solid)
			)
			(layer "F.SilkS")
		)
		(fp_line
			(start -1.18 -0.319)
			(end -1.18 0.321)
			(stroke
				(width 0.15)
				(type solid)
			)
			(layer "F.SilkS")
		)
		(fp_line
			(start 0.105328 0.001008)
			(end 0.24 0.001)
			(stroke
				(width 0.1)
				(type solid)
			)
			(layer "F.SilkS")
		)
		(fp_line
			(start -0.094672 0.001008)
			(end 0.105328 -0.198992)
			(stroke
				(width 0.1)
				(type solid)
			)
			(layer "F.SilkS")
		)
		(fp_line
			(start -0.094672 0.001008)
			(end -0.24 0.001008)
			(stroke
				(width 0.1)
				(type solid)
			)
			(layer "F.SilkS")
		)
		(fp_line
			(start 0.105328 0.201008)
			(end 0.105328 -0.198992)
			(stroke
				(width 0.1)
				(type solid)
			)
			(layer "F.SilkS")
		)
		(fp_line
			(start 0.105328 0.201008)
			(end -0.094672 0.001008)
			(stroke
				(width 0.1)
				(type solid)
			)
			(layer "F.SilkS")
		)
		(fp_line
			(start -0.094672 0.201008)
			(end -0.094672 -0.198992)
			(stroke
				(width 0.1)
				(type solid)
			)
			(layer "F.SilkS")
		)
		(fp_line
			(start 0.22 0.35)
			(end -0.22 0.35)
			(stroke
				(width 0.15)
				(type solid)
			)
			(layer "F.SilkS")
		)
		(fp_rect
			(start 1.25 0.65)
			(end -1.25 -0.65)
			(stroke
				(width 0.05)
				(type solid)
			)
			(fill no)
			(layer "F.CrtYd")
		)
		(fp_line
			(start 0.201 -0.202)
			(end -0.101 0)
			(stroke
				(width 0.15)
				(type solid)
			)
			(layer "F.Fab")
		)
		(fp_line
			(start -0.199 -0.202)
			(end -0.199 0.1)
			(stroke
				(width 0.15)
				(type solid)
			)
			(layer "F.Fab")
		)
		(fp_line
			(start 0.599 0)
			(end 0.201 0)
			(stroke
				(width 0.15)
				(type solid)
			)
			(layer "F.Fab")
		)
		(fp_line
			(start 0.201 0)
			(end 0.201 -0.202)
			(stroke
				(width 0.15)
				(type solid)
			)
			(layer "F.Fab")
		)
		(fp_line
			(start -0.101 0)
			(end 0.201 0.2)
			(stroke
				(width 0.15)
				(type solid)
			)
			(layer "F.Fab")
		)
		(fp_line
			(start -0.199 0)
			(end -0.597 0)
			(stroke
				(width 0.15)
				(type solid)
			)
			(layer "F.Fab")
		)
		(fp_line
			(start 0.201 0.2)
			(end 0.201 0)
			(stroke
				(width 0.15)
				(type solid)
			)
			(layer "F.Fab")
		)
		(fp_line
			(start -0.199 0.2)
			(end -0.199 0.1)
			(stroke
				(width 0.15)
				(type solid)
			)
			(layer "F.Fab")
		)
		(fp_rect
			(start 0.848 0.4)
			(end -0.85 -0.402)
			(stroke
				(width 0.15)
				(type solid)
			)
			(fill no)
			(layer "F.Fab")
		)
		(pad "1" smd roundrect
			(at -0.7 0 270)
			(size 0.8 1)
			(layers "F.Cu" "F.Mask" "F.Paste")
			(roundrect_rratio 0.2)
			(net 5 "/M.2 key E/~{LED_1}")
			(pinfunction "C")
			(pintype "passive")
			(teardrops
				(best_length_ratio 0.2)
				(max_length 1)
				(best_width_ratio 0.9)
				(max_width 2)
				(curved_edges yes)
				(filter_ratio 0.9)
				(enabled yes)
				(allow_two_segments yes)
				(prefer_zone_connections yes)
			)
		)
		(pad "2" smd roundrect
			(at 0.7 0 270)
			(size 0.8 1)
			(layers "F.Cu" "F.Mask" "F.Paste")
			(roundrect_rratio 0.2)
			(net 937 "Net-(D15-A)")
			(pinfunction "A")
			(pintype "passive")
			(teardrops
				(best_length_ratio 0.2)
				(max_length 1)
				(best_width_ratio 0.9)
				(max_width 2)
				(curved_edges yes)
				(filter_ratio 0.9)
				(enabled yes)
				(allow_two_segments yes)
				(prefer_zone_connections yes)
			)
		)
	)
	(footprint "antmicro-footprints:R_0402_1005Metric"
		(layer "F.Cu")
		(at 313.765499 97.4365 -90)
		(descr "Resistor SMD 0402")
		(tags "resistor SMD 0402")
		(property "Reference" "R109"
			(at -10.1265 -4.734501 90)
			(layer "F.SilkS")
			(effects
				(font
					(size 0.7 0.7)
					(thickness 0.15)
				)
				(justify right bottom)
			)
		)
		(property "Value" "R_110k_0402"
			(at -1.011843 1.772047 90)
			(layer "F.Fab")
			(effects
				(font
					(size 0.7 0.7)
					(thickness 0.15)
				)
				(justify right bottom)
			)
		)
		(property "Datasheet" "https://www.bourns.com/docs/product-datasheets/cr.pdf"
			(at 0 0 270)
			(layer "F.Fab")
			(hide yes)
			(effects
				(font
					(size 1.27 1.27)
					(thickness 0.15)
				)
			)
		)
		(property "Author" "Antmicro"
			(at 216.328999 411.201999 0)
			(layer "F.Fab")
			(hide yes)
			(effects
				(font
					(size 1 1)
					(thickness 0.15)
				)
			)
		)
		(property "License" "Apache-2.0"
			(at 216.328999 411.201999 0)
			(layer "F.Fab")
			(hide yes)
			(effects
				(font
					(size 1 1)
					(thickness 0.15)
				)
			)
		)
		(property "MPN" "CR0402-FX-1103GLF"
			(at 216.328999 411.201999 0)
			(layer "F.Fab")
			(hide yes)
			(effects
				(font
					(size 1 1)
					(thickness 0.15)
				)
			)
		)
		(property "Manufacturer" "Bourns"
			(at 216.328999 411.201999 0)
			(layer "F.Fab")
			(hide yes)
			(effects
				(font
					(size 1 1)
					(thickness 0.15)
				)
			)
		)
		(property "Public" "False"
			(at 216.328999 411.201999 0)
			(layer "F.Fab")
			(hide yes)
			(effects
				(font
					(size 1 1)
					(thickness 0.15)
				)
			)
		)
		(property "Tolerance" "1%"
			(at 216.328999 411.201999 0)
			(layer "F.Fab")
			(hide yes)
			(effects
				(font
					(size 1 1)
					(thickness 0.15)
				)
			)
		)
		(property "Val" "110k"
			(at 216.328999 411.201999 0)
			(layer "F.Fab")
			(hide yes)
			(effects
				(font
					(size 1 1)
					(thickness 0.15)
				)
			)
		)
		(sheetname "Power")
		(sheetfile "power.kicad_sch")
		(attr smd)
		(fp_rect
			(start -0.925 -0.47)
			(end 0.925 0.47)
			(stroke
				(width 0.05)
				(type default)
			)
			(fill no)
			(layer "F.CrtYd")
		)
		(fp_rect
			(start -0.5 -0.25)
			(end 0.5 0.25)
			(stroke
				(width 0.15)
				(type solid)
			)
			(fill no)
			(layer "F.Fab")
		)
		(pad "1" smd roundrect
			(at -0.48 0 270)
			(size 0.59 0.64)
			(layers "F.Cu" "F.Mask" "F.Paste")
			(roundrect_rratio 0.25)
			(net 585 "Net-(U21-FB)")
			(pintype "passive")
			(teardrops
				(best_length_ratio 0.2)
				(max_length 1)
				(best_width_ratio 0.9)
				(max_width 2)
				(curved_edges yes)
				(filter_ratio 0.9)
				(enabled yes)
				(allow_two_segments yes)
				(prefer_zone_connections yes)
			)
		)
		(pad "2" smd roundrect
			(at 0.48 0 270)
			(size 0.59 0.64)
			(layers "F.Cu" "F.Mask" "F.Paste")
			(roundrect_rratio 0.25)
			(net 75 "Net-(U50-IN+)")
			(pintype "passive")
			(teardrops
				(best_length_ratio 0.2)
				(max_length 1)
				(best_width_ratio 0.9)
				(max_width 2)
				(curved_edges yes)
				(filter_ratio 0.9)
				(enabled yes)
				(allow_two_segments yes)
				(prefer_zone_connections yes)
			)
		)
	)
	(footprint "antmicro-footprints:C_0402_1005Metric"
		(layer "F.Cu")
		(at 300.55 137.41 90)
		(descr "Capacitor SMD 0402")
		(tags "capacitor SMD 0402")
		(property "Reference" "C68"
			(at -1.1 -0.5 90)
			(layer "F.SilkS")
			(effects
				(font
					(size 0.7 0.7)
					(thickness 0.15)
				)
				(justify left bottom)
			)
		)
		(property "Value" "C_1u_0402"
			(at -1.022927 2.155213 90)
			(layer "F.Fab")
			(effects
				(font
					(size 0.7 0.7)
					(thickness 0.15)
				)
				(justify left bottom)
			)
		)
		(property "Datasheet" "https://product.tdk.com/en/search/capacitor/ceramic/mlcc/info?part_no=C1005X6S1A105K050BC"
			(at 0 0 90)
			(layer "F.Fab")
			(hide yes)
			(effects
				(font
					(size 1.27 1.27)
					(thickness 0.15)
				)
			)
		)
		(property "Author" "Antmicro"
			(at 437.96 -163.14 0)
			(layer "F.Fab")
			(hide yes)
			(effects
				(font
					(size 1 1)
					(thickness 0.15)
				)
			)
		)
		(property "Dielectric" ""
			(at 437.96 -163.14 0)
			(layer "F.Fab")
			(hide yes)
			(effects
				(font
					(size 1 1)
					(thickness 0.15)
				)
			)
		)
		(property "License" "Apache-2.0"
			(at 437.96 -163.14 0)
			(layer "F.Fab")
			(hide yes)
			(effects
				(font
					(size 1 1)
					(thickness 0.15)
				)
			)
		)
		(property "MPN" "C1005X6S1A105K050BC"
			(at 437.96 -163.14 0)
			(layer "F.Fab")
			(hide yes)
			(effects
				(font
					(size 1 1)
					(thickness 0.15)
				)
			)
		)
		(property "Manufacturer" "TDK"
			(at 437.96 -163.14 0)
			(layer "F.Fab")
			(hide yes)
			(effects
				(font
					(size 1 1)
					(thickness 0.15)
				)
			)
		)
		(property "Public" "False"
			(at 437.96 -163.14 0)
			(layer "F.Fab")
			(hide yes)
			(effects
				(font
					(size 1 1)
					(thickness 0.15)
				)
			)
		)
		(property "Val" "1u"
			(at 437.96 -163.14 0)
			(layer "F.Fab")
			(hide yes)
			(effects
				(font
					(size 1 1)
					(thickness 0.15)
				)
			)
		)
		(property "Voltage" ""
			(at 437.96 -163.14 0)
			(layer "F.Fab")
			(hide yes)
			(effects
				(font
					(size 1 1)
					(thickness 0.15)
				)
			)
		)
		(sheetname "Power")
		(sheetfile "power.kicad_sch")
		(attr smd)
		(fp_rect
			(start -0.925 -0.47)
			(end 0.925 0.47)
			(stroke
				(width 0.05)
				(type default)
			)
			(fill no)
			(layer "F.CrtYd")
		)
		(fp_line
			(start 0.504 -0.25)
			(end 0.504 0.248)
			(stroke
				(width 0.15)
				(type solid)
			)
			(layer "F.Fab")
		)
		(fp_line
			(start -0.494 -0.25)
			(end 0.504 -0.25)
			(stroke
				(width 0.15)
				(type solid)
			)
			(layer "F.Fab")
		)
		(fp_line
			(start 0.504 0.248)
			(end -0.494 0.248)
			(stroke
				(width 0.15)
				(type solid)
			)
			(layer "F.Fab")
		)
		(fp_line
			(start -0.494 0.248)
			(end -0.494 -0.25)
			(stroke
				(width 0.15)
				(type solid)
			)
			(layer "F.Fab")
		)
		(pad "1" smd roundrect
			(at -0.48 0 90)
			(size 0.59 0.64)
			(layers "F.Cu" "F.Mask" "F.Paste")
			(roundrect_rratio 0.25)
			(net 1 "GND")
			(pintype "passive")
			(teardrops
				(best_length_ratio 0.2)
				(max_length 1)
				(best_width_ratio 0.9)
				(max_width 2)
				(curved_edges yes)
				(filter_ratio 0.9)
				(enabled yes)
				(allow_two_segments yes)
				(prefer_zone_connections yes)
			)
		)
		(pad "2" smd roundrect
			(at 0.48 0 90)
			(size 0.59 0.64)
			(layers "F.Cu" "F.Mask" "F.Paste")
			(roundrect_rratio 0.25)
			(net 78 "+1V8")
			(pintype "passive")
			(teardrops
				(best_length_ratio 0.2)
				(max_length 1)
				(best_width_ratio 0.9)
				(max_width 2)
				(curved_edges yes)
				(filter_ratio 0.9)
				(enabled yes)
				(allow_two_segments yes)
				(prefer_zone_connections yes)
			)
		)
	)
	(footprint "antmicro-footprints:R_0402_1005Metric"
		(layer "F.Cu")
		(at 130.08 115.6 180)
		(descr "Resistor SMD 0402")
		(tags "resistor SMD 0402")
		(property "Reference" "R23"
			(at 0.780999 0.45 0)
			(layer "F.SilkS")
			(effects
				(font
					(size 0.7 0.7)
					(thickness 0.15)
				)
				(justify right top)
			)
		)
		(property "Value" "R_0R_0402"
			(at -1.011843 1.772046 0)
			(layer "F.Fab")
			(effects
				(font
					(size 0.7 0.7)
					(thickness 0.15)
				)
				(justify right top)
			)
		)
		(property "Datasheet" "https://industrial.panasonic.com/cdbs/www-data/pdf/RDA0000/AOA0000C301.pdf"
			(at 0 0 0)
			(layer "F.Fab")
			(hide yes)
			(effects
				(font
					(size 1.27 1.27)
					(thickness 0.15)
				)
			)
		)
		(property "Author" "Antmicro"
			(at 355.241 -59.058999 90)
			(layer "F.Fab")
			(hide yes)
			(effects
				(font
					(size 1 1)
					(thickness 0.15)
				)
			)
		)
		(property "Current" "1A"
			(at 355.241 -59.058999 90)
			(layer "F.Fab")
			(hide yes)
			(effects
				(font
					(size 1 1)
					(thickness 0.15)
				)
			)
		)
		(property "License" "Apache-2.0"
			(at 355.241 -59.058999 90)
			(layer "F.Fab")
			(hide yes)
			(effects
				(font
					(size 1 1)
					(thickness 0.15)
				)
			)
		)
		(property "MPN" "ERJ2GE0R00X"
			(at 355.241 -59.058999 90)
			(layer "F.Fab")
			(hide yes)
			(effects
				(font
					(size 1 1)
					(thickness 0.15)
				)
			)
		)
		(property "Manufacturer" "Panasonic"
			(at 355.241 -59.058999 90)
			(layer "F.Fab")
			(hide yes)
			(effects
				(font
					(size 1 1)
					(thickness 0.15)
				)
			)
		)
		(property "Public" "False"
			(at 355.241 -59.058999 90)
			(layer "F.Fab")
			(hide yes)
			(effects
				(font
					(size 1 1)
					(thickness 0.15)
				)
			)
		)
		(property "Tolerance" ""
			(at 355.241 -59.058999 90)
			(layer "F.Fab")
			(hide yes)
			(effects
				(font
					(size 1 1)
					(thickness 0.15)
				)
			)
		)
		(property "Val" "0R"
			(at 355.241 -59.058999 90)
			(layer "F.Fab")
			(hide yes)
			(effects
				(font
					(size 1 1)
					(thickness 0.15)
				)
			)
		)
		(sheetname "2xUSB3.0+RJ45")
		(sheetfile "usb3+rj45.kicad_sch")
		(attr smd)
		(fp_rect
			(start -0.925 -0.47)
			(end 0.925 0.47)
			(stroke
				(width 0.05)
				(type default)
			)
			(fill no)
			(layer "F.CrtYd")
		)
		(fp_rect
			(start -0.5 -0.25)
			(end 0.5 0.25)
			(stroke
				(width 0.15)
				(type solid)
			)
			(fill no)
			(layer "F.Fab")
		)
		(pad "1" smd roundrect
			(at -0.48 0 180)
			(size 0.59 0.64)
			(layers "F.Cu" "F.Mask" "F.Paste")
			(roundrect_rratio 0.25)
			(net 374 "/2xUSB3.0+RJ45/USB_2.D-")
			(pintype "passive")
			(teardrops
				(best_length_ratio 0.2)
				(max_length 1)
				(best_width_ratio 0.9)
				(max_width 2)
				(curved_edges yes)
				(filter_ratio 0.9)
				(enabled yes)
				(allow_two_segments yes)
				(prefer_zone_connections yes)
			)
		)
		(pad "2" smd roundrect
			(at 0.48 0 180)
			(size 0.59 0.64)
			(layers "F.Cu" "F.Mask" "F.Paste")
			(roundrect_rratio 0.25)
			(net 125 "/2xUSB3.0+RJ45/P2_D-")
			(pintype "passive")
			(teardrops
				(best_length_ratio 0.2)
				(max_length 1)
				(best_width_ratio 0.9)
				(max_width 2)
				(curved_edges yes)
				(filter_ratio 0.9)
				(enabled yes)
				(allow_two_segments yes)
				(prefer_zone_connections yes)
			)
		)
	)
	(footprint "antmicro-footprints:R_0402_1005Metric"
		(layer "F.Cu")
		(at 245.8 132.353999 -90)
		(descr "Resistor SMD 0402")
		(tags "resistor SMD 0402")
		(property "Reference" "R174"
			(at 0.856001 -0.4 90)
			(layer "F.SilkS")
			(effects
				(font
					(size 0.7 0.7)
					(thickness 0.15)
				)
				(justify right bottom)
			)
		)
		(property "Value" "R_0R_0402"
			(at -1.011843 1.772047 90)
			(layer "F.Fab")
			(effects
				(font
					(size 0.7 0.7)
					(thickness 0.15)
				)
				(justify right bottom)
			)
		)
		(property "Datasheet" "https://industrial.panasonic.com/cdbs/www-data/pdf/RDA0000/AOA0000C301.pdf"
			(at 0 0 270)
			(layer "F.Fab")
			(hide yes)
			(effects
				(font
					(size 1.27 1.27)
					(thickness 0.15)
				)
			)
		)
		(property "Author" "Antmicro"
			(at 113.446001 378.153999 0)
			(layer "F.Fab")
			(hide yes)
			(effects
				(font
					(size 1 1)
					(thickness 0.15)
				)
			)
		)
		(property "Current" "1A"
			(at 113.446001 378.153999 0)
			(layer "F.Fab")
			(hide yes)
			(effects
				(font
					(size 1 1)
					(thickness 0.15)
				)
			)
		)
		(property "License" "Apache-2.0"
			(at 113.446001 378.153999 0)
			(layer "F.Fab")
			(hide yes)
			(effects
				(font
					(size 1 1)
					(thickness 0.15)
				)
			)
		)
		(property "MPN" "ERJ2GE0R00X"
			(at 113.446001 378.153999 0)
			(layer "F.Fab")
			(hide yes)
			(effects
				(font
					(size 1 1)
					(thickness 0.15)
				)
			)
		)
		(property "Manufacturer" "Panasonic"
			(at 113.446001 378.153999 0)
			(layer "F.Fab")
			(hide yes)
			(effects
				(font
					(size 1 1)
					(thickness 0.15)
				)
			)
		)
		(property "Public" "False"
			(at 113.446001 378.153999 0)
			(layer "F.Fab")
			(hide yes)
			(effects
				(font
					(size 1 1)
					(thickness 0.15)
				)
			)
		)
		(property "Tolerance" ""
			(at 113.446001 378.153999 0)
			(layer "F.Fab")
			(hide yes)
			(effects
				(font
					(size 1 1)
					(thickness 0.15)
				)
			)
		)
		(property "Val" "0R"
			(at 113.446001 378.153999 0)
			(layer "F.Fab")
			(hide yes)
			(effects
				(font
					(size 1 1)
					(thickness 0.15)
				)
			)
		)
		(sheetname "Com Express 7 MGMT")
		(sheetfile "com_express_7_mgmt.kicad_sch")
		(attr smd)
		(fp_rect
			(start -0.925 -0.47)
			(end 0.925 0.47)
			(stroke
				(width 0.05)
				(type default)
			)
			(fill no)
			(layer "F.CrtYd")
		)
		(fp_rect
			(start -0.5 -0.25)
			(end 0.5 0.25)
			(stroke
				(width 0.15)
				(type solid)
			)
			(fill no)
			(layer "F.Fab")
		)
		(pad "1" smd roundrect
			(at -0.48 0 270)
			(size 0.59 0.64)
			(layers "F.Cu" "F.Mask" "F.Paste")
			(roundrect_rratio 0.25)
			(net 872 "Net-(U34-~{KILL})")
			(pintype "passive")
			(teardrops
				(best_length_ratio 0.2)
				(max_length 1)
				(best_width_ratio 0.9)
				(max_width 2)
				(curved_edges yes)
				(filter_ratio 0.9)
				(enabled yes)
				(allow_two_segments yes)
				(prefer_zone_connections yes)
			)
		)
		(pad "2" smd roundrect
			(at 0.48 0 270)
			(size 0.59 0.64)
			(layers "F.Cu" "F.Mask" "F.Paste")
			(roundrect_rratio 0.25)
			(net 303 "/Com Express 7 MGMT/~{SUS_S5}")
			(pintype "passive")
			(teardrops
				(best_length_ratio 0.2)
				(max_length 1)
				(best_width_ratio 0.9)
				(max_width 2)
				(curved_edges yes)
				(filter_ratio 0.9)
				(enabled yes)
				(allow_two_segments yes)
				(prefer_zone_connections yes)
			)
		)
	)
	(footprint "antmicro-footprints:C_0402_1005Metric"
		(layer "F.Cu")
		(at 193.902276 134.134199 135)
		(descr "Capacitor SMD 0402")
		(tags "capacitor SMD 0402")
		(property "Reference" "C136"
			(at 3.773458 -0.048138 135)
			(layer "F.SilkS")
			(effects
				(font
					(size 0.7 0.7)
					(thickness 0.15)
				)
				(justify left top)
			)
		)
		(property "Value" "C_100n_0402"
			(at -1.022927 2.155213 135)
			(layer "F.Fab")
			(effects
				(font
					(size 0.7 0.7)
					(thickness 0.15)
				)
				(justify left top)
			)
		)
		(property "Datasheet" "https://www.murata.com/products/productdetail?partno=GRM155R61H104KE14%23"
			(at 0 0 135)
			(layer "B.Fab")
			(hide yes)
			(effects
				(font
					(size 1.27 1.27)
					(thickness 0.15)
				)
				(justify mirror)
			)
		)
		(property "Author" "Antmicro"
			(at 322.014 53.288 45)
			(layer "F.Fab")
			(hide yes)
			(effects
				(font
					(size 1 1)
					(thickness 0.15)
				)
			)
		)
		(property "Dielectric" "X5R"
			(at 322.014 53.288 45)
			(layer "F.Fab")
			(hide yes)
			(effects
				(font
					(size 1 1)
					(thickness 0.15)
				)
			)
		)
		(property "License" "Apache-2.0"
			(at 322.014 53.288 45)
			(layer "F.Fab")
			(hide yes)
			(effects
				(font
					(size 1 1)
					(thickness 0.15)
				)
			)
		)
		(property "MPN" "GRM155R61H104KE14D"
			(at 322.014 53.288 45)
			(layer "F.Fab")
			(hide yes)
			(effects
				(font
					(size 1 1)
					(thickness 0.15)
				)
			)
		)
		(property "Manufacturer" "Murata"
			(at 322.014 53.288 45)
			(layer "F.Fab")
			(hide yes)
			(effects
				(font
					(size 1 1)
					(thickness 0.15)
				)
			)
		)
		(property "Public" "False"
			(at 322.014 53.288 45)
			(layer "F.Fab")
			(hide yes)
			(effects
				(font
					(size 1 1)
					(thickness 0.15)
				)
			)
		)
		(property "Val" "100n"
			(at 322.014 53.288 45)
			(layer "F.Fab")
			(hide yes)
			(effects
				(font
					(size 1 1)
					(thickness 0.15)
				)
			)
		)
		(property "Voltage" "50V"
			(at 322.014 53.288 45)
			(layer "F.Fab")
			(hide yes)
			(effects
				(font
					(size 1 1)
					(thickness 0.15)
				)
			)
		)
		(sheetname "PCIe redriver")
		(sheetfile "pcie_redriver.kicad_sch")
		(attr smd)
		(fp_poly
			(pts
				(xy -0.925 -0.47) (xy 0.925 -0.47) (xy 0.925 0.47) (xy -0.925 0.47)
			)
			(stroke
				(width 0.05)
				(type default)
			)
			(fill no)
			(layer "F.CrtYd")
		)
		(fp_line
			(start 0.504 -0.25)
			(end 0.504 0.248)
			(stroke
				(width 0.15)
				(type solid)
			)
			(layer "F.Fab")
		)
		(fp_line
			(start 0.504 0.248)
			(end -0.494 0.248)
			(stroke
				(width 0.15)
				(type solid)
			)
			(layer "F.Fab")
		)
		(fp_line
			(start -0.494 -0.25)
			(end 0.504 -0.25)
			(stroke
				(width 0.15)
				(type solid)
			)
			(layer "F.Fab")
		)
		(fp_line
			(start -0.494 0.248)
			(end -0.494 -0.25)
			(stroke
				(width 0.15)
				(type solid)
			)
			(layer "F.Fab")
		)
		(pad "1" smd roundrect
			(at -0.48 0 135)
			(size 0.59 0.64)
			(layers "F.Cu" "F.Mask" "F.Paste")
			(roundrect_rratio 0.25)
			(net 1 "GND")
			(pintype "passive")
			(teardrops
				(best_length_ratio 0.2)
				(max_length 1)
				(best_width_ratio 0.9)
				(max_width 2)
				(curved_edges yes)
				(filter_ratio 0.9)
				(enabled yes)
				(allow_two_segments yes)
				(prefer_zone_connections yes)
			)
		)
		(pad "2" smd roundrect
			(at 0.48 0 135)
			(size 0.59 0.64)
			(layers "F.Cu" "F.Mask" "F.Paste")
			(roundrect_rratio 0.25)
			(net 2 "+3V3")
			(pintype "passive")
			(teardrops
				(best_length_ratio 0.2)
				(max_length 1)
				(best_width_ratio 0.9)
				(max_width 2)
				(curved_edges yes)
				(filter_ratio 0.9)
				(enabled yes)
				(allow_two_segments yes)
				(prefer_zone_connections yes)
			)
		)
	)
	(footprint "antmicro-footprints:C_0402_1005Metric"
		(layer "F.Cu")
		(at 194.962937 133.073539 135)
		(descr "Capacitor SMD 0402")
		(tags "capacitor SMD 0402")
		(property "Reference" "C138"
			(at 3.773458 -0.558189 135)
			(layer "F.SilkS")
			(effects
				(font
					(size 0.7 0.7)
					(thickness 0.15)
				)
				(justify left top)
			)
		)
		(property "Value" "C_100n_0402"
			(at -1.022927 2.155213 135)
			(layer "F.Fab")
			(effects
				(font
					(size 0.7 0.7)
					(thickness 0.15)
				)
				(justify left top)
			)
		)
		(property "Datasheet" "https://www.murata.com/products/productdetail?partno=GRM155R61H104KE14%23"
			(at 0 0 135)
			(layer "B.Fab")
			(hide yes)
			(effects
				(font
					(size 1.27 1.27)
					(thickness 0.15)
				)
				(justify mirror)
			)
		)
		(property "Author" "Antmicro"
			(at 320.514 51.788 45)
			(layer "F.Fab")
			(hide yes)
			(effects
				(font
					(size 1 1)
					(thickness 0.15)
				)
			)
		)
		(property "Dielectric" "X5R"
			(at 320.514 51.788 45)
			(layer "F.Fab")
			(hide yes)
			(effects
				(font
					(size 1 1)
					(thickness 0.15)
				)
			)
		)
		(property "License" "Apache-2.0"
			(at 320.514 51.788 45)
			(layer "F.Fab")
			(hide yes)
			(effects
				(font
					(size 1 1)
					(thickness 0.15)
				)
			)
		)
		(property "MPN" "GRM155R61H104KE14D"
			(at 320.514 51.788 45)
			(layer "F.Fab")
			(hide yes)
			(effects
				(font
					(size 1 1)
					(thickness 0.15)
				)
			)
		)
		(property "Manufacturer" "Murata"
			(at 320.514 51.788 45)
			(layer "F.Fab")
			(hide yes)
			(effects
				(font
					(size 1 1)
					(thickness 0.15)
				)
			)
		)
		(property "Public" "False"
			(at 320.514 51.788 45)
			(layer "F.Fab")
			(hide yes)
			(effects
				(font
					(size 1 1)
					(thickness 0.15)
				)
			)
		)
		(property "Val" "100n"
			(at 320.514 51.788 45)
			(layer "F.Fab")
			(hide yes)
			(effects
				(font
					(size 1 1)
					(thickness 0.15)
				)
			)
		)
		(property "Voltage" "50V"
			(at 320.514 51.788 45)
			(layer "F.Fab")
			(hide yes)
			(effects
				(font
					(size 1 1)
					(thickness 0.15)
				)
			)
		)
		(sheetname "PCIe redriver")
		(sheetfile "pcie_redriver.kicad_sch")
		(attr smd)
		(fp_poly
			(pts
				(xy -0.925 -0.47) (xy 0.925 -0.47) (xy 0.925 0.47) (xy -0.925 0.47)
			)
			(stroke
				(width 0.05)
				(type default)
			)
			(fill no)
			(layer "F.CrtYd")
		)
		(fp_line
			(start 0.504 -0.25)
			(end 0.504 0.248)
			(stroke
				(width 0.15)
				(type solid)
			)
			(layer "F.Fab")
		)
		(fp_line
			(start 0.504 0.248)
			(end -0.494 0.248)
			(stroke
				(width 0.15)
				(type solid)
			)
			(layer "F.Fab")
		)
		(fp_line
			(start -0.494 -0.25)
			(end 0.504 -0.25)
			(stroke
				(width 0.15)
				(type solid)
			)
			(layer "F.Fab")
		)
		(fp_line
			(start -0.494 0.248)
			(end -0.494 -0.25)
			(stroke
				(width 0.15)
				(type solid)
			)
			(layer "F.Fab")
		)
		(pad "1" smd roundrect
			(at -0.48 0 135)
			(size 0.59 0.64)
			(layers "F.Cu" "F.Mask" "F.Paste")
			(roundrect_rratio 0.25)
			(net 1 "GND")
			(pintype "passive")
			(teardrops
				(best_length_ratio 0.2)
				(max_length 1)
				(best_width_ratio 0.9)
				(max_width 2)
				(curved_edges yes)
				(filter_ratio 0.9)
				(enabled yes)
				(allow_two_segments yes)
				(prefer_zone_connections yes)
			)
		)
		(pad "2" smd roundrect
			(at 0.48 0 135)
			(size 0.59 0.64)
			(layers "F.Cu" "F.Mask" "F.Paste")
			(roundrect_rratio 0.25)
			(net 2 "+3V3")
			(pintype "passive")
			(teardrops
				(best_length_ratio 0.2)
				(max_length 1)
				(best_width_ratio 0.9)
				(max_width 2)
				(curved_edges yes)
				(filter_ratio 0.9)
				(enabled yes)
				(allow_two_segments yes)
				(prefer_zone_connections yes)
			)
		)
	)
	(footprint "antmicro-footprints:C_0402_1005Metric"
		(layer "F.Cu")
		(at 231.270707 78.115 -90)
		(descr "Capacitor SMD 0402")
		(tags "capacitor SMD 0402")
		(property "Reference" "C88"
			(at -1.105 0.499999 90)
			(layer "F.SilkS")
			(effects
				(font
					(size 0.7 0.7)
					(thickness 0.15)
				)
				(justify right bottom)
			)
		)
		(property "Value" "C_100n_0402"
			(at -1.022927 2.155213 90)
			(layer "F.Fab")
			(effects
				(font
					(size 0.7 0.7)
					(thickness 0.15)
				)
				(justify right bottom)
			)
		)
		(property "Datasheet" "https://www.murata.com/products/productdetail?partno=GRM155R61H104KE14%23"
			(at 0 0 270)
			(layer "F.Fab")
			(hide yes)
			(effects
				(font
					(size 1.27 1.27)
					(thickness 0.15)
				)
			)
		)
		(property "Author" "Antmicro"
			(at 153.155707 309.385707 0)
			(layer "F.Fab")
			(hide yes)
			(effects
				(font
					(size 1 1)
					(thickness 0.15)
				)
			)
		)
		(property "Dielectric" "X5R"
			(at 153.155707 309.385707 0)
			(layer "F.Fab")
			(hide yes)
			(effects
				(font
					(size 1 1)
					(thickness 0.15)
				)
			)
		)
		(property "License" "Apache-2.0"
			(at 153.155707 309.385707 0)
			(layer "F.Fab")
			(hide yes)
			(effects
				(font
					(size 1 1)
					(thickness 0.15)
				)
			)
		)
		(property "MPN" "GRM155R61H104KE14D"
			(at 153.155707 309.385707 0)
			(layer "F.Fab")
			(hide yes)
			(effects
				(font
					(size 1 1)
					(thickness 0.15)
				)
			)
		)
		(property "Manufacturer" "Murata"
			(at 153.155707 309.385707 0)
			(layer "F.Fab")
			(hide yes)
			(effects
				(font
					(size 1 1)
					(thickness 0.15)
				)
			)
		)
		(property "Public" "False"
			(at 153.155707 309.385707 0)
			(layer "F.Fab")
			(hide yes)
			(effects
				(font
					(size 1 1)
					(thickness 0.15)
				)
			)
		)
		(property "Val" "100n"
			(at 153.155707 309.385707 0)
			(layer "F.Fab")
			(hide yes)
			(effects
				(font
					(size 1 1)
					(thickness 0.15)
				)
			)
		)
		(property "Voltage" "50V"
			(at 153.155707 309.385707 0)
			(layer "F.Fab")
			(hide yes)
			(effects
				(font
					(size 1 1)
					(thickness 0.15)
				)
			)
		)
		(sheetname "Misc")
		(sheetfile "misc.kicad_sch")
		(attr smd)
		(fp_rect
			(start -0.925 -0.47)
			(end 0.925 0.47)
			(stroke
				(width 0.05)
				(type default)
			)
			(fill no)
			(layer "F.CrtYd")
		)
		(fp_line
			(start -0.494 0.248)
			(end -0.494 -0.25)
			(stroke
				(width 0.15)
				(type solid)
			)
			(layer "F.Fab")
		)
		(fp_line
			(start 0.504 0.248)
			(end -0.494 0.248)
			(stroke
				(width 0.15)
				(type solid)
			)
			(layer "F.Fab")
		)
		(fp_line
			(start -0.494 -0.25)
			(end 0.504 -0.25)
			(stroke
				(width 0.15)
				(type solid)
			)
			(layer "F.Fab")
		)
		(fp_line
			(start 0.504 -0.25)
			(end 0.504 0.248)
			(stroke
				(width 0.15)
				(type solid)
			)
			(layer "F.Fab")
		)
		(pad "1" smd roundrect
			(at -0.48 0 270)
			(size 0.59 0.64)
			(layers "F.Cu" "F.Mask" "F.Paste")
			(roundrect_rratio 0.25)
			(net 1 "GND")
			(pintype "passive")
			(teardrops
				(best_length_ratio 0.2)
				(max_length 1)
				(best_width_ratio 0.9)
				(max_width 2)
				(curved_edges yes)
				(filter_ratio 0.9)
				(enabled yes)
				(allow_two_segments yes)
				(prefer_zone_connections yes)
			)
		)
		(pad "2" smd roundrect
			(at 0.48 0 270)
			(size 0.59 0.64)
			(layers "F.Cu" "F.Mask" "F.Paste")
			(roundrect_rratio 0.25)
			(net 2 "+3V3")
			(pintype "passive")
			(teardrops
				(best_length_ratio 0.2)
				(max_length 1)
				(best_width_ratio 0.9)
				(max_width 2)
				(curved_edges yes)
				(filter_ratio 0.9)
				(enabled yes)
				(allow_two_segments yes)
				(prefer_zone_connections yes)
			)
		)
	)
	(footprint "antmicro-footprints:Vishay_PowerPAK_1212-8_Single"
		(layer "F.Cu")
		(at 293.1 99.01 -90)
		(descr "PowerPAK 1212-8 Single")
		(tags "Vishay PowerPAK 1212-8 Single")
		(property "Reference" "Q4"
			(at -2.15 -1.95 0)
			(layer "F.SilkS")
			(effects
				(font
					(size 0.7 0.7)
					(thickness 0.15)
				)
				(justify right bottom)
			)
		)
		(property "Value" "SI7613DN-T1-GE3"
			(at 0 2.7 90)
			(layer "F.Fab")
			(effects
				(font
					(size 0.7 0.7)
					(thickness 0.15)
				)
				(justify right bottom)
			)
		)
		(property "Datasheet" "https://www.vishay.com/docs/64809/si7613dn.pdf"
			(at 0 0 270)
			(layer "F.Fab")
			(hide yes)
			(effects
				(font
					(size 1.27 1.27)
					(thickness 0.15)
				)
			)
		)
		(property "Author" "Antmicro"
			(at 194.09 392.11 0)
			(layer "F.Fab")
			(hide yes)
			(effects
				(font
					(size 1 1)
					(thickness 0.15)
				)
			)
		)
		(property "License" "Apache-2.0"
			(at 194.09 392.11 0)
			(layer "F.Fab")
			(hide yes)
			(effects
				(font
					(size 1 1)
					(thickness 0.15)
				)
			)
		)
		(property "MPN" "SI7613DN-T1-GE3"
			(at 194.09 392.11 0)
			(layer "F.Fab")
			(hide yes)
			(effects
				(font
					(size 1 1)
					(thickness 0.15)
				)
			)
		)
		(property "Manufacturer" "Vishay"
			(at 194.09 392.11 0)
			(layer "F.Fab")
			(hide yes)
			(effects
				(font
					(size 1 1)
					(thickness 0.15)
				)
			)
		)
		(sheetname "Power")
		(sheetfile "power.kicad_sch")
		(attr smd)
		(fp_line
			(start -1.635 1.634)
			(end 1.634 1.634)
			(stroke
				(width 0.15)
				(type solid)
			)
			(layer "F.SilkS")
		)
		(fp_line
			(start -1.635 1.3)
			(end -1.635 1.634)
			(stroke
				(width 0.15)
				(type solid)
			)
			(layer "F.SilkS")
		)
		(fp_line
			(start 1.634 1.3)
			(end 1.634 1.634)
			(stroke
				(width 0.15)
				(type solid)
			)
			(layer "F.SilkS")
		)
		(fp_line
			(start -1.651 -1.651)
			(end -1.651 -1.317)
			(stroke
				(width 0.15)
				(type solid)
			)
			(layer "F.SilkS")
		)
		(fp_line
			(start -1.651 -1.651)
			(end 1.648 -1.651)
			(stroke
				(width 0.15)
				(type solid)
			)
			(layer "F.SilkS")
		)
		(fp_line
			(start 1.648 -1.651)
			(end 1.648 -1.317)
			(stroke
				(width 0.15)
				(type solid)
			)
			(layer "F.SilkS")
		)
		(fp_circle
			(center -1.9 -1.4)
			(end -1.85 -1.4)
			(stroke
				(width 0.15)
				(type solid)
			)
			(fill yes)
			(layer "F.SilkS")
		)
		(fp_rect
			(start -2 -1.8)
			(end 2 1.798)
			(stroke
				(width 0.05)
				(type solid)
			)
			(fill no)
			(layer "F.CrtYd")
		)
		(fp_line
			(start -1.6425 -1.4175)
			(end -1.4175 -1.6425)
			(stroke
				(width 0.15)
				(type solid)
			)
			(layer "F.Fab")
		)
		(fp_rect
			(start -1.651 -1.651)
			(end 1.648 1.648)
			(stroke
				(width 0.15)
				(type solid)
			)
			(fill no)
			(layer "F.Fab")
		)
		(pad "1" smd rect
			(at -1.436 -0.99 270)
			(size 0.99 0.405)
			(layers "F.Cu" "F.Mask" "F.Paste")
			(net 77 "+5V_AON")
			(pinfunction "S")
			(pintype "passive")
			(teardrops
				(best_length_ratio 0.2)
				(max_length 1)
				(best_width_ratio 0.9)
				(max_width 2)
				(curved_edges yes)
				(filter_ratio 0.9)
				(enabled yes)
				(allow_two_segments yes)
				(prefer_zone_connections yes)
			)
		)
		(pad "2" smd rect
			(at -1.436 -0.332 270)
			(size 0.99 0.405)
			(layers "F.Cu" "F.Mask" "F.Paste")
			(net 77 "+5V_AON")
			(pinfunction "S")
			(pintype "passive")
			(teardrops
				(best_length_ratio 0.2)
				(max_length 1)
				(best_width_ratio 0.9)
				(max_width 2)
				(curved_edges yes)
				(filter_ratio 0.9)
				(enabled yes)
				(allow_two_segments yes)
				(prefer_zone_connections yes)
			)
		)
		(pad "3" smd rect
			(at -1.436 0.33 270)
			(size 0.99 0.405)
			(layers "F.Cu" "F.Mask" "F.Paste")
			(net 77 "+5V_AON")
			(pinfunction "S")
			(pintype "passive")
			(teardrops
				(best_length_ratio 0.2)
				(max_length 1)
				(best_width_ratio 0.9)
				(max_width 2)
				(curved_edges yes)
				(filter_ratio 0.9)
				(enabled yes)
				(allow_two_segments yes)
				(prefer_zone_connections yes)
			)
		)
		(pad "4" smd rect
			(at -1.436 0.988 270)
			(size 0.99 0.405)
			(layers "F.Cu" "F.Mask" "F.Paste")
			(net 536 "Net-(Q3-D)")
			(pinfunction "G")
			(pintype "passive")
			(teardrops
				(best_length_ratio 0.2)
				(max_length 1)
				(best_width_ratio 0.9)
				(max_width 2)
				(curved_edges yes)
				(filter_ratio 0.9)
				(enabled yes)
				(allow_two_segments yes)
				(prefer_zone_connections yes)
			)
		)
		(pad "5" smd custom
			(at 0.557 0 270)
			(size 1.725 2.235)
			(layers "F.Cu" "F.Mask" "F.Paste")
			(net 52 "+5V")
			(pinfunction "D")
			(pintype "passive")
			(zone_connect 2)
			(options
				(clearance outline)
				(anchor rect)
			)
			(primitives
				(gr_poly
					(pts
						(xy 0.8625 0.1275) (xy 0.8625 -0.1275) (xy 1.3725 -0.1275) (xy 1.3725 -0.5325) (xy 0.8625 -0.5325)
						(xy 0.8625 -0.7875) (xy 1.3725 -0.7875) (xy 1.3725 -1.195) (xy 0.6125 -1.195) (xy 0.6125 1.195)
						(xy 1.3725 1.195) (xy 1.3725 0.7875) (xy 0.8625 0.7875) (xy 0.8625 0.5325) (xy 1.3725 0.5325)
						(xy 1.3725 0.1275)
					)
					(width 0)
					(fill yes)
				)
			)
			(teardrops
				(best_length_ratio 0.2)
				(max_length 1)
				(best_width_ratio 0.9)
				(max_width 2)
				(curved_edges yes)
				(filter_ratio 0.9)
				(enabled yes)
				(allow_two_segments yes)
				(prefer_zone_connections yes)
			)
		)
	)
	(footprint "antmicro-footprints:LED_0603_1608Metric_G"
		(layer "F.Cu")
		(at 199.70861 74.802163 90)
		(descr "LED SMD 0603 Green")
		(tags "LED SMD 0603 Green")
		(property "Reference" "D27"
			(at -1.1 -0.55 90)
			(layer "F.SilkS")
			(effects
				(font
					(size 0.7 0.7)
					(thickness 0.15)
				)
				(justify left bottom)
			)
		)
		(property "Value" "LED_G_0603_LTST-C190GKT"
			(at -0.001 1.599 90)
			(layer "F.Fab")
			(effects
				(font
					(size 0.7 0.7)
					(thickness 0.15)
				)
				(justify left bottom)
			)
		)
		(property "Datasheet" "https://media.digikey.com/pdf/Data%20Sheets/Lite-On%20PDFs/LTST-C190GKT.pdf"
			(at 0 0 90)
			(layer "F.Fab")
			(hide yes)
			(effects
				(font
					(size 1.27 1.27)
					(thickness 0.15)
				)
			)
		)
		(property "Author" "Antmicro"
			(at 274.510773 -124.906447 0)
			(layer "F.Fab")
			(hide yes)
			(effects
				(font
					(size 1 1)
					(thickness 0.15)
				)
			)
		)
		(property "Color" "Green"
			(at 274.510773 -124.906447 0)
			(layer "F.Fab")
			(hide yes)
			(effects
				(font
					(size 1 1)
					(thickness 0.15)
				)
			)
		)
		(property "License" "Apache-2.0"
			(at 274.510773 -124.906447 0)
			(layer "F.Fab")
			(hide yes)
			(effects
				(font
					(size 1 1)
					(thickness 0.15)
				)
			)
		)
		(property "MPN" "LTST-C190GKT"
			(at 274.510773 -124.906447 0)
			(layer "F.Fab")
			(hide yes)
			(effects
				(font
					(size 1 1)
					(thickness 0.15)
				)
			)
		)
		(property "Manufacturer" "Lite-On"
			(at 274.510773 -124.906447 0)
			(layer "F.Fab")
			(hide yes)
			(effects
				(font
					(size 1 1)
					(thickness 0.15)
				)
			)
		)
		(property "Public" "False"
			(at 274.510773 -124.906447 0)
			(layer "F.Fab")
			(hide yes)
			(effects
				(font
					(size 1 1)
					(thickness 0.15)
				)
			)
		)
		(sheetname "Power")
		(sheetfile "power.kicad_sch")
		(attr smd)
		(fp_line
			(start 0.22 -0.35)
			(end -0.22 -0.35)
			(stroke
				(width 0.15)
				(type solid)
			)
			(layer "F.SilkS")
		)
		(fp_line
			(start -1.18 -0.319)
			(end -1.18 0.321)
			(stroke
				(width 0.15)
				(type solid)
			)
			(layer "F.SilkS")
		)
		(fp_line
			(start 0.105328 0.001008)
			(end 0.24 0.001)
			(stroke
				(width 0.1)
				(type solid)
			)
			(layer "F.SilkS")
		)
		(fp_line
			(start -0.094672 0.001008)
			(end 0.105328 -0.198992)
			(stroke
				(width 0.1)
				(type solid)
			)
			(layer "F.SilkS")
		)
		(fp_line
			(start -0.094672 0.001008)
			(end -0.24 0.001008)
			(stroke
				(width 0.1)
				(type solid)
			)
			(layer "F.SilkS")
		)
		(fp_line
			(start 0.105328 0.201008)
			(end 0.105328 -0.198992)
			(stroke
				(width 0.1)
				(type solid)
			)
			(layer "F.SilkS")
		)
		(fp_line
			(start 0.105328 0.201008)
			(end -0.094672 0.001008)
			(stroke
				(width 0.1)
				(type solid)
			)
			(layer "F.SilkS")
		)
		(fp_line
			(start -0.094672 0.201008)
			(end -0.094672 -0.198992)
			(stroke
				(width 0.1)
				(type solid)
			)
			(layer "F.SilkS")
		)
		(fp_line
			(start 0.22 0.35)
			(end -0.22 0.35)
			(stroke
				(width 0.15)
				(type solid)
			)
			(layer "F.SilkS")
		)
		(fp_rect
			(start 1.25 0.65)
			(end -1.25 -0.65)
			(stroke
				(width 0.05)
				(type solid)
			)
			(fill no)
			(layer "F.CrtYd")
		)
		(fp_line
			(start 0.201 -0.202)
			(end -0.101 0)
			(stroke
				(width 0.15)
				(type solid)
			)
			(layer "F.Fab")
		)
		(fp_line
			(start -0.199 -0.202)
			(end -0.199 0.1)
			(stroke
				(width 0.15)
				(type solid)
			)
			(layer "F.Fab")
		)
		(fp_line
			(start 0.599 0)
			(end 0.201 0)
			(stroke
				(width 0.15)
				(type solid)
			)
			(layer "F.Fab")
		)
		(fp_line
			(start 0.201 0)
			(end 0.201 -0.202)
			(stroke
				(width 0.15)
				(type solid)
			)
			(layer "F.Fab")
		)
		(fp_line
			(start -0.101 0)
			(end 0.201 0.2)
			(stroke
				(width 0.15)
				(type solid)
			)
			(layer "F.Fab")
		)
		(fp_line
			(start -0.199 0)
			(end -0.597 0)
			(stroke
				(width 0.15)
				(type solid)
			)
			(layer "F.Fab")
		)
		(fp_line
			(start 0.201 0.2)
			(end 0.201 0)
			(stroke
				(width 0.15)
				(type solid)
			)
			(layer "F.Fab")
		)
		(fp_line
			(start -0.199 0.2)
			(end -0.199 0.1)
			(stroke
				(width 0.15)
				(type solid)
			)
			(layer "F.Fab")
		)
		(fp_rect
			(start 0.848 0.4)
			(end -0.85 -0.402)
			(stroke
				(width 0.15)
				(type solid)
			)
			(fill no)
			(layer "F.Fab")
		)
		(pad "1" smd roundrect
			(at -0.7 0 270)
			(size 0.8 1)
			(layers "F.Cu" "F.Mask" "F.Paste")
			(roundrect_rratio 0.2)
			(net 980 "Net-(D27-C)")
			(pinfunction "C")
			(pintype "passive")
			(teardrops
				(best_length_ratio 0.2)
				(max_length 1)
				(best_width_ratio 0.9)
				(max_width 2)
				(curved_edges yes)
				(filter_ratio 0.9)
				(enabled yes)
				(allow_two_segments yes)
				(prefer_zone_connections yes)
			)
		)
		(pad "2" smd roundrect
			(at 0.7 0 270)
			(size 0.8 1)
			(layers "F.Cu" "F.Mask" "F.Paste")
			(roundrect_rratio 0.2)
			(net 62 "+12V_AON")
			(pinfunction "A")
			(pintype "passive")
			(teardrops
				(best_length_ratio 0.2)
				(max_length 1)
				(best_width_ratio 0.9)
				(max_width 2)
				(curved_edges yes)
				(filter_ratio 0.9)
				(enabled yes)
				(allow_two_segments yes)
				(prefer_zone_connections yes)
			)
		)
	)
	(footprint "antmicro-footprints:Spacer_Drill3.7mm_H5mm_9774050151R"
		(layer "F.Cu")
		(at 161.93 167.8 90)
		(descr "Spacer M=3 h=5mm fi=5.1mm")
		(property "Reference" "H6"
			(at 0 -3.2 90)
			(layer "F.SilkS")
			(hide yes)
			(effects
				(font
					(size 0.7 0.7)
					(thickness 0.15)
				)
				(justify left bottom)
			)
		)
		(property "Value" "Spacer_Drill3.7mm_H5mm_9774050151R"
			(at 0 4 90)
			(layer "F.Fab")
			(effects
				(font
					(size 0.7 0.7)
					(thickness 0.15)
				)
				(justify left bottom)
			)
		)
		(property "Datasheet" "https://www.we-online.com/catalog/datasheet/9774050151.pdf"
			(at 0 0 90)
			(layer "F.Fab")
			(hide yes)
			(effects
				(font
					(size 1.27 1.27)
					(thickness 0.15)
				)
			)
		)
		(property "Author" "Antmicro"
			(at 329.73 5.87 0)
			(layer "F.Fab")
			(hide yes)
			(effects
				(font
					(size 1 1)
					(thickness 0.15)
				)
			)
		)
		(property "License" "Apache-2.0"
			(at 329.73 5.87 0)
			(layer "F.Fab")
			(hide yes)
			(effects
				(font
					(size 1 1)
					(thickness 0.15)
				)
			)
		)
		(property "MPN" "9774050151R"
			(at 329.73 5.87 0)
			(layer "F.Fab")
			(hide yes)
			(effects
				(font
					(size 1 1)
					(thickness 0.15)
				)
			)
		)
		(property "Manufacturer" "Würth Elektronik"
			(at 329.73 5.87 0)
			(layer "F.Fab")
			(hide yes)
			(effects
				(font
					(size 1 1)
					(thickness 0.15)
				)
			)
		)
		(sheetname "Com Express 7 Interfaces")
		(sheetfile "com_express_7_interfaces.kicad_sch")
		(solder_paste_margin_ratio -1)
		(attr smd)
		(fp_circle
			(center 0 0)
			(end 3.05 0)
			(stroke
				(width 0.05)
				(type solid)
			)
			(fill no)
			(layer "F.CrtYd")
		)
		(fp_circle
			(center 0 0)
			(end 2.6 0)
			(stroke
				(width 0.15)
				(type solid)
			)
			(fill no)
			(layer "F.Fab")
		)
		(pad "" smd custom
			(at -1.7 -1.7 90)
			(size 0.62 0.62)
			(layers "F.Paste")
			(thermal_bridge_angle 90)
			(options
				(clearance outline)
				(anchor circle)
			)
			(primitives
				(gr_arc
					(start -0.250195 1.279127)
					(mid 0.285453 0.294389)
					(end 1.266786 -0.24747)
					(width 0.2)
				)
				(gr_arc
					(start -0.34334 1.279127)
					(mid 0.218448 0.232561)
					(end 1.259603 -0.339191)
					(width 0.2)
				)
				(gr_arc
					(start -0.436309 1.279127)
					(mid 0.152481 0.169693)
					(end 1.255279 -0.431435)
					(width 0.2)
				)
				(gr_arc
					(start -0.529126 1.279127)
					(mid 0.087542 0.105784)
					(end 1.253811 -0.524161)
					(width 0.2)
				)
				(gr_arc
					(start -0.621807 1.279127)
					(mid 0.0309 0.033527)
					(end 1.275473 -0.621136)
					(width 0.2)
				)
				(gr_arc
					(start -0.71437 1.279127)
					(mid -0.037758 -0.026651)
					(end 1.263664 -0.711602)
					(width 0.2)
				)
				(gr_arc
					(start -0.806826 1.279127)
					(mid -0.105837 -0.087395)
					(end 1.253435 -0.802342)
					(width 0.2)
				)
				(gr_arc
					(start -0.899187 1.279127)
					(mid -0.165236 -0.156885)
					(end 1.267475 -0.897258)
					(width 0.2)
				)
				(gr_arc
					(start -0.991463 1.279127)
					(mid -0.228522 -0.222449)
					(end 1.270645 -0.990112)
					(width 0.2)
				)
				(gr_arc
					(start -1.083663 1.279127)
					(mid -0.294507 -0.285313)
					(end 1.266278 -1.081674)
					(width 0.2)
				)
				(gr_line
					(start 1.279127 -0.250195)
					(end 1.279127 -1.083663)
					(width 0.2)
				)
				(gr_line
					(start -0.250195 1.279127)
					(end -1.083663 1.279127)
					(width 0.2)
				)
			)
			(teardrops
				(best_length_ratio 0.2)
				(max_length 1)
				(best_width_ratio 0.9)
				(max_width 2)
				(curved_edges yes)
				(filter_ratio 0.9)
				(enabled yes)
				(allow_two_segments yes)
				(prefer_zone_connections yes)
			)
		)
		(pad "" smd custom
			(at -1.7 1.7 180)
			(size 0.62 0.62)
			(layers "F.Paste")
			(thermal_bridge_angle 90)
			(options
				(clearance outline)
				(anchor circle)
			)
			(primitives
				(gr_arc
					(start -0.250195 1.279127)
					(mid 0.285453 0.294389)
					(end 1.266786 -0.24747)
					(width 0.2)
				)
				(gr_arc
					(start -0.34334 1.279127)
					(mid 0.218448 0.232561)
					(end 1.259603 -0.339191)
					(width 0.2)
				)
				(gr_arc
					(start -0.436309 1.279127)
					(mid 0.152481 0.169693)
					(end 1.255279 -0.431435)
					(width 0.2)
				)
				(gr_arc
					(start -0.529126 1.279127)
					(mid 0.087542 0.105784)
					(end 1.253811 -0.524161)
					(width 0.2)
				)
				(gr_arc
					(start -0.621807 1.279127)
					(mid 0.0309 0.033527)
					(end 1.275473 -0.621136)
					(width 0.2)
				)
				(gr_arc
					(start -0.71437 1.279127)
					(mid -0.037758 -0.026651)
					(end 1.263664 -0.711602)
					(width 0.2)
				)
				(gr_arc
					(start -0.806826 1.279127)
					(mid -0.105837 -0.087395)
					(end 1.253435 -0.802342)
					(width 0.2)
				)
				(gr_arc
					(start -0.899187 1.279127)
					(mid -0.165236 -0.156885)
					(end 1.267475 -0.897258)
					(width 0.2)
				)
				(gr_arc
					(start -0.991463 1.279127)
					(mid -0.228522 -0.222449)
					(end 1.270645 -0.990112)
					(width 0.2)
				)
				(gr_arc
					(start -1.083663 1.279127)
					(mid -0.294507 -0.285313)
					(end 1.266278 -1.081674)
					(width 0.2)
				)
				(gr_line
					(start 1.279127 -0.250195)
					(end 1.279127 -1.083663)
					(width 0.2)
				)
				(gr_line
					(start -0.250195 1.279127)
					(end -1.083663 1.279127)
					(width 0.2)
				)
			)
			(teardrops
				(best_length_ratio 0.2)
				(max_length 1)
				(best_width_ratio 0.9)
				(max_width 2)
				(curved_edges yes)
				(filter_ratio 0.9)
				(enabled yes)
				(allow_two_segments yes)
				(prefer_zone_connections yes)
			)
		)
		(pad "" smd custom
			(at 1.7 -1.7)
			(size 0.62 0.62)
			(layers "F.Paste")
			(thermal_bridge_angle 90)
			(options
				(clearance outline)
				(anchor circle)
			)
			(primitives
				(gr_arc
					(start -0.250195 1.279127)
					(mid 0.285453 0.294389)
					(end 1.266786 -0.24747)
					(width 0.2)
				)
				(gr_arc
					(start -0.34334 1.279127)
					(mid 0.218448 0.232561)
					(end 1.259603 -0.339191)
					(width 0.2)
				)
				(gr_arc
					(start -0.436309 1.279127)
					(mid 0.152481 0.169693)
					(end 1.255279 -0.431435)
					(width 0.2)
				)
				(gr_arc
					(start -0.529126 1.279127)
					(mid 0.087542 0.105784)
					(end 1.253811 -0.524161)
					(width 0.2)
				)
				(gr_arc
					(start -0.621807 1.279127)
					(mid 0.0309 0.033527)
					(end 1.275473 -0.621136)
					(width 0.2)
				)
				(gr_arc
					(start -0.71437 1.279127)
					(mid -0.037758 -0.026651)
					(end 1.263664 -0.711602)
					(width 0.2)
				)
				(gr_arc
					(start -0.806826 1.279127)
					(mid -0.105837 -0.087395)
					(end 1.253435 -0.802342)
					(width 0.2)
				)
				(gr_arc
					(start -0.899187 1.279127)
					(mid -0.165236 -0.156885)
					(end 1.267475 -0.897258)
					(width 0.2)
				)
				(gr_arc
					(start -0.991463 1.279127)
					(mid -0.228522 -0.222449)
					(end 1.270645 -0.990112)
					(width 0.2)
				)
				(gr_arc
					(start -1.083663 1.279127)
					(mid -0.294507 -0.285313)
					(end 1.266278 -1.081674)
					(width 0.2)
				)
				(gr_line
					(start 1.279127 -0.250195)
					(end 1.279127 -1.083663)
					(width 0.2)
				)
				(gr_line
					(start -0.250195 1.279127)
					(end -1.083663 1.279127)
					(width 0.2)
				)
			)
			(teardrops
				(best_length_ratio 0.2)
				(max_length 1)
				(best_width_ratio 0.9)
				(max_width 2)
				(curved_edges yes)
				(filter_ratio 0.9)
				(enabled yes)
				(allow_two_segments yes)
				(prefer_zone_connections yes)
			)
		)
		(pad "" smd custom
			(at 1.7 1.7 270)
			(size 0.62 0.62)
			(layers "F.Paste")
			(thermal_bridge_angle 90)
			(options
				(clearance outline)
				(anchor circle)
			)
			(primitives
				(gr_arc
					(start -0.250195 1.279127)
					(mid 0.285453 0.294389)
					(end 1.266786 -0.24747)
					(width 0.2)
				)
				(gr_arc
					(start -0.34334 1.279127)
					(mid 0.218448 0.232561)
					(end 1.259603 -0.339191)
					(width 0.2)
				)
				(gr_arc
					(start -0.436309 1.279127)
					(mid 0.152481 0.169693)
					(end 1.255279 -0.431435)
					(width 0.2)
				)
				(gr_arc
					(start -0.529126 1.279127)
					(mid 0.087542 0.105784)
					(end 1.253811 -0.524161)
					(width 0.2)
				)
				(gr_arc
					(start -0.621807 1.279127)
					(mid 0.0309 0.033527)
					(end 1.275473 -0.621136)
					(width 0.2)
				)
				(gr_arc
					(start -0.71437 1.279127)
					(mid -0.037758 -0.026651)
					(end 1.263664 -0.711602)
					(width 0.2)
				)
				(gr_arc
					(start -0.806826 1.279127)
					(mid -0.105837 -0.087395)
					(end 1.253435 -0.802342)
					(width 0.2)
				)
				(gr_arc
					(start -0.899187 1.279127)
					(mid -0.165236 -0.156885)
					(end 1.267475 -0.897258)
					(width 0.2)
				)
				(gr_arc
					(start -0.991463 1.279127)
					(mid -0.228522 -0.222449)
					(end 1.270645 -0.990112)
					(width 0.2)
				)
				(gr_arc
					(start -1.083663 1.279127)
					(mid -0.294507 -0.285313)
					(end 1.266278 -1.081674)
					(width 0.2)
				)
				(gr_line
					(start 1.279127 -0.250195)
					(end 1.279127 -1.083663)
					(width 0.2)
				)
				(gr_line
					(start -0.250195 1.279127)
					(end -1.083663 1.279127)
					(width 0.2)
				)
			)
			(teardrops
				(best_length_ratio 0.2)
				(max_length 1)
				(best_width_ratio 0.9)
				(max_width 2)
				(curved_edges yes)
				(filter_ratio 0.9)
				(enabled yes)
				(allow_two_segments yes)
				(prefer_zone_connections yes)
			)
		)
		(pad "1" thru_hole circle
			(at 0 0 90)
			(size 6 6)
			(drill 3.7)
			(layers "*.Cu" "*.Mask")
			(remove_unused_layers no)
			(net 1 "GND")
			(pintype "passive")
			(teardrops
				(best_length_ratio 0.4)
				(max_length 1)
				(best_width_ratio 0.9)
				(max_width 2)
				(curved_edges yes)
				(filter_ratio 0.9)
				(enabled yes)
				(allow_two_segments yes)
				(prefer_zone_connections yes)
			)
		)
	)
	(footprint "antmicro-footprints:C_0402_1005Metric"
		(layer "F.Cu")
		(at 192.219362 138.815246 -45)
		(descr "Capacitor SMD 0402")
		(tags "capacitor SMD 0402")
		(property "Reference" "C117"
			(at 3.864615 -0.381761 135)
			(layer "F.SilkS")
			(effects
				(font
					(size 0.7 0.7)
					(thickness 0.15)
				)
				(justify right top)
			)
		)
		(property "Value" "C_100n_0402"
			(at -1.022927 2.155213 135)
			(layer "F.Fab")
			(effects
				(font
					(size 0.7 0.7)
					(thickness 0.15)
				)
				(justify right top)
			)
		)
		(property "Datasheet" "https://www.murata.com/products/productdetail?partno=GRM155R61H104KE14%23"
			(at 0 0 135)
			(layer "B.Fab")
			(hide yes)
			(effects
				(font
					(size 1.27 1.27)
					(thickness 0.15)
				)
				(justify mirror)
			)
		)
		(property "Author" "Antmicro"
			(at 55.668 -328.634 45)
			(layer "F.Fab")
			(hide yes)
			(effects
				(font
					(size 1 1)
					(thickness 0.15)
				)
			)
		)
		(property "Dielectric" "X5R"
			(at 55.668 -328.634 45)
			(layer "F.Fab")
			(hide yes)
			(effects
				(font
					(size 1 1)
					(thickness 0.15)
				)
			)
		)
		(property "License" "Apache-2.0"
			(at 55.668 -328.634 45)
			(layer "F.Fab")
			(hide yes)
			(effects
				(font
					(size 1 1)
					(thickness 0.15)
				)
			)
		)
		(property "MPN" "GRM155R61H104KE14D"
			(at 55.668 -328.634 45)
			(layer "F.Fab")
			(hide yes)
			(effects
				(font
					(size 1 1)
					(thickness 0.15)
				)
			)
		)
		(property "Manufacturer" "Murata"
			(at 55.668 -328.634 45)
			(layer "F.Fab")
			(hide yes)
			(effects
				(font
					(size 1 1)
					(thickness 0.15)
				)
			)
		)
		(property "Public" "False"
			(at 55.668 -328.634 45)
			(layer "F.Fab")
			(hide yes)
			(effects
				(font
					(size 1 1)
					(thickness 0.15)
				)
			)
		)
		(property "Val" "100n"
			(at 55.668 -328.634 45)
			(layer "F.Fab")
			(hide yes)
			(effects
				(font
					(size 1 1)
					(thickness 0.15)
				)
			)
		)
		(property "Voltage" "50V"
			(at 55.668 -328.634 45)
			(layer "F.Fab")
			(hide yes)
			(effects
				(font
					(size 1 1)
					(thickness 0.15)
				)
			)
		)
		(sheetname "PCIe redriver")
		(sheetfile "pcie_redriver.kicad_sch")
		(attr smd)
		(fp_poly
			(pts
				(xy -0.925 -0.47) (xy 0.925 -0.47) (xy 0.925 0.47) (xy -0.925 0.47)
			)
			(stroke
				(width 0.05)
				(type default)
			)
			(fill no)
			(layer "F.CrtYd")
		)
		(fp_line
			(start -0.494 0.248)
			(end -0.494 -0.25)
			(stroke
				(width 0.15)
				(type solid)
			)
			(layer "F.Fab")
		)
		(fp_line
			(start -0.494 -0.25)
			(end 0.504 -0.25)
			(stroke
				(width 0.15)
				(type solid)
			)
			(layer "F.Fab")
		)
		(fp_line
			(start 0.504 0.248)
			(end -0.494 0.248)
			(stroke
				(width 0.15)
				(type solid)
			)
			(layer "F.Fab")
		)
		(fp_line
			(start 0.504 -0.25)
			(end 0.504 0.248)
			(stroke
				(width 0.15)
				(type solid)
			)
			(layer "F.Fab")
		)
		(pad "1" smd roundrect
			(at -0.48 0 315)
			(size 0.59 0.64)
			(layers "F.Cu" "F.Mask" "F.Paste")
			(roundrect_rratio 0.25)
			(net 1 "GND")
			(pintype "passive")
			(teardrops
				(best_length_ratio 0.2)
				(max_length 1)
				(best_width_ratio 0.9)
				(max_width 2)
				(curved_edges yes)
				(filter_ratio 0.9)
				(enabled yes)
				(allow_two_segments yes)
				(prefer_zone_connections yes)
			)
		)
		(pad "2" smd roundrect
			(at 0.48 0 315)
			(size 0.59 0.64)
			(layers "F.Cu" "F.Mask" "F.Paste")
			(roundrect_rratio 0.25)
			(net 2 "+3V3")
			(pintype "passive")
			(teardrops
				(best_length_ratio 0.2)
				(max_length 1)
				(best_width_ratio 0.9)
				(max_width 2)
				(curved_edges yes)
				(filter_ratio 0.9)
				(enabled yes)
				(allow_two_segments yes)
				(prefer_zone_connections yes)
			)
		)
	)
	(footprint "antmicro-footprints:R_0402_1005Metric"
		(layer "F.Cu")
		(at 160.55 156.81 -90)
		(descr "Resistor SMD 0402")
		(tags "resistor SMD 0402")
		(property "Reference" "R33"
			(at -3.013 -0.449 90)
			(layer "F.SilkS")
			(effects
				(font
					(size 0.7 0.7)
					(thickness 0.15)
				)
				(justify right bottom)
			)
		)
		(property "Value" "R_0R_0402"
			(at -1.011843 1.772047 90)
			(layer "F.Fab")
			(effects
				(font
					(size 0.7 0.7)
					(thickness 0.15)
				)
				(justify right bottom)
			)
		)
		(property "Datasheet" "https://industrial.panasonic.com/cdbs/www-data/pdf/RDA0000/AOA0000C301.pdf"
			(at 0 0 270)
			(layer "F.Fab")
			(hide yes)
			(effects
				(font
					(size 1.27 1.27)
					(thickness 0.15)
				)
			)
		)
		(property "Author" "Antmicro"
			(at 3.74 317.36 0)
			(layer "F.Fab")
			(hide yes)
			(effects
				(font
					(size 1 1)
					(thickness 0.15)
				)
			)
		)
		(property "Current" "1A"
			(at 3.74 317.36 0)
			(layer "F.Fab")
			(hide yes)
			(effects
				(font
					(size 1 1)
					(thickness 0.15)
				)
			)
		)
		(property "License" "Apache-2.0"
			(at 3.74 317.36 0)
			(layer "F.Fab")
			(hide yes)
			(effects
				(font
					(size 1 1)
					(thickness 0.15)
				)
			)
		)
		(property "MPN" "ERJ2GE0R00X"
			(at 3.74 317.36 0)
			(layer "F.Fab")
			(hide yes)
			(effects
				(font
					(size 1 1)
					(thickness 0.15)
				)
			)
		)
		(property "Manufacturer" "Panasonic"
			(at 3.74 317.36 0)
			(layer "F.Fab")
			(hide yes)
			(effects
				(font
					(size 1 1)
					(thickness 0.15)
				)
			)
		)
		(property "Public" "False"
			(at 3.74 317.36 0)
			(layer "F.Fab")
			(hide yes)
			(effects
				(font
					(size 1 1)
					(thickness 0.15)
				)
			)
		)
		(property "Tolerance" ""
			(at 3.74 317.36 0)
			(layer "F.Fab")
			(hide yes)
			(effects
				(font
					(size 1 1)
					(thickness 0.15)
				)
			)
		)
		(property "Val" "0R"
			(at 3.74 317.36 0)
			(layer "F.Fab")
			(hide yes)
			(effects
				(font
					(size 1 1)
					(thickness 0.15)
				)
			)
		)
		(sheetname "2xSFP+")
		(sheetfile "2xSFP+.kicad_sch")
		(attr smd)
		(fp_rect
			(start -0.925 -0.47)
			(end 0.925 0.47)
			(stroke
				(width 0.05)
				(type default)
			)
			(fill no)
			(layer "F.CrtYd")
		)
		(fp_rect
			(start -0.5 -0.25)
			(end 0.5 0.25)
			(stroke
				(width 0.15)
				(type solid)
			)
			(fill no)
			(layer "F.Fab")
		)
		(pad "1" smd roundrect
			(at -0.48 0 270)
			(size 0.59 0.64)
			(layers "F.Cu" "F.Mask" "F.Paste")
			(roundrect_rratio 0.25)
			(net 422 "/2xSFP+/I2C_{LED}.SDA")
			(pintype "passive")
			(teardrops
				(best_length_ratio 0.2)
				(max_length 1)
				(best_width_ratio 0.9)
				(max_width 2)
				(curved_edges yes)
				(filter_ratio 0.9)
				(enabled yes)
				(allow_two_segments yes)
				(prefer_zone_connections yes)
			)
		)
		(pad "2" smd roundrect
			(at 0.48 0 270)
			(size 0.59 0.64)
			(layers "F.Cu" "F.Mask" "F.Paste")
			(roundrect_rratio 0.25)
			(net 558 "Net-(U5-SDA)")
			(pintype "passive")
			(teardrops
				(best_length_ratio 0.2)
				(max_length 1)
				(best_width_ratio 0.9)
				(max_width 2)
				(curved_edges yes)
				(filter_ratio 0.9)
				(enabled yes)
				(allow_two_segments yes)
				(prefer_zone_connections yes)
			)
		)
	)
	(footprint "antmicro-footprints:LED_0603_1608Metric_Y"
		(layer "F.Cu")
		(at 138.63 156.17 180)
		(descr "LED SMD 0603 Yellow")
		(tags "LED SMD 0603 Yellow")
		(property "Reference" "D5"
			(at 2.68 -0.44 180)
			(layer "F.SilkS")
			(effects
				(font
					(size 0.7 0.7)
					(thickness 0.15)
				)
				(justify left bottom)
			)
		)
		(property "Value" "LED_Y_0603_LTST-C191KSKT"
			(at 0 1.6 180)
			(layer "F.Fab")
			(effects
				(font
					(size 0.7 0.7)
					(thickness 0.15)
				)
				(justify left bottom)
			)
		)
		(property "Datasheet" "https://optoelectronics.liteon.com/upload/download/DS22-2000-224/LTST-C191KSKT.PDF"
			(at 0 0 180)
			(layer "F.Fab")
			(hide yes)
			(effects
				(font
					(size 1.27 1.27)
					(thickness 0.15)
				)
			)
		)
		(property "Author" "Antmicro"
			(at 277.26 312.34 0)
			(layer "F.Fab")
			(hide yes)
			(effects
				(font
					(size 1 1)
					(thickness 0.15)
				)
			)
		)
		(property "Color" "Yellow"
			(at 277.26 312.34 0)
			(layer "F.Fab")
			(hide yes)
			(effects
				(font
					(size 1 1)
					(thickness 0.15)
				)
			)
		)
		(property "License" "Apache-2.0"
			(at 277.26 312.34 0)
			(layer "F.Fab")
			(hide yes)
			(effects
				(font
					(size 1 1)
					(thickness 0.15)
				)
			)
		)
		(property "MPN" "LTST-C191KSKT"
			(at 277.26 312.34 0)
			(layer "F.Fab")
			(hide yes)
			(effects
				(font
					(size 1 1)
					(thickness 0.15)
				)
			)
		)
		(property "Manufacturer" "Lite-On"
			(at 277.26 312.34 0)
			(layer "F.Fab")
			(hide yes)
			(effects
				(font
					(size 1 1)
					(thickness 0.15)
				)
			)
		)
		(sheetname "2xSFP+")
		(sheetfile "2xSFP+.kicad_sch")
		(attr smd)
		(fp_line
			(start 0.22 0.35)
			(end -0.22 0.35)
			(stroke
				(width 0.15)
				(type solid)
			)
			(layer "F.SilkS")
		)
		(fp_line
			(start 0.22 -0.35)
			(end -0.22 -0.35)
			(stroke
				(width 0.15)
				(type solid)
			)
			(layer "F.SilkS")
		)
		(fp_line
			(start 0.105328 0.201008)
			(end 0.105328 -0.198992)
			(stroke
				(width 0.1)
				(type solid)
			)
			(layer "F.SilkS")
		)
		(fp_line
			(start 0.105328 0.201008)
			(end -0.094672 0.001008)
			(stroke
				(width 0.1)
				(type solid)
			)
			(layer "F.SilkS")
		)
		(fp_line
			(start 0.105328 0.001008)
			(end 0.24 0.001)
			(stroke
				(width 0.1)
				(type solid)
			)
			(layer "F.SilkS")
		)
		(fp_line
			(start -0.094672 0.201008)
			(end -0.094672 -0.198992)
			(stroke
				(width 0.1)
				(type solid)
			)
			(layer "F.SilkS")
		)
		(fp_line
			(start -0.094672 0.001008)
			(end 0.105328 -0.198992)
			(stroke
				(width 0.1)
				(type solid)
			)
			(layer "F.SilkS")
		)
		(fp_line
			(start -0.094672 0.001008)
			(end -0.24 0.001008)
			(stroke
				(width 0.1)
				(type solid)
			)
			(layer "F.SilkS")
		)
		(fp_line
			(start -1.18 -0.319)
			(end -1.18 0.321)
			(stroke
				(width 0.15)
				(type solid)
			)
			(layer "F.SilkS")
		)
		(fp_rect
			(start 1.25 0.65)
			(end -1.25 -0.65)
			(stroke
				(width 0.05)
				(type solid)
			)
			(fill no)
			(layer "F.CrtYd")
		)
		(fp_line
			(start 0.599 0)
			(end 0.201 0)
			(stroke
				(width 0.15)
				(type solid)
			)
			(layer "F.Fab")
		)
		(fp_line
			(start 0.201 0.2)
			(end 0.201 0)
			(stroke
				(width 0.15)
				(type solid)
			)
			(layer "F.Fab")
		)
		(fp_line
			(start 0.201 0)
			(end 0.201 -0.202)
			(stroke
				(width 0.15)
				(type solid)
			)
			(layer "F.Fab")
		)
		(fp_line
			(start 0.201 -0.202)
			(end -0.101 0)
			(stroke
				(width 0.15)
				(type solid)
			)
			(layer "F.Fab")
		)
		(fp_line
			(start -0.101 0)
			(end 0.201 0.2)
			(stroke
				(width 0.15)
				(type solid)
			)
			(layer "F.Fab")
		)
		(fp_line
			(start -0.199 0.2)
			(end -0.199 0.1)
			(stroke
				(width 0.15)
				(type solid)
			)
			(layer "F.Fab")
		)
		(fp_line
			(start -0.199 0)
			(end -0.597 0)
			(stroke
				(width 0.15)
				(type solid)
			)
			(layer "F.Fab")
		)
		(fp_line
			(start -0.199 -0.202)
			(end -0.199 0.1)
			(stroke
				(width 0.15)
				(type solid)
			)
			(layer "F.Fab")
		)
		(fp_rect
			(start 0.848 0.4)
			(end -0.85 -0.402)
			(stroke
				(width 0.15)
				(type solid)
			)
			(fill no)
			(layer "F.Fab")
		)
		(pad "1" smd roundrect
			(at -0.7 0)
			(size 0.8 1)
			(layers "F.Cu" "F.Mask" "F.Paste")
			(roundrect_rratio 0.2)
			(net 930 "Net-(D5-C)")
			(pinfunction "C")
			(pintype "passive")
			(teardrops
				(best_length_ratio 0.2)
				(max_length 1)
				(best_width_ratio 0.9)
				(max_width 2)
				(curved_edges yes)
				(filter_ratio 0.9)
				(enabled yes)
				(allow_two_segments yes)
				(prefer_zone_connections yes)
			)
		)
		(pad "2" smd roundrect
			(at 0.7 0)
			(size 0.8 1)
			(layers "F.Cu" "F.Mask" "F.Paste")
			(roundrect_rratio 0.2)
			(net 2 "+3V3")
			(pinfunction "A")
			(pintype "passive")
			(teardrops
				(best_length_ratio 0.2)
				(max_length 1)
				(best_width_ratio 0.9)
				(max_width 2)
				(curved_edges yes)
				(filter_ratio 0.9)
				(enabled yes)
				(allow_two_segments yes)
				(prefer_zone_connections yes)
			)
		)
	)
	(footprint "antmicro-footprints:R_0402_1005Metric"
		(layer "F.Cu")
		(at 222.68 127.195)
		(descr "Resistor SMD 0402")
		(tags "resistor SMD 0402")
		(property "Reference" "R186"
			(at 0.77 0.465 0)
			(layer "F.SilkS")
			(effects
				(font
					(size 0.7 0.7)
					(thickness 0.15)
				)
				(justify left bottom)
			)
		)
		(property "Value" "R_1k_0402"
			(at -1.011843 1.772047 0)
			(layer "F.Fab")
			(effects
				(font
					(size 0.7 0.7)
					(thickness 0.15)
				)
				(justify left bottom)
			)
		)
		(property "Datasheet" "https://www.bourns.com/docs/product-datasheets/cr.pdf"
			(at 0 0 0)
			(layer "F.Fab")
			(hide yes)
			(effects
				(font
					(size 1.27 1.27)
					(thickness 0.15)
				)
			)
		)
		(property "Author" "Antmicro"
			(at 0 0 0)
			(layer "F.Fab")
			(hide yes)
			(effects
				(font
					(size 1 1)
					(thickness 0.15)
				)
			)
		)
		(property "License" "Apache-2.0"
			(at 0 0 0)
			(layer "F.Fab")
			(hide yes)
			(effects
				(font
					(size 1 1)
					(thickness 0.15)
				)
			)
		)
		(property "MPN" "CR0402-FX-1001GLF"
			(at 0 0 0)
			(layer "F.Fab")
			(hide yes)
			(effects
				(font
					(size 1 1)
					(thickness 0.15)
				)
			)
		)
		(property "Manufacturer" "Bourns"
			(at 0 0 0)
			(layer "F.Fab")
			(hide yes)
			(effects
				(font
					(size 1 1)
					(thickness 0.15)
				)
			)
		)
		(property "Public" "False"
			(at 0 0 0)
			(layer "F.Fab")
			(hide yes)
			(effects
				(font
					(size 1 1)
					(thickness 0.15)
				)
			)
		)
		(property "Tolerance" "1%"
			(at 0 0 0)
			(layer "F.Fab")
			(hide yes)
			(effects
				(font
					(size 1 1)
					(thickness 0.15)
				)
			)
		)
		(property "Val" "1k"
			(at 0 0 0)
			(layer "F.Fab")
			(hide yes)
			(effects
				(font
					(size 1 1)
					(thickness 0.15)
				)
			)
		)
		(sheetname "PCIe misc")
		(sheetfile "pcie_misc.kicad_sch")
		(attr smd)
		(fp_rect
			(start -0.925 -0.47)
			(end 0.925 0.47)
			(stroke
				(width 0.05)
				(type default)
			)
			(fill no)
			(layer "F.CrtYd")
		)
		(fp_rect
			(start -0.5 -0.25)
			(end 0.5 0.25)
			(stroke
				(width 0.15)
				(type solid)
			)
			(fill no)
			(layer "F.Fab")
		)
		(pad "1" smd roundrect
			(at -0.48 0)
			(size 0.59 0.64)
			(layers "F.Cu" "F.Mask" "F.Paste")
			(roundrect_rratio 0.25)
			(net 606 "Net-(U37-~{OE4})")
			(pintype "passive")
			(teardrops
				(best_length_ratio 0.2)
				(max_length 1)
				(best_width_ratio 0.9)
				(max_width 2)
				(curved_edges yes)
				(filter_ratio 0.9)
				(enabled yes)
				(allow_two_segments yes)
				(prefer_zone_connections yes)
			)
		)
		(pad "2" smd roundrect
			(at 0.48 0)
			(size 0.59 0.64)
			(layers "F.Cu" "F.Mask" "F.Paste")
			(roundrect_rratio 0.25)
			(net 1 "GND")
			(pintype "passive")
			(teardrops
				(best_length_ratio 0.2)
				(max_length 1)
				(best_width_ratio 0.9)
				(max_width 2)
				(curved_edges yes)
				(filter_ratio 0.9)
				(enabled yes)
				(allow_two_segments yes)
				(prefer_zone_connections yes)
			)
		)
	)
	(footprint "antmicro-footprints:L_WE-MAPI-4020"
		(layer "F.Cu")
		(at 311.25 125.46 180)
		(property "Reference" "L1"
			(at -2.3 -2.3 0)
			(layer "F.SilkS")
			(effects
				(font
					(size 0.7 0.7)
					(thickness 0.15)
				)
				(justify left bottom)
			)
		)
		(property "Value" "L_1u8_6.8A_WE-MAPI-4020"
			(at -2.4 3.4 0)
			(layer "F.Fab")
			(effects
				(font
					(size 0.7 0.7)
					(thickness 0.15)
				)
				(justify left bottom)
			)
		)
		(property "Datasheet" "https://www.we-online.com/components/products/datasheet/74438356018.pdf"
			(at 0 0 180)
			(layer "F.Fab")
			(hide yes)
			(effects
				(font
					(size 1.27 1.27)
					(thickness 0.15)
				)
			)
		)
		(property "Author" "Antmicro"
			(at 622.5 250.92 0)
			(layer "F.Fab")
			(hide yes)
			(effects
				(font
					(size 1 1)
					(thickness 0.15)
				)
			)
		)
		(property "IMax" "6.8 A"
			(at 622.5 250.92 0)
			(layer "F.Fab")
			(hide yes)
			(effects
				(font
					(size 1 1)
					(thickness 0.15)
				)
			)
		)
		(property "ISat" "6.5 A"
			(at 622.5 250.92 0)
			(layer "F.Fab")
			(hide yes)
			(effects
				(font
					(size 1 1)
					(thickness 0.15)
				)
			)
		)
		(property "License" "Apache-2.0"
			(at 622.5 250.92 0)
			(layer "F.Fab")
			(hide yes)
			(effects
				(font
					(size 1 1)
					(thickness 0.15)
				)
			)
		)
		(property "MPN" "74438356018"
			(at 622.5 250.92 0)
			(layer "F.Fab")
			(hide yes)
			(effects
				(font
					(size 1 1)
					(thickness 0.15)
				)
			)
		)
		(property "Manufacturer" "Würth Elektronik"
			(at 622.5 250.92 0)
			(layer "F.Fab")
			(hide yes)
			(effects
				(font
					(size 1 1)
					(thickness 0.15)
				)
			)
		)
		(property "Public" "False"
			(at 622.5 250.92 0)
			(layer "F.Fab")
			(hide yes)
			(effects
				(font
					(size 1 1)
					(thickness 0.15)
				)
			)
		)
		(property "Size" "4.1x4.1mm"
			(at 622.5 250.92 0)
			(layer "F.Fab")
			(hide yes)
			(effects
				(font
					(size 1 1)
					(thickness 0.15)
				)
			)
		)
		(property "Val" "1u8/6.8A"
			(at 622.5 250.92 0)
			(layer "F.Fab")
			(hide yes)
			(effects
				(font
					(size 1 1)
					(thickness 0.15)
				)
			)
		)
		(sheetname "Power")
		(sheetfile "power.kicad_sch")
		(attr smd)
		(fp_rect
			(start -2.2 -2.2)
			(end 2.2 2.2)
			(stroke
				(width 0.15)
				(type solid)
			)
			(fill no)
			(layer "F.SilkS")
		)
		(fp_rect
			(start -2.3 -2.3)
			(end 2.3 2.3)
			(stroke
				(width 0.05)
				(type solid)
			)
			(fill no)
			(layer "F.CrtYd")
		)
		(fp_rect
			(start -2.05 -2.05)
			(end 2.05 2.05)
			(stroke
				(width 0.15)
				(type solid)
			)
			(fill no)
			(layer "F.Fab")
		)
		(pad "1" smd roundrect
			(at -1.185 0 270)
			(size 3.7 1)
			(layers "F.Cu" "F.Mask" "F.Paste")
			(roundrect_rratio 0.1)
			(net 67 "Net-(C47-Pad2)")
			(pintype "passive")
			(teardrops
				(best_length_ratio 0.2)
				(max_length 1)
				(best_width_ratio 0.9)
				(max_width 2)
				(curved_edges yes)
				(filter_ratio 0.9)
				(enabled yes)
				(allow_two_segments yes)
				(prefer_zone_connections yes)
			)
		)
		(pad "2" smd roundrect
			(at 1.185 0 270)
			(size 3.7 1)
			(layers "F.Cu" "F.Mask" "F.Paste")
			(roundrect_rratio 0.1)
			(net 70 "Net-(C49-Pad2)")
			(pintype "passive")
			(teardrops
				(best_length_ratio 0.2)
				(max_length 1)
				(best_width_ratio 0.9)
				(max_width 2)
				(curved_edges yes)
				(filter_ratio 0.9)
				(enabled yes)
				(allow_two_segments yes)
				(prefer_zone_connections yes)
			)
		)
	)
	(footprint "antmicro-footprints:R_0805_2012Metric"
		(layer "F.Cu")
		(at 304.25 100.64 180)
		(property "Reference" "R104"
			(at -1.55 0.93 0)
			(layer "F.SilkS")
			(effects
				(font
					(size 0.7 0.7)
					(thickness 0.15)
				)
				(justify right bottom)
			)
		)
		(property "Value" "R_0R001_0805"
			(at 1.82 2.18 0)
			(layer "F.Fab")
			(effects
				(font
					(size 0.7 0.7)
					(thickness 0.15)
				)
				(justify left bottom mirror)
			)
		)
		(property "Datasheet" "https://www.eaton.com/content/dam/eaton/products/electronic-components/resources/data-sheet/eaton-msma-automotive-smd-current-sense-resistor-metal-strip-data-sheet-elx1179.pdf"
			(at 0 0 180)
			(layer "F.Fab")
			(hide yes)
			(effects
				(font
					(size 1.27 1.27)
					(thickness 0.15)
				)
			)
		)
		(property "Author" "Antmicro"
			(at 608.5 201.28 0)
			(layer "F.Fab")
			(hide yes)
			(effects
				(font
					(size 1 1)
					(thickness 0.15)
				)
			)
		)
		(property "License" "Apache-2.0"
			(at 608.5 201.28 0)
			(layer "F.Fab")
			(hide yes)
			(effects
				(font
					(size 1 1)
					(thickness 0.15)
				)
			)
		)
		(property "MPN" "MSMA0805R0010FSM"
			(at 608.5 201.28 0)
			(layer "F.Fab")
			(hide yes)
			(effects
				(font
					(size 1 1)
					(thickness 0.15)
				)
			)
		)
		(property "Manufacturer" "Eaton"
			(at 608.5 201.28 0)
			(layer "F.Fab")
			(hide yes)
			(effects
				(font
					(size 1 1)
					(thickness 0.15)
				)
			)
		)
		(property "Public" "False"
			(at 608.5 201.28 0)
			(layer "F.Fab")
			(hide yes)
			(effects
				(font
					(size 1 1)
					(thickness 0.15)
				)
			)
		)
		(property "Tolerance" "1%"
			(at 608.5 201.28 0)
			(layer "F.Fab")
			(hide yes)
			(effects
				(font
					(size 1 1)
					(thickness 0.15)
				)
			)
		)
		(property "Val" "0R001"
			(at 608.5 201.28 0)
			(layer "F.Fab")
			(hide yes)
			(effects
				(font
					(size 1 1)
					(thickness 0.15)
				)
			)
		)
		(sheetname "Power")
		(sheetfile "power.kicad_sch")
		(attr smd)
		(fp_line
			(start -0.3 -0.701)
			(end 0.298 -0.701)
			(stroke
				(width 0.15)
				(type solid)
			)
			(layer "F.SilkS")
		)
		(fp_line
			(start -0.32 0.699)
			(end 0.28 0.699)
			(stroke
				(width 0.15)
				(type solid)
			)
			(layer "F.SilkS")
		)
		(fp_rect
			(start 1.95 -0.9)
			(end -1.95 0.9)
			(stroke
				(width 0.05)
				(type default)
			)
			(fill no)
			(layer "F.CrtYd")
		)
		(fp_line
			(start 0.949 -0.677)
			(end 0.949 0.675)
			(stroke
				(width 0.15)
				(type solid)
			)
			(layer "F.Fab")
		)
		(fp_line
			(start -0.951 0.68)
			(end 0.949 0.68)
			(stroke
				(width 0.15)
				(type solid)
			)
			(layer "F.Fab")
		)
		(fp_line
			(start -0.951 -0.677)
			(end -0.951 0.675)
			(stroke
				(width 0.15)
				(type solid)
			)
			(layer "F.Fab")
		)
		(fp_line
			(start -0.951 -0.682)
			(end 0.949 -0.682)
			(stroke
				(width 0.15)
				(type solid)
			)
			(layer "F.Fab")
		)
		(pad "1" smd roundrect
			(at -1.1 0 180)
			(size 1.2 1.3)
			(layers "F.Cu" "F.Mask" "F.Paste")
			(roundrect_rratio 0.25)
			(net 71 "Net-(U49-IN+)")
			(pintype "passive")
			(teardrops
				(best_length_ratio 0.2)
				(max_length 1)
				(best_width_ratio 0.9)
				(max_width 2)
				(curved_edges yes)
				(filter_ratio 0.9)
				(enabled yes)
				(allow_two_segments yes)
				(prefer_zone_connections yes)
			)
		)
		(pad "2" smd roundrect
			(at 1.1 0 180)
			(size 1.2 1.3)
			(layers "F.Cu" "F.Mask" "F.Paste")
			(roundrect_rratio 0.25)
			(net 2 "+3V3")
			(pintype "passive")
			(teardrops
				(best_length_ratio 0.2)
				(max_length 1)
				(best_width_ratio 0.9)
				(max_width 2)
				(curved_edges yes)
				(filter_ratio 0.9)
				(enabled yes)
				(allow_two_segments yes)
				(prefer_zone_connections yes)
			)
		)
	)
	(footprint "antmicro-footprints:BGA-144_12x12_13.05x13.05mm_P1.0mm"
		(layer "F.Cu")
		(at 132.79 137.36 -90)
		(property "Reference" "U45"
			(at 7.9 4.85 180)
			(layer "F.SilkS")
			(effects
				(font
					(size 0.7 0.7)
					(thickness 0.15)
				)
				(justify right bottom)
			)
		)
		(property "Value" "TLK10232CTR"
			(at 0 7.525 90)
			(layer "F.Fab")
			(effects
				(font
					(size 0.7 0.7)
					(thickness 0.15)
				)
				(justify right bottom)
			)
		)
		(property "Datasheet" "https://www.ti.com/lit/ds/symlink/tlk10232.pdf?ts=1712150848075&ref_url=https%253A%252F%252Fwww.mouser.pl%252F"
			(at 0 0 270)
			(layer "F.Fab")
			(hide yes)
			(effects
				(font
					(size 1.27 1.27)
					(thickness 0.15)
				)
			)
		)
		(property "Author" "Antmicro"
			(at -4.57 270.15 0)
			(layer "F.Fab")
			(hide yes)
			(effects
				(font
					(size 1 1)
					(thickness 0.15)
				)
			)
		)
		(property "License" "Apache-2.0"
			(at -4.57 270.15 0)
			(layer "F.Fab")
			(hide yes)
			(effects
				(font
					(size 1 1)
					(thickness 0.15)
				)
			)
		)
		(property "MPN" "TLK10232CTR"
			(at -4.57 270.15 0)
			(layer "F.Fab")
			(hide yes)
			(effects
				(font
					(size 1 1)
					(thickness 0.15)
				)
			)
		)
		(property "Manufacturer" "Texas Instruments"
			(at -4.57 270.15 0)
			(layer "F.Fab")
			(hide yes)
			(effects
				(font
					(size 1 1)
					(thickness 0.15)
				)
			)
		)
		(sheetname "KR to SFI #2")
		(sheetfile "kr_sfi.kicad_sch")
		(attr smd)
		(fp_line
			(start -6.645 6.645)
			(end -6.645 3.382)
			(stroke
				(width 0.15)
				(type solid)
			)
			(layer "F.SilkS")
		)
		(fp_line
			(start -3.382 6.645)
			(end -6.645 6.645)
			(stroke
				(width 0.15)
				(type solid)
			)
			(layer "F.SilkS")
		)
		(fp_line
			(start 3.382 6.645)
			(end 6.645 6.645)
			(stroke
				(width 0.15)
				(type solid)
			)
			(layer "F.SilkS")
		)
		(fp_line
			(start 6.645 6.645)
			(end 6.645 3.382)
			(stroke
				(width 0.15)
				(type solid)
			)
			(layer "F.SilkS")
		)
		(fp_line
			(start -6.645 -5.525)
			(end -6.645 -3.382)
			(stroke
				(width 0.15)
				(type solid)
			)
			(layer "F.SilkS")
		)
		(fp_line
			(start -5.525 -6.645)
			(end -6.645 -5.525)
			(stroke
				(width 0.15)
				(type solid)
			)
			(layer "F.SilkS")
		)
		(fp_line
			(start -3.382 -6.645)
			(end -5.525 -6.645)
			(stroke
				(width 0.15)
				(type solid)
			)
			(layer "F.SilkS")
		)
		(fp_line
			(start 3.382 -6.645)
			(end 6.645 -6.645)
			(stroke
				(width 0.15)
				(type solid)
			)
			(layer "F.SilkS")
		)
		(fp_line
			(start 6.645 -6.645)
			(end 6.645 -3.382)
			(stroke
				(width 0.15)
				(type solid)
			)
			(layer "F.SilkS")
		)
		(fp_circle
			(center -6.525 -6.525)
			(end -6.425 -6.525)
			(stroke
				(width 0.2)
				(type solid)
			)
			(fill no)
			(layer "F.SilkS")
		)
		(fp_rect
			(start -6.95 -6.95)
			(end 6.95 6.95)
			(stroke
				(width 0.05)
				(type solid)
			)
			(fill no)
			(layer "F.CrtYd")
		)
		(fp_line
			(start -6.525 6.525)
			(end 6.525 6.525)
			(stroke
				(width 0.15)
				(type solid)
			)
			(layer "F.Fab")
		)
		(fp_line
			(start 6.525 6.525)
			(end 6.525 -6.525)
			(stroke
				(width 0.15)
				(type solid)
			)
			(layer "F.Fab")
		)
		(fp_line
			(start -6.525 -5.525)
			(end -6.525 6.525)
			(stroke
				(width 0.15)
				(type solid)
			)
			(layer "F.Fab")
		)
		(fp_line
			(start -5.525 -6.525)
			(end -6.525 -5.525)
			(stroke
				(width 0.15)
				(type solid)
			)
			(layer "F.Fab")
		)
		(fp_line
			(start 6.525 -6.525)
			(end -5.525 -6.525)
			(stroke
				(width 0.15)
				(type solid)
			)
			(layer "F.Fab")
		)
		(pad "A1" smd circle
			(at -5.5 -5.5 270)
			(size 0.5 0.5)
			(layers "F.Cu" "F.Mask" "F.Paste")
			(net 832 "unconnected-(U45A-INA1+-PadA1)")
			(pinfunction "INA1+")
			(pintype "input+no_connect")
			(solder_mask_margin 0.05)
			(teardrops
				(best_length_ratio 0.4)
				(max_length 1)
				(best_width_ratio 0.9)
				(max_width 2)
				(curved_edges yes)
				(filter_ratio 0.9)
				(enabled yes)
				(allow_two_segments yes)
				(prefer_zone_connections yes)
			)
		)
		(pad "A2" smd circle
			(at -4.5 -5.5 270)
			(size 0.5 0.5)
			(layers "F.Cu" "F.Mask" "F.Paste")
			(net 1 "GND")
			(pinfunction "GND")
			(pintype "passive")
			(solder_mask_margin 0.05)
			(teardrops
				(best_length_ratio 0.4)
				(max_length 1)
				(best_width_ratio 0.9)
				(max_width 2)
				(curved_edges yes)
				(filter_ratio 0.9)
				(enabled yes)
				(allow_two_segments yes)
				(prefer_zone_connections yes)
			)
		)
		(pad "A3" smd circle
			(at -3.5 -5.5 270)
			(size 0.5 0.5)
			(layers "F.Cu" "F.Mask" "F.Paste")
			(net 833 "unconnected-(U45A-INA0--PadA3)")
			(pinfunction "INA0-")
			(pintype "input+no_connect")
			(solder_mask_margin 0.05)
			(teardrops
				(best_length_ratio 0.4)
				(max_length 1)
				(best_width_ratio 0.9)
				(max_width 2)
				(curved_edges yes)
				(filter_ratio 0.9)
				(enabled yes)
				(allow_two_segments yes)
				(prefer_zone_connections yes)
			)
		)
		(pad "A4" smd circle
			(at -2.5 -5.5 270)
			(size 0.5 0.5)
			(layers "F.Cu" "F.Mask" "F.Paste")
			(net 834 "unconnected-(U45A-INA0+-PadA4)")
			(pinfunction "INA0+")
			(pintype "input+no_connect")
			(solder_mask_margin 0.05)
			(teardrops
				(best_length_ratio 0.4)
				(max_length 1)
				(best_width_ratio 0.9)
				(max_width 2)
				(curved_edges yes)
				(filter_ratio 0.9)
				(enabled yes)
				(allow_two_segments yes)
				(prefer_zone_connections yes)
			)
		)
		(pad "A5" smd circle
			(at -1.5 -5.5 270)
			(size 0.5 0.5)
			(layers "F.Cu" "F.Mask" "F.Paste")
			(net 1 "GND")
			(pinfunction "GND")
			(pintype "passive")
			(solder_mask_margin 0.05)
			(teardrops
				(best_length_ratio 0.4)
				(max_length 1)
				(best_width_ratio 0.9)
				(max_width 2)
				(curved_edges yes)
				(filter_ratio 0.9)
				(enabled yes)
				(allow_two_segments yes)
				(prefer_zone_connections yes)
			)
		)
		(pad "A6" smd circle
			(at -0.5 -5.5 270)
			(size 0.5 0.5)
			(layers "F.Cu" "F.Mask" "F.Paste")
			(net 835 "unconnected-(U45A-OUTA0+-PadA6)")
			(pinfunction "OUTA0+")
			(pintype "output+no_connect")
			(solder_mask_margin 0.05)
			(teardrops
				(best_length_ratio 0.4)
				(max_length 1)
				(best_width_ratio 0.9)
				(max_width 2)
				(curved_edges yes)
				(filter_ratio 0.9)
				(enabled yes)
				(allow_two_segments yes)
				(prefer_zone_connections yes)
			)
		)
		(pad "A7" smd circle
			(at 0.5 -5.5 270)
			(size 0.5 0.5)
			(layers "F.Cu" "F.Mask" "F.Paste")
			(net 836 "unconnected-(U45A-OUTA0--PadA7)")
			(pinfunction "OUTA0-")
			(pintype "output+no_connect")
			(solder_mask_margin 0.05)
			(teardrops
				(best_length_ratio 0.4)
				(max_length 1)
				(best_width_ratio 0.9)
				(max_width 2)
				(curved_edges yes)
				(filter_ratio 0.9)
				(enabled yes)
				(allow_two_segments yes)
				(prefer_zone_connections yes)
			)
		)
		(pad "A8" smd circle
			(at 1.5 -5.5 270)
			(size 0.5 0.5)
			(layers "F.Cu" "F.Mask" "F.Paste")
			(net 678 "Net-(U45A-~{PDTRXA})")
			(pinfunction "~{PDTRXA}")
			(pintype "input")
			(solder_mask_margin 0.05)
			(teardrops
				(best_length_ratio 0.4)
				(max_length 1)
				(best_width_ratio 0.9)
				(max_width 2)
				(curved_edges yes)
				(filter_ratio 0.9)
				(enabled yes)
				(allow_two_segments yes)
				(prefer_zone_connections yes)
			)
		)
		(pad "A9" smd circle
			(at 2.5 -5.5 270)
			(size 0.5 0.5)
			(layers "F.Cu" "F.Mask" "F.Paste")
			(net 752 "Net-(U45C-CLKOUTB+)")
			(pinfunction "CLKOUTB+")
			(pintype "output")
			(solder_mask_margin 0.05)
			(teardrops
				(best_length_ratio 0.4)
				(max_length 1)
				(best_width_ratio 0.9)
				(max_width 2)
				(curved_edges yes)
				(filter_ratio 0.9)
				(enabled yes)
				(allow_two_segments yes)
				(prefer_zone_connections yes)
			)
		)
		(pad "A10" smd circle
			(at 3.5 -5.5 270)
			(size 0.5 0.5)
			(layers "F.Cu" "F.Mask" "F.Paste")
			(net 753 "Net-(U45C-CLKOUTB-)")
			(pinfunction "CLKOUTB-")
			(pintype "output")
			(solder_mask_margin 0.05)
			(teardrops
				(best_length_ratio 0.4)
				(max_length 1)
				(best_width_ratio 0.9)
				(max_width 2)
				(curved_edges yes)
				(filter_ratio 0.9)
				(enabled yes)
				(allow_two_segments yes)
				(prefer_zone_connections yes)
			)
		)
		(pad "A11" smd circle
			(at 4.5 -5.5 270)
			(size 0.5 0.5)
			(layers "F.Cu" "F.Mask" "F.Paste")
			(net 1 "GND")
			(pinfunction "GND")
			(pintype "power_in")
			(solder_mask_margin 0.05)
			(teardrops
				(best_length_ratio 0.4)
				(max_length 1)
				(best_width_ratio 0.9)
				(max_width 2)
				(curved_edges yes)
				(filter_ratio 0.9)
				(enabled yes)
				(allow_two_segments yes)
				(prefer_zone_connections yes)
			)
		)
		(pad "A12" smd circle
			(at 5.5 -5.5 270)
			(size 0.5 0.5)
			(layers "F.Cu" "F.Mask" "F.Paste")
			(net 122 "/2xSFP+/KR to SFI #2/KR_C.TX-")
			(pinfunction "HSRXA-")
			(pintype "input")
			(solder_mask_margin 0.05)
			(teardrops
				(best_length_ratio 0.4)
				(max_length 1)
				(best_width_ratio 0.9)
				(max_width 2)
				(curved_edges yes)
				(filter_ratio 0.9)
				(enabled yes)
				(allow_two_segments yes)
				(prefer_zone_connections yes)
			)
		)
		(pad "B1" smd circle
			(at -5.5 -4.5 270)
			(size 0.5 0.5)
			(layers "F.Cu" "F.Mask" "F.Paste")
			(net 837 "unconnected-(U45A-INA1--PadB1)")
			(pinfunction "INA1-")
			(pintype "input+no_connect")
			(solder_mask_margin 0.05)
			(teardrops
				(best_length_ratio 0.4)
				(max_length 1)
				(best_width_ratio 0.9)
				(max_width 2)
				(curved_edges yes)
				(filter_ratio 0.9)
				(enabled yes)
				(allow_two_segments yes)
				(prefer_zone_connections yes)
			)
		)
		(pad "B2" smd circle
			(at -4.5 -4.5 270)
			(size 0.5 0.5)
			(layers "F.Cu" "F.Mask" "F.Paste")
			(net 838 "unconnected-(U45A-INA2+-PadB2)")
			(pinfunction "INA2+")
			(pintype "input+no_connect")
			(solder_mask_margin 0.05)
			(teardrops
				(best_length_ratio 0.4)
				(max_length 1)
				(best_width_ratio 0.9)
				(max_width 2)
				(curved_edges yes)
				(filter_ratio 0.9)
				(enabled yes)
				(allow_two_segments yes)
				(prefer_zone_connections yes)
			)
		)
		(pad "B3" smd circle
			(at -3.5 -4.5 270)
			(size 0.5 0.5)
			(layers "F.Cu" "F.Mask" "F.Paste")
			(net 1 "GND")
			(pinfunction "GND")
			(pintype "passive")
			(solder_mask_margin 0.05)
			(teardrops
				(best_length_ratio 0.4)
				(max_length 1)
				(best_width_ratio 0.9)
				(max_width 2)
				(curved_edges yes)
				(filter_ratio 0.9)
				(enabled yes)
				(allow_two_segments yes)
				(prefer_zone_connections yes)
			)
		)
		(pad "B4" smd circle
			(at -2.5 -4.5 270)
			(size 0.5 0.5)
			(layers "F.Cu" "F.Mask" "F.Paste")
			(net 1 "GND")
			(pinfunction "GND")
			(pintype "passive")
			(solder_mask_margin 0.05)
			(teardrops
				(best_length_ratio 0.4)
				(max_length 1)
				(best_width_ratio 0.9)
				(max_width 2)
				(curved_edges yes)
				(filter_ratio 0.9)
				(enabled yes)
				(allow_two_segments yes)
				(prefer_zone_connections yes)
			)
		)
		(pad "B5" smd circle
			(at -1.5 -4.5 270)
			(size 0.5 0.5)
			(layers "F.Cu" "F.Mask" "F.Paste")
			(net 839 "unconnected-(U45A-OUTA1+-PadB5)")
			(pinfunction "OUTA1+")
			(pintype "output+no_connect")
			(solder_mask_margin 0.05)
			(teardrops
				(best_length_ratio 0.4)
				(max_length 1)
				(best_width_ratio 0.9)
				(max_width 2)
				(curved_edges yes)
				(filter_ratio 0.9)
				(enabled yes)
				(allow_two_segments yes)
				(prefer_zone_connections yes)
			)
		)
		(pad "B6" smd circle
			(at -0.5 -4.5 270)
			(size 0.5 0.5)
			(layers "F.Cu" "F.Mask" "F.Paste")
			(net 840 "unconnected-(U45A-OUTA1--PadB6)")
			(pinfunction "OUTA1-")
			(pintype "output+no_connect")
			(solder_mask_margin 0.05)
			(teardrops
				(best_length_ratio 0.4)
				(max_length 1)
				(best_width_ratio 0.9)
				(max_width 2)
				(curved_edges yes)
				(filter_ratio 0.9)
				(enabled yes)
				(allow_two_segments yes)
				(prefer_zone_connections yes)
			)
		)
		(pad "B7" smd circle
			(at 0.5 -4.5 270)
			(size 0.5 0.5)
			(layers "F.Cu" "F.Mask" "F.Paste")
			(net 1 "GND")
			(pinfunction "GND")
			(pintype "passive")
			(solder_mask_margin 0.05)
			(teardrops
				(best_length_ratio 0.4)
				(max_length 1)
				(best_width_ratio 0.9)
				(max_width 2)
				(curved_edges yes)
				(filter_ratio 0.9)
				(enabled yes)
				(allow_two_segments yes)
				(prefer_zone_connections yes)
			)
		)
		(pad "B8" smd circle
			(at 1.5 -4.5 270)
			(size 0.5 0.5)
			(layers "F.Cu" "F.Mask" "F.Paste")
			(net 744 "/2xSFP+/KR to SFI #2/TMS")
			(pinfunction "TMS")
			(pintype "input")
			(solder_mask_margin 0.05)
			(teardrops
				(best_length_ratio 0.4)
				(max_length 1)
				(best_width_ratio 0.9)
				(max_width 2)
				(curved_edges yes)
				(filter_ratio 0.9)
				(enabled yes)
				(allow_two_segments yes)
				(prefer_zone_connections yes)
			)
		)
		(pad "B9" smd circle
			(at 2.5 -4.5 270)
			(size 0.5 0.5)
			(layers "F.Cu" "F.Mask" "F.Paste")
			(net 673 "/2xSFP+/KR to SFI #2/PRBSEN")
			(pinfunction "PRBSEN")
			(pintype "input")
			(solder_mask_margin 0.05)
			(teardrops
				(best_length_ratio 0.4)
				(max_length 1)
				(best_width_ratio 0.9)
				(max_width 2)
				(curved_edges yes)
				(filter_ratio 0.9)
				(enabled yes)
				(allow_two_segments yes)
				(prefer_zone_connections yes)
			)
		)
		(pad "B10" smd circle
			(at 3.5 -4.5 270)
			(size 0.5 0.5)
			(layers "F.Cu" "F.Mask" "F.Paste")
			(net 755 "Net-(U45A-LS_OK_{IN_A})")
			(pinfunction "LS_OK_{IN_A}")
			(pintype "input")
			(solder_mask_margin 0.05)
			(teardrops
				(best_length_ratio 0.4)
				(max_length 1)
				(best_width_ratio 0.9)
				(max_width 2)
				(curved_edges yes)
				(filter_ratio 0.9)
				(enabled yes)
				(allow_two_segments yes)
				(prefer_zone_connections yes)
			)
		)
		(pad "B11" smd circle
			(at 4.5 -4.5 270)
			(size 0.5 0.5)
			(layers "F.Cu" "F.Mask" "F.Paste")
			(net 1 "GND")
			(pinfunction "GND")
			(pintype "passive")
			(solder_mask_margin 0.05)
			(teardrops
				(best_length_ratio 0.4)
				(max_length 1)
				(best_width_ratio 0.9)
				(max_width 2)
				(curved_edges yes)
				(filter_ratio 0.9)
				(enabled yes)
				(allow_two_segments yes)
				(prefer_zone_connections yes)
			)
		)
		(pad "B12" smd circle
			(at 5.5 -4.5 270)
			(size 0.5 0.5)
			(layers "F.Cu" "F.Mask" "F.Paste")
			(net 120 "/2xSFP+/KR to SFI #2/KR_C.TX+")
			(pinfunction "HSRXA+")
			(pintype "input")
			(solder_mask_margin 0.05)
			(teardrops
				(best_length_ratio 0.4)
				(max_length 1)
				(best_width_ratio 0.9)
				(max_width 2)
				(curved_edges yes)
				(filter_ratio 0.9)
				(enabled yes)
				(allow_two_segments yes)
				(prefer_zone_connections yes)
			)
		)
		(pad "C1" smd circle
			(at -5.5 -3.5 270)
			(size 0.5 0.5)
			(layers "F.Cu" "F.Mask" "F.Paste")
			(net 1 "GND")
			(pinfunction "GND")
			(pintype "passive")
			(solder_mask_margin 0.05)
			(teardrops
				(best_length_ratio 0.4)
				(max_length 1)
				(best_width_ratio 0.9)
				(max_width 2)
				(curved_edges yes)
				(filter_ratio 0.9)
				(enabled yes)
				(allow_two_segments yes)
				(prefer_zone_connections yes)
			)
		)
		(pad "C2" smd circle
			(at -4.5 -3.5 270)
			(size 0.5 0.5)
			(layers "F.Cu" "F.Mask" "F.Paste")
			(net 841 "unconnected-(U45A-INA2--PadC2)")
			(pinfunction "INA2-")
			(pintype "input+no_connect")
			(solder_mask_margin 0.05)
			(teardrops
				(best_length_ratio 0.4)
				(max_length 1)
				(best_width_ratio 0.9)
				(max_width 2)
				(curved_edges yes)
				(filter_ratio 0.9)
				(enabled yes)
				(allow_two_segments yes)
				(prefer_zone_connections yes)
			)
		)
		(pad "C3" smd circle
			(at -3.5 -3.5 270)
			(size 0.5 0.5)
			(layers "F.Cu" "F.Mask" "F.Paste")
			(net 78 "+1V8")
			(pinfunction "VDDRA_{LS/HS}")
			(pintype "power_in")
			(solder_mask_margin 0.05)
			(teardrops
				(best_length_ratio 0.4)
				(max_length 1)
				(best_width_ratio 0.9)
				(max_width 2)
				(curved_edges yes)
				(filter_ratio 0.9)
				(enabled yes)
				(allow_two_segments yes)
				(prefer_zone_connections yes)
			)
		)
		(pad "C4" smd circle
			(at -2.5 -3.5 270)
			(size 0.5 0.5)
			(layers "F.Cu" "F.Mask" "F.Paste")
			(net 842 "unconnected-(U45A-OUTA2+-PadC4)")
			(pinfunction "OUTA2+")
			(pintype "output+no_connect")
			(solder_mask_margin 0.05)
			(teardrops
				(best_length_ratio 0.4)
				(max_length 1)
				(best_width_ratio 0.9)
				(max_width 2)
				(curved_edges yes)
				(filter_ratio 0.9)
				(enabled yes)
				(allow_two_segments yes)
				(prefer_zone_connections yes)
			)
		)
		(pad "C5" smd circle
			(at -1.5 -3.5 270)
			(size 0.5 0.5)
			(layers "F.Cu" "F.Mask" "F.Paste")
			(net 843 "unconnected-(U45A-OUTA2--PadC5)")
			(pinfunction "OUTA2-")
			(pintype "output+no_connect")
			(solder_mask_margin 0.05)
			(teardrops
				(best_length_ratio 0.4)
				(max_length 1)
				(best_width_ratio 0.9)
				(max_width 2)
				(curved_edges yes)
				(filter_ratio 0.9)
				(enabled yes)
				(allow_two_segments yes)
				(prefer_zone_connections yes)
			)
		)
		(pad "C6" smd circle
			(at -0.5 -3.5 270)
			(size 0.5 0.5)
			(layers "F.Cu" "F.Mask" "F.Paste")
			(net 1 "GND")
			(pinfunction "GND")
			(pintype "passive")
			(solder_mask_margin 0.05)
			(teardrops
				(best_length_ratio 0.4)
				(max_length 1)
				(best_width_ratio 0.9)
				(max_width 2)
				(curved_edges yes)
				(filter_ratio 0.9)
				(enabled yes)
				(allow_two_segments yes)
				(prefer_zone_connections yes)
			)
		)
		(pad "C7" smd circle
			(at 0.5 -3.5 270)
			(size 0.5 0.5)
			(layers "F.Cu" "F.Mask" "F.Paste")
			(net 74 "+1V0")
			(pinfunction "VDDO0")
			(pintype "power_in")
			(solder_mask_margin 0.05)
			(teardrops
				(best_length_ratio 0.4)
				(max_length 1)
				(best_width_ratio 0.9)
				(max_width 2)
				(curved_edges yes)
				(filter_ratio 0.9)
				(enabled yes)
				(allow_two_segments yes)
				(prefer_zone_connections yes)
			)
		)
		(pad "C8" smd circle
			(at 1.5 -3.5 270)
			(size 0.5 0.5)
			(layers "F.Cu" "F.Mask" "F.Paste")
			(net 742 "/2xSFP+/KR to SFI #2/TDI")
			(pinfunction "TDI")
			(pintype "input")
			(solder_mask_margin 0.05)
			(teardrops
				(best_length_ratio 0.4)
				(max_length 1)
				(best_width_ratio 0.9)
				(max_width 2)
				(curved_edges yes)
				(filter_ratio 0.9)
				(enabled yes)
				(allow_two_segments yes)
				(prefer_zone_connections yes)
			)
		)
		(pad "C9" smd circle
			(at 2.5 -3.5 270)
			(size 0.5 0.5)
			(layers "F.Cu" "F.Mask" "F.Paste")
			(net 750 "Net-(U45C-CLKOUTA+)")
			(pinfunction "CLKOUTA+")
			(pintype "output")
			(solder_mask_margin 0.05)
			(teardrops
				(best_length_ratio 0.4)
				(max_length 1)
				(best_width_ratio 0.9)
				(max_width 2)
				(curved_edges yes)
				(filter_ratio 0.9)
				(enabled yes)
				(allow_two_segments yes)
				(prefer_zone_connections yes)
			)
		)
		(pad "C10" smd circle
			(at 3.5 -3.5 270)
			(size 0.5 0.5)
			(layers "F.Cu" "F.Mask" "F.Paste")
			(net 751 "Net-(U45C-CLKOUTA-)")
			(pinfunction "CLKOUTA-")
			(pintype "output")
			(solder_mask_margin 0.05)
			(teardrops
				(best_length_ratio 0.4)
				(max_length 1)
				(best_width_ratio 0.9)
				(max_width 2)
				(curved_edges yes)
				(filter_ratio 0.9)
				(enabled yes)
				(allow_two_segments yes)
				(prefer_zone_connections yes)
			)
		)
		(pad "C11" smd circle
			(at 4.5 -3.5 270)
			(size 0.5 0.5)
			(layers "F.Cu" "F.Mask" "F.Paste")
			(net 748 "Net-(U45C-AMUXA)")
			(pinfunction "AMUXA")
			(pintype "passive")
			(solder_mask_margin 0.05)
			(teardrops
				(best_length_ratio 0.4)
				(max_length 1)
				(best_width_ratio 0.9)
				(max_width 2)
				(curved_edges yes)
				(filter_ratio 0.9)
				(enabled yes)
				(allow_two_segments yes)
				(prefer_zone_connections yes)
			)
		)
		(pad "C12" smd circle
			(at 5.5 -3.5 270)
			(size 0.5 0.5)
			(layers "F.Cu" "F.Mask" "F.Paste")
			(net 1 "GND")
			(pinfunction "GND")
			(pintype "passive")
			(solder_mask_margin 0.05)
			(teardrops
				(best_length_ratio 0.4)
				(max_length 1)
				(best_width_ratio 0.9)
				(max_width 2)
				(curved_edges yes)
				(filter_ratio 0.9)
				(enabled yes)
				(allow_two_segments yes)
				(prefer_zone_connections yes)
			)
		)
		(pad "D1" smd circle
			(at -5.5 -2.5 270)
			(size 0.5 0.5)
			(layers "F.Cu" "F.Mask" "F.Paste")
			(net 844 "unconnected-(U45A-INA3+-PadD1)")
			(pinfunction "INA3+")
			(pintype "input+no_connect")
			(solder_mask_margin 0.05)
			(teardrops
				(best_length_ratio 0.4)
				(max_length 1)
				(best_width_ratio 0.9)
				(max_width 2)
				(curved_edges yes)
				(filter_ratio 0.9)
				(enabled yes)
				(allow_two_segments yes)
				(prefer_zone_connections yes)
			)
		)
		(pad "D2" smd circle
			(at -4.5 -2.5 270)
			(size 0.5 0.5)
			(layers "F.Cu" "F.Mask" "F.Paste")
			(net 74 "+1V0")
			(pinfunction "VDDA_{LS/HS}")
			(pintype "power_in")
			(solder_mask_margin 0.05)
			(teardrops
				(best_length_ratio 0.4)
				(max_length 1)
				(best_width_ratio 0.9)
				(max_width 2)
				(curved_edges yes)
				(filter_ratio 0.9)
				(enabled yes)
				(allow_two_segments yes)
				(prefer_zone_connections yes)
			)
		)
		(pad "D3" smd circle
			(at -3.5 -2.5 270)
			(size 0.5 0.5)
			(layers "F.Cu" "F.Mask" "F.Paste")
			(net 1 "GND")
			(pinfunction "GND")
			(pintype "passive")
			(solder_mask_margin 0.05)
			(teardrops
				(best_length_ratio 0.4)
				(max_length 1)
				(best_width_ratio 0.9)
				(max_width 2)
				(curved_edges yes)
				(filter_ratio 0.9)
				(enabled yes)
				(allow_two_segments yes)
				(prefer_zone_connections yes)
			)
		)
		(pad "D4" smd circle
			(at -2.5 -2.5 270)
			(size 0.5 0.5)
			(layers "F.Cu" "F.Mask" "F.Paste")
			(net 749 "Net-(U45C-AMUXB)")
			(pinfunction "AMUXB")
			(pintype "passive")
			(solder_mask_margin 0.05)
			(teardrops
				(best_length_ratio 0.4)
				(max_length 1)
				(best_width_ratio 0.9)
				(max_width 2)
				(curved_edges yes)
				(filter_ratio 0.9)
				(enabled yes)
				(allow_two_segments yes)
				(prefer_zone_connections yes)
			)
		)
		(pad "D5" smd circle
			(at -1.5 -2.5 270)
			(size 0.5 0.5)
			(layers "F.Cu" "F.Mask" "F.Paste")
			(net 1 "GND")
			(pinfunction "GND")
			(pintype "passive")
			(solder_mask_margin 0.05)
			(teardrops
				(best_length_ratio 0.4)
				(max_length 1)
				(best_width_ratio 0.9)
				(max_width 2)
				(curved_edges yes)
				(filter_ratio 0.9)
				(enabled yes)
				(allow_two_segments yes)
				(prefer_zone_connections yes)
			)
		)
		(pad "D6" smd circle
			(at -0.5 -2.5 270)
			(size 0.5 0.5)
			(layers "F.Cu" "F.Mask" "F.Paste")
			(net 743 "/2xSFP+/KR to SFI #2/TDO")
			(pinfunction "TDO")
			(pintype "output")
			(solder_mask_margin 0.05)
			(teardrops
				(best_length_ratio 0.4)
				(max_length 1)
				(best_width_ratio 0.9)
				(max_width 2)
				(curved_edges yes)
				(filter_ratio 0.9)
				(enabled yes)
				(allow_two_segments yes)
				(prefer_zone_connections yes)
			)
		)
		(pad "D7" smd circle
			(at 0.5 -2.5 270)
			(size 0.5 0.5)
			(layers "F.Cu" "F.Mask" "F.Paste")
			(net 74 "+1V0")
			(pinfunction "VPP")
			(pintype "power_in")
			(solder_mask_margin 0.05)
			(teardrops
				(best_length_ratio 0.4)
				(max_length 1)
				(best_width_ratio 0.9)
				(max_width 2)
				(curved_edges yes)
				(filter_ratio 0.9)
				(enabled yes)
				(allow_two_segments yes)
				(prefer_zone_connections yes)
			)
		)
		(pad "D8" smd circle
			(at 1.5 -2.5 270)
			(size 0.5 0.5)
			(layers "F.Cu" "F.Mask" "F.Paste")
			(net 745 "/2xSFP+/KR to SFI #2/TCK")
			(pinfunction "TCK")
			(pintype "input")
			(solder_mask_margin 0.05)
			(teardrops
				(best_length_ratio 0.4)
				(max_length 1)
				(best_width_ratio 0.9)
				(max_width 2)
				(curved_edges yes)
				(filter_ratio 0.9)
				(enabled yes)
				(allow_two_segments yes)
				(prefer_zone_connections yes)
			)
		)
		(pad "D9" smd circle
			(at 2.5 -2.5 270)
			(size 0.5 0.5)
			(layers "F.Cu" "F.Mask" "F.Paste")
			(net 756 "Net-(U45A-LS_OK_{OUT_A})")
			(pinfunction "LS_OK_{OUT_A}")
			(pintype "output")
			(solder_mask_margin 0.05)
			(teardrops
				(best_length_ratio 0.4)
				(max_length 1)
				(best_width_ratio 0.9)
				(max_width 2)
				(curved_edges yes)
				(filter_ratio 0.9)
				(enabled yes)
				(allow_two_segments yes)
				(prefer_zone_connections yes)
			)
		)
		(pad "D10" smd circle
			(at 3.5 -2.5 270)
			(size 0.5 0.5)
			(layers "F.Cu" "F.Mask" "F.Paste")
			(net 1 "GND")
			(pinfunction "GND")
			(pintype "passive")
			(solder_mask_margin 0.05)
			(teardrops
				(best_length_ratio 0.4)
				(max_length 1)
				(best_width_ratio 0.9)
				(max_width 2)
				(curved_edges yes)
				(filter_ratio 0.9)
				(enabled yes)
				(allow_two_segments yes)
				(prefer_zone_connections yes)
			)
		)
		(pad "D11" smd circle
			(at 4.5 -2.5 270)
			(size 0.5 0.5)
			(layers "F.Cu" "F.Mask" "F.Paste")
			(net 1 "GND")
			(pinfunction "GND")
			(pintype "passive")
			(solder_mask_margin 0.05)
			(teardrops
				(best_length_ratio 0.4)
				(max_length 1)
				(best_width_ratio 0.9)
				(max_width 2)
				(curved_edges yes)
				(filter_ratio 0.9)
				(enabled yes)
				(allow_two_segments yes)
				(prefer_zone_connections yes)
			)
		)
		(pad "D12" smd circle
			(at 5.5 -2.5 270)
			(size 0.5 0.5)
			(layers "F.Cu" "F.Mask" "F.Paste")
			(net 687 "/2xSFP+/KR to SFI #2/KR_R.RX+")
			(pinfunction "HSTXA+")
			(pintype "output")
			(solder_mask_margin 0.05)
			(teardrops
				(best_length_ratio 0.4)
				(max_length 1)
				(best_width_ratio 0.9)
				(max_width 2)
				(curved_edges yes)
				(filter_ratio 0.9)
				(enabled yes)
				(allow_two_segments yes)
				(prefer_zone_connections yes)
			)
		)
		(pad "E1" smd circle
			(at -5.5 -1.5 270)
			(size 0.5 0.5)
			(layers "F.Cu" "F.Mask" "F.Paste")
			(net 845 "unconnected-(U45A-INA3--PadE1)")
			(pinfunction "INA3-")
			(pintype "input+no_connect")
			(solder_mask_margin 0.05)
			(teardrops
				(best_length_ratio 0.4)
				(max_length 1)
				(best_width_ratio 0.9)
				(max_width 2)
				(curved_edges yes)
				(filter_ratio 0.9)
				(enabled yes)
				(allow_two_segments yes)
				(prefer_zone_connections yes)
			)
		)
		(pad "E2" smd circle
			(at -4.5 -1.5 270)
			(size 0.5 0.5)
			(layers "F.Cu" "F.Mask" "F.Paste")
			(net 1 "GND")
			(pinfunction "GND")
			(pintype "passive")
			(solder_mask_margin 0.05)
			(teardrops
				(best_length_ratio 0.4)
				(max_length 1)
				(best_width_ratio 0.9)
				(max_width 2)
				(curved_edges yes)
				(filter_ratio 0.9)
				(enabled yes)
				(allow_two_segments yes)
				(prefer_zone_connections yes)
			)
		)
		(pad "E3" smd circle
			(at -3.5 -1.5 270)
			(size 0.5 0.5)
			(layers "F.Cu" "F.Mask" "F.Paste")
			(net 846 "unconnected-(U45A-OUTA3--PadE3)")
			(pinfunction "OUTA3-")
			(pintype "output+no_connect")
			(solder_mask_margin 0.05)
			(teardrops
				(best_length_ratio 0.4)
				(max_length 1)
				(best_width_ratio 0.9)
				(max_width 2)
				(curved_edges yes)
				(filter_ratio 0.9)
				(enabled yes)
				(allow_two_segments yes)
				(prefer_zone_connections yes)
			)
		)
		(pad "E4" smd circle
			(at -2.5 -1.5 270)
			(size 0.5 0.5)
			(layers "F.Cu" "F.Mask" "F.Paste")
			(net 1 "GND")
			(pinfunction "GND")
			(pintype "passive")
			(solder_mask_margin 0.05)
			(teardrops
				(best_length_ratio 0.4)
				(max_length 1)
				(best_width_ratio 0.9)
				(max_width 2)
				(curved_edges yes)
				(filter_ratio 0.9)
				(enabled yes)
				(allow_two_segments yes)
				(prefer_zone_connections yes)
			)
		)
		(pad "E5" smd circle
			(at -1.5 -1.5 270)
			(size 0.5 0.5)
			(layers "F.Cu" "F.Mask" "F.Paste")
			(net 746 "/2xSFP+/KR to SFI #2/~{TRST}")
			(pinfunction "~{TRST}")
			(pintype "input")
			(solder_mask_margin 0.05)
			(teardrops
				(best_length_ratio 0.4)
				(max_length 1)
				(best_width_ratio 0.9)
				(max_width 2)
				(curved_edges yes)
				(filter_ratio 0.9)
				(enabled yes)
				(allow_two_segments yes)
				(prefer_zone_connections yes)
			)
		)
		(pad "E6" smd circle
			(at -0.5 -1.5 270)
			(size 0.5 0.5)
			(layers "F.Cu" "F.Mask" "F.Paste")
			(net 74 "+1V0")
			(pinfunction "VDDD")
			(pintype "power_in")
			(solder_mask_margin 0.05)
			(teardrops
				(best_length_ratio 0.4)
				(max_length 1)
				(best_width_ratio 0.9)
				(max_width 2)
				(curved_edges yes)
				(filter_ratio 0.9)
				(enabled yes)
				(allow_two_segments yes)
				(prefer_zone_connections yes)
			)
		)
		(pad "E7" smd circle
			(at 0.5 -1.5 270)
			(size 0.5 0.5)
			(layers "F.Cu" "F.Mask" "F.Paste")
			(net 74 "+1V0")
			(pinfunction "DVDD")
			(pintype "power_in")
			(solder_mask_margin 0.05)
			(teardrops
				(best_length_ratio 0.4)
				(max_length 1)
				(best_width_ratio 0.9)
				(max_width 2)
				(curved_edges yes)
				(filter_ratio 0.9)
				(enabled yes)
				(allow_two_segments yes)
				(prefer_zone_connections yes)
			)
		)
		(pad "E8" smd circle
			(at 1.5 -1.5 270)
			(size 0.5 0.5)
			(layers "F.Cu" "F.Mask" "F.Paste")
			(net 74 "+1V0")
			(pinfunction "VDDD")
			(pintype "passive")
			(solder_mask_margin 0.05)
			(teardrops
				(best_length_ratio 0.4)
				(max_length 1)
				(best_width_ratio 0.9)
				(max_width 2)
				(curved_edges yes)
				(filter_ratio 0.9)
				(enabled yes)
				(allow_two_segments yes)
				(prefer_zone_connections yes)
			)
		)
		(pad "E9" smd circle
			(at 2.5 -1.5 270)
			(size 0.5 0.5)
			(layers "F.Cu" "F.Mask" "F.Paste")
			(net 754 "Net-(U45A-LOSA)")
			(pinfunction "LOSA")
			(pintype "output")
			(solder_mask_margin 0.05)
			(teardrops
				(best_length_ratio 0.4)
				(max_length 1)
				(best_width_ratio 0.9)
				(max_width 2)
				(curved_edges yes)
				(filter_ratio 0.9)
				(enabled yes)
				(allow_two_segments yes)
				(prefer_zone_connections yes)
			)
		)
		(pad "E10" smd circle
			(at 3.5 -1.5 270)
			(size 0.5 0.5)
			(layers "F.Cu" "F.Mask" "F.Paste")
			(net 676 "Net-(U45C-PRTAD0)")
			(pinfunction "PRTAD0")
			(pintype "input")
			(solder_mask_margin 0.05)
			(teardrops
				(best_length_ratio 0.4)
				(max_length 1)
				(best_width_ratio 0.9)
				(max_width 2)
				(curved_edges yes)
				(filter_ratio 0.9)
				(enabled yes)
				(allow_two_segments yes)
				(prefer_zone_connections yes)
			)
		)
		(pad "E11" smd circle
			(at 4.5 -1.5 270)
			(size 0.5 0.5)
			(layers "F.Cu" "F.Mask" "F.Paste")
			(net 78 "+1V8")
			(pinfunction "VDDRA_{LS/HS}")
			(pintype "passive")
			(solder_mask_margin 0.05)
			(teardrops
				(best_length_ratio 0.4)
				(max_length 1)
				(best_width_ratio 0.9)
				(max_width 2)
				(curved_edges yes)
				(filter_ratio 0.9)
				(enabled yes)
				(allow_two_segments yes)
				(prefer_zone_connections yes)
			)
		)
		(pad "E12" smd circle
			(at 5.5 -1.5 270)
			(size 0.5 0.5)
			(layers "F.Cu" "F.Mask" "F.Paste")
			(net 688 "/2xSFP+/KR to SFI #2/KR_R.RX-")
			(pinfunction "HSTXA-")
			(pintype "output")
			(solder_mask_margin 0.05)
			(teardrops
				(best_length_ratio 0.4)
				(max_length 1)
				(best_width_ratio 0.9)
				(max_width 2)
				(curved_edges yes)
				(filter_ratio 0.9)
				(enabled yes)
				(allow_two_segments yes)
				(prefer_zone_connections yes)
			)
		)
		(pad "F1" smd circle
			(at -5.5 -0.5 270)
			(size 0.5 0.5)
			(layers "F.Cu" "F.Mask" "F.Paste")
			(net 1 "GND")
			(pinfunction "GND")
			(pintype "passive")
			(solder_mask_margin 0.05)
			(teardrops
				(best_length_ratio 0.4)
				(max_length 1)
				(best_width_ratio 0.9)
				(max_width 2)
				(curved_edges yes)
				(filter_ratio 0.9)
				(enabled yes)
				(allow_two_segments yes)
				(prefer_zone_connections yes)
			)
		)
		(pad "F2" smd circle
			(at -4.5 -0.5 270)
			(size 0.5 0.5)
			(layers "F.Cu" "F.Mask" "F.Paste")
			(net 74 "+1V0")
			(pinfunction "VDDA_{LS/HS}")
			(pintype "passive")
			(solder_mask_margin 0.05)
			(teardrops
				(best_length_ratio 0.4)
				(max_length 1)
				(best_width_ratio 0.9)
				(max_width 2)
				(curved_edges yes)
				(filter_ratio 0.9)
				(enabled yes)
				(allow_two_segments yes)
				(prefer_zone_connections yes)
			)
		)
		(pad "F3" smd circle
			(at -3.5 -0.5 270)
			(size 0.5 0.5)
			(layers "F.Cu" "F.Mask" "F.Paste")
			(net 847 "unconnected-(U45A-OUTA3+-PadF3)")
			(pinfunction "OUTA3+")
			(pintype "output+no_connect")
			(solder_mask_margin 0.05)
			(teardrops
				(best_length_ratio 0.4)
				(max_length 1)
				(best_width_ratio 0.9)
				(max_width 2)
				(curved_edges yes)
				(filter_ratio 0.9)
				(enabled yes)
				(allow_two_segments yes)
				(prefer_zone_connections yes)
			)
		)
		(pad "F4" smd circle
			(at -2.5 -0.5 270)
			(size 0.5 0.5)
			(layers "F.Cu" "F.Mask" "F.Paste")
			(net 74 "+1V0")
			(pinfunction "VDDT_{LS/HS}")
			(pintype "power_in")
			(solder_mask_margin 0.05)
			(teardrops
				(best_length_ratio 0.4)
				(max_length 1)
				(best_width_ratio 0.9)
				(max_width 2)
				(curved_edges yes)
				(filter_ratio 0.9)
				(enabled yes)
				(allow_two_segments yes)
				(prefer_zone_connections yes)
			)
		)
		(pad "F5" smd circle
			(at -1.5 -0.5 270)
			(size 0.5 0.5)
			(layers "F.Cu" "F.Mask" "F.Paste")
			(net 1 "GND")
			(pinfunction "GND")
			(pintype "passive")
			(solder_mask_margin 0.05)
			(teardrops
				(best_length_ratio 0.4)
				(max_length 1)
				(best_width_ratio 0.9)
				(max_width 2)
				(curved_edges yes)
				(filter_ratio 0.9)
				(enabled yes)
				(allow_two_segments yes)
				(prefer_zone_connections yes)
			)
		)
		(pad "F6" smd circle
			(at -0.5 -0.5 270)
			(size 0.5 0.5)
			(layers "F.Cu" "F.Mask" "F.Paste")
			(net 74 "+1V0")
			(pinfunction "VDDD")
			(pintype "passive")
			(solder_mask_margin 0.05)
			(teardrops
				(best_length_ratio 0.4)
				(max_length 1)
				(best_width_ratio 0.9)
				(max_width 2)
				(curved_edges yes)
				(filter_ratio 0.9)
				(enabled yes)
				(allow_two_segments yes)
				(prefer_zone_connections yes)
			)
		)
		(pad "F7" smd circle
			(at 0.5 -0.5 270)
			(size 0.5 0.5)
			(layers "F.Cu" "F.Mask" "F.Paste")
			(net 74 "+1V0")
			(pinfunction "DVDD")
			(pintype "passive")
			(solder_mask_margin 0.05)
			(teardrops
				(best_length_ratio 0.4)
				(max_length 1)
				(best_width_ratio 0.9)
				(max_width 2)
				(curved_edges yes)
				(filter_ratio 0.9)
				(enabled yes)
				(allow_two_segments yes)
				(prefer_zone_connections yes)
			)
		)
		(pad "F8" smd circle
			(at 1.5 -0.5 270)
			(size 0.5 0.5)
			(layers "F.Cu" "F.Mask" "F.Paste")
			(net 1 "GND")
			(pinfunction "GND")
			(pintype "passive")
			(solder_mask_margin 0.05)
			(teardrops
				(best_length_ratio 0.4)
				(max_length 1)
				(best_width_ratio 0.9)
				(max_width 2)
				(curved_edges yes)
				(filter_ratio 0.9)
				(enabled yes)
				(allow_two_segments yes)
				(prefer_zone_connections yes)
			)
		)
		(pad "F9" smd circle
			(at 2.5 -0.5 270)
			(size 0.5 0.5)
			(layers "F.Cu" "F.Mask" "F.Paste")
			(net 74 "+1V0")
			(pinfunction "VDDT_{LS/HS}")
			(pintype "passive")
			(solder_mask_margin 0.05)
			(teardrops
				(best_length_ratio 0.4)
				(max_length 1)
				(best_width_ratio 0.9)
				(max_width 2)
				(curved_edges yes)
				(filter_ratio 0.9)
				(enabled yes)
				(allow_two_segments yes)
				(prefer_zone_connections yes)
			)
		)
		(pad "F10" smd circle
			(at 3.5 -0.5 270)
			(size 0.5 0.5)
			(layers "F.Cu" "F.Mask" "F.Paste")
			(net 1 "GND")
			(pinfunction "GND")
			(pintype "passive")
			(solder_mask_margin 0.05)
			(teardrops
				(best_length_ratio 0.4)
				(max_length 1)
				(best_width_ratio 0.9)
				(max_width 2)
				(curved_edges yes)
				(filter_ratio 0.9)
				(enabled yes)
				(allow_two_segments yes)
				(prefer_zone_connections yes)
			)
		)
		(pad "F11" smd circle
			(at 4.5 -0.5 270)
			(size 0.5 0.5)
			(layers "F.Cu" "F.Mask" "F.Paste")
			(net 74 "+1V0")
			(pinfunction "VDDA_{LS/HS}")
			(pintype "passive")
			(solder_mask_margin 0.05)
			(teardrops
				(best_length_ratio 0.4)
				(max_length 1)
				(best_width_ratio 0.9)
				(max_width 2)
				(curved_edges yes)
				(filter_ratio 0.9)
				(enabled yes)
				(allow_two_segments yes)
				(prefer_zone_connections yes)
			)
		)
		(pad "F12" smd circle
			(at 5.5 -0.5 270)
			(size 0.5 0.5)
			(layers "F.Cu" "F.Mask" "F.Paste")
			(net 1 "GND")
			(pinfunction "GND")
			(pintype "passive")
			(solder_mask_margin 0.05)
			(teardrops
				(best_length_ratio 0.4)
				(max_length 1)
				(best_width_ratio 0.9)
				(max_width 2)
				(curved_edges yes)
				(filter_ratio 0.9)
				(enabled yes)
				(allow_two_segments yes)
				(prefer_zone_connections yes)
			)
		)
		(pad "G1" smd circle
			(at -5.5 0.5 270)
			(size 0.5 0.5)
			(layers "F.Cu" "F.Mask" "F.Paste")
			(net 1 "GND")
			(pinfunction "GND")
			(pintype "passive")
			(solder_mask_margin 0.05)
			(teardrops
				(best_length_ratio 0.4)
				(max_length 1)
				(best_width_ratio 0.9)
				(max_width 2)
				(curved_edges yes)
				(filter_ratio 0.9)
				(enabled yes)
				(allow_two_segments yes)
				(prefer_zone_connections yes)
			)
		)
		(pad "G2" smd circle
			(at -4.5 0.5 270)
			(size 0.5 0.5)
			(layers "F.Cu" "F.Mask" "F.Paste")
			(net 74 "+1V0")
			(pinfunction "VDDA_{LS/HS}")
			(pintype "passive")
			(solder_mask_margin 0.05)
			(teardrops
				(best_length_ratio 0.4)
				(max_length 1)
				(best_width_ratio 0.9)
				(max_width 2)
				(curved_edges yes)
				(filter_ratio 0.9)
				(enabled yes)
				(allow_two_segments yes)
				(prefer_zone_connections yes)
			)
		)
		(pad "G3" smd circle
			(at -3.5 0.5 270)
			(size 0.5 0.5)
			(layers "F.Cu" "F.Mask" "F.Paste")
			(net 1 "GND")
			(pinfunction "GND")
			(pintype "passive")
			(solder_mask_margin 0.05)
			(teardrops
				(best_length_ratio 0.4)
				(max_length 1)
				(best_width_ratio 0.9)
				(max_width 2)
				(curved_edges yes)
				(filter_ratio 0.9)
				(enabled yes)
				(allow_two_segments yes)
				(prefer_zone_connections yes)
			)
		)
		(pad "G4" smd circle
			(at -2.5 0.5 270)
			(size 0.5 0.5)
			(layers "F.Cu" "F.Mask" "F.Paste")
			(net 74 "+1V0")
			(pinfunction "VDDT_{LS/HS}")
			(pintype "passive")
			(solder_mask_margin 0.05)
			(teardrops
				(best_length_ratio 0.4)
				(max_length 1)
				(best_width_ratio 0.9)
				(max_width 2)
				(curved_edges yes)
				(filter_ratio 0.9)
				(enabled yes)
				(allow_two_segments yes)
				(prefer_zone_connections yes)
			)
		)
		(pad "G5" smd circle
			(at -1.5 0.5 270)
			(size 0.5 0.5)
			(layers "F.Cu" "F.Mask" "F.Paste")
			(net 1 "GND")
			(pinfunction "GND")
			(pintype "passive")
			(solder_mask_margin 0.05)
			(teardrops
				(best_length_ratio 0.4)
				(max_length 1)
				(best_width_ratio 0.9)
				(max_width 2)
				(curved_edges yes)
				(filter_ratio 0.9)
				(enabled yes)
				(allow_two_segments yes)
				(prefer_zone_connections yes)
			)
		)
		(pad "G6" smd circle
			(at -0.5 0.5 270)
			(size 0.5 0.5)
			(layers "F.Cu" "F.Mask" "F.Paste")
			(net 74 "+1V0")
			(pinfunction "DVDD")
			(pintype "passive")
			(solder_mask_margin 0.05)
			(teardrops
				(best_length_ratio 0.4)
				(max_length 1)
				(best_width_ratio 0.9)
				(max_width 2)
				(curved_edges yes)
				(filter_ratio 0.9)
				(enabled yes)
				(allow_two_segments yes)
				(prefer_zone_connections yes)
			)
		)
		(pad "G7" smd circle
			(at 0.5 0.5 270)
			(size 0.5 0.5)
			(layers "F.Cu" "F.Mask" "F.Paste")
			(net 1 "GND")
			(pinfunction "GND")
			(pintype "passive")
			(solder_mask_margin 0.05)
			(teardrops
				(best_length_ratio 0.4)
				(max_length 1)
				(best_width_ratio 0.9)
				(max_width 2)
				(curved_edges yes)
				(filter_ratio 0.9)
				(enabled yes)
				(allow_two_segments yes)
				(prefer_zone_connections yes)
			)
		)
		(pad "G8" smd circle
			(at 1.5 0.5 270)
			(size 0.5 0.5)
			(layers "F.Cu" "F.Mask" "F.Paste")
			(net 74 "+1V0")
			(pinfunction "DVDD")
			(pintype "passive")
			(solder_mask_margin 0.05)
			(teardrops
				(best_length_ratio 0.4)
				(max_length 1)
				(best_width_ratio 0.9)
				(max_width 2)
				(curved_edges yes)
				(filter_ratio 0.9)
				(enabled yes)
				(allow_two_segments yes)
				(prefer_zone_connections yes)
			)
		)
		(pad "G9" smd circle
			(at 2.5 0.5 270)
			(size 0.5 0.5)
			(layers "F.Cu" "F.Mask" "F.Paste")
			(net 677 "Net-(U45C-PRTAD1)")
			(pinfunction "PRTAD1")
			(pintype "input")
			(solder_mask_margin 0.05)
			(teardrops
				(best_length_ratio 0.4)
				(max_length 1)
				(best_width_ratio 0.9)
				(max_width 2)
				(curved_edges yes)
				(filter_ratio 0.9)
				(enabled yes)
				(allow_two_segments yes)
				(prefer_zone_connections yes)
			)
		)
		(pad "G10" smd circle
			(at 3.5 0.5 270)
			(size 0.5 0.5)
			(layers "F.Cu" "F.Mask" "F.Paste")
			(net 74 "+1V0")
			(pinfunction "VDDA_{LS/HS}")
			(pintype "passive")
			(solder_mask_margin 0.05)
			(teardrops
				(best_length_ratio 0.4)
				(max_length 1)
				(best_width_ratio 0.9)
				(max_width 2)
				(curved_edges yes)
				(filter_ratio 0.9)
				(enabled yes)
				(allow_two_segments yes)
				(prefer_zone_connections yes)
			)
		)
		(pad "G11" smd circle
			(at 4.5 0.5 270)
			(size 0.5 0.5)
			(layers "F.Cu" "F.Mask" "F.Paste")
			(net 1 "GND")
			(pinfunction "GND")
			(pintype "passive")
			(solder_mask_margin 0.05)
			(teardrops
				(best_length_ratio 0.4)
				(max_length 1)
				(best_width_ratio 0.9)
				(max_width 2)
				(curved_edges yes)
				(filter_ratio 0.9)
				(enabled yes)
				(allow_two_segments yes)
				(prefer_zone_connections yes)
			)
		)
		(pad "G12" smd circle
			(at 5.5 0.5 270)
			(size 0.5 0.5)
			(layers "F.Cu" "F.Mask" "F.Paste")
			(net 953 "/2xSFP+/KR to SFI #2/SFI_R.RX-")
			(pinfunction "HSRXB-")
			(pintype "input")
			(solder_mask_margin 0.05)
			(teardrops
				(best_length_ratio 0.4)
				(max_length 1)
				(best_width_ratio 0.9)
				(max_width 2)
				(curved_edges yes)
				(filter_ratio 0.9)
				(enabled yes)
				(allow_two_segments yes)
				(prefer_zone_connections yes)
			)
		)
		(pad "H1" smd circle
			(at -5.5 1.5 270)
			(size 0.5 0.5)
			(layers "F.Cu" "F.Mask" "F.Paste")
			(net 848 "unconnected-(U45B-INB0+-PadH1)")
			(pinfunction "INB0+")
			(pintype "input+no_connect")
			(solder_mask_margin 0.05)
			(teardrops
				(best_length_ratio 0.4)
				(max_length 1)
				(best_width_ratio 0.9)
				(max_width 2)
				(curved_edges yes)
				(filter_ratio 0.9)
				(enabled yes)
				(allow_two_segments yes)
				(prefer_zone_connections yes)
			)
		)
		(pad "H2" smd circle
			(at -4.5 1.5 270)
			(size 0.5 0.5)
			(layers "F.Cu" "F.Mask" "F.Paste")
			(net 1 "GND")
			(pinfunction "GND")
			(pintype "passive")
			(solder_mask_margin 0.05)
			(teardrops
				(best_length_ratio 0.4)
				(max_length 1)
				(best_width_ratio 0.9)
				(max_width 2)
				(curved_edges yes)
				(filter_ratio 0.9)
				(enabled yes)
				(allow_two_segments yes)
				(prefer_zone_connections yes)
			)
		)
		(pad "H3" smd circle
			(at -3.5 1.5 270)
			(size 0.5 0.5)
			(layers "F.Cu" "F.Mask" "F.Paste")
			(net 849 "unconnected-(U45B-OUTB0--PadH3)")
			(pinfunction "OUTB0-")
			(pintype "output+no_connect")
			(solder_mask_margin 0.05)
			(teardrops
				(best_length_ratio 0.4)
				(max_length 1)
				(best_width_ratio 0.9)
				(max_width 2)
				(curved_edges yes)
				(filter_ratio 0.9)
				(enabled yes)
				(allow_two_segments yes)
				(prefer_zone_connections yes)
			)
		)
		(pad "H4" smd circle
			(at -2.5 1.5 270)
			(size 0.5 0.5)
			(layers "F.Cu" "F.Mask" "F.Paste")
			(net 1 "GND")
			(pinfunction "GND")
			(pintype "passive")
			(solder_mask_margin 0.05)
			(teardrops
				(best_length_ratio 0.4)
				(max_length 1)
				(best_width_ratio 0.9)
				(max_width 2)
				(curved_edges yes)
				(filter_ratio 0.9)
				(enabled yes)
				(allow_two_segments yes)
				(prefer_zone_connections yes)
			)
		)
		(pad "H5" smd circle
			(at -1.5 1.5 270)
			(size 0.5 0.5)
			(layers "F.Cu" "F.Mask" "F.Paste")
			(net 143 "/2xSFP+/KR to SFI #2/~{RESET}")
			(pinfunction "~{RESET}")
			(pintype "input")
			(solder_mask_margin 0.05)
			(teardrops
				(best_length_ratio 0.4)
				(max_length 1)
				(best_width_ratio 0.9)
				(max_width 2)
				(curved_edges yes)
				(filter_ratio 0.9)
				(enabled yes)
				(allow_two_segments yes)
				(prefer_zone_connections yes)
			)
		)
		(pad "H6" smd circle
			(at -0.5 1.5 270)
			(size 0.5 0.5)
			(layers "F.Cu" "F.Mask" "F.Paste")
			(net 74 "+1V0")
			(pinfunction "VDDD")
			(pintype "passive")
			(solder_mask_margin 0.05)
			(teardrops
				(best_length_ratio 0.4)
				(max_length 1)
				(best_width_ratio 0.9)
				(max_width 2)
				(curved_edges yes)
				(filter_ratio 0.9)
				(enabled yes)
				(allow_two_segments yes)
				(prefer_zone_connections yes)
			)
		)
		(pad "H7" smd circle
			(at 0.5 1.5 270)
			(size 0.5 0.5)
			(layers "F.Cu" "F.Mask" "F.Paste")
			(net 74 "+1V0")
			(pinfunction "DVDD")
			(pintype "passive")
			(solder_mask_margin 0.05)
			(teardrops
				(best_length_ratio 0.4)
				(max_length 1)
				(best_width_ratio 0.9)
				(max_width 2)
				(curved_edges yes)
				(filter_ratio 0.9)
				(enabled yes)
				(allow_two_segments yes)
				(prefer_zone_connections yes)
			)
		)
		(pad "H8" smd circle
			(at 1.5 1.5 270)
			(size 0.5 0.5)
			(layers "F.Cu" "F.Mask" "F.Paste")
			(net 74 "+1V0")
			(pinfunction "VDDD")
			(pintype "passive")
			(solder_mask_margin 0.05)
			(teardrops
				(best_length_ratio 0.4)
				(max_length 1)
				(best_width_ratio 0.9)
				(max_width 2)
				(curved_edges yes)
				(filter_ratio 0.9)
				(enabled yes)
				(allow_two_segments yes)
				(prefer_zone_connections yes)
			)
		)
		(pad "H9" smd circle
			(at 2.5 1.5 270)
			(size 0.5 0.5)
			(layers "F.Cu" "F.Mask" "F.Paste")
			(net 759 "Net-(U45B-LS_OK_{OUT_B})")
			(pinfunction "LS_OK_{OUT_B}")
			(pintype "output")
			(solder_mask_margin 0.05)
			(teardrops
				(best_length_ratio 0.4)
				(max_length 1)
				(best_width_ratio 0.9)
				(max_width 2)
				(curved_edges yes)
				(filter_ratio 0.9)
				(enabled yes)
				(allow_two_segments yes)
				(prefer_zone_connections yes)
			)
		)
		(pad "H10" smd circle
			(at 3.5 1.5 270)
			(size 0.5 0.5)
			(layers "F.Cu" "F.Mask" "F.Paste")
			(net 683 "Net-(U45C-MODE_{SEL})")
			(pinfunction "MODE_{SEL}")
			(pintype "input")
			(solder_mask_margin 0.05)
			(teardrops
				(best_length_ratio 0.4)
				(max_length 1)
				(best_width_ratio 0.9)
				(max_width 2)
				(curved_edges yes)
				(filter_ratio 0.9)
				(enabled yes)
				(allow_two_segments yes)
				(prefer_zone_connections yes)
			)
		)
		(pad "H11" smd circle
			(at 4.5 1.5 270)
			(size 0.5 0.5)
			(layers "F.Cu" "F.Mask" "F.Paste")
			(net 1 "GND")
			(pinfunction "GND")
			(pintype "passive")
			(solder_mask_margin 0.05)
			(teardrops
				(best_length_ratio 0.4)
				(max_length 1)
				(best_width_ratio 0.9)
				(max_width 2)
				(curved_edges yes)
				(filter_ratio 0.9)
				(enabled yes)
				(allow_two_segments yes)
				(prefer_zone_connections yes)
			)
		)
		(pad "H12" smd circle
			(at 5.5 1.5 270)
			(size 0.5 0.5)
			(layers "F.Cu" "F.Mask" "F.Paste")
			(net 950 "/2xSFP+/KR to SFI #2/SFI_R.RX+")
			(pinfunction "HSRXB+")
			(pintype "input")
			(solder_mask_margin 0.05)
			(teardrops
				(best_length_ratio 0.4)
				(max_length 1)
				(best_width_ratio 0.9)
				(max_width 2)
				(curved_edges yes)
				(filter_ratio 0.9)
				(enabled yes)
				(allow_two_segments yes)
				(prefer_zone_connections yes)
			)
		)
		(pad "J1" smd circle
			(at -5.5 2.5 270)
			(size 0.5 0.5)
			(layers "F.Cu" "F.Mask" "F.Paste")
			(net 850 "unconnected-(U45B-INB0--PadJ1)")
			(pinfunction "INB0-")
			(pintype "input+no_connect")
			(solder_mask_margin 0.05)
			(teardrops
				(best_length_ratio 0.4)
				(max_length 1)
				(best_width_ratio 0.9)
				(max_width 2)
				(curved_edges yes)
				(filter_ratio 0.9)
				(enabled yes)
				(allow_two_segments yes)
				(prefer_zone_connections yes)
			)
		)
		(pad "J2" smd circle
			(at -4.5 2.5 270)
			(size 0.5 0.5)
			(layers "F.Cu" "F.Mask" "F.Paste")
			(net 74 "+1V0")
			(pinfunction "VDDA_{LS/HS}")
			(pintype "passive")
			(solder_mask_margin 0.05)
			(teardrops
				(best_length_ratio 0.4)
				(max_length 1)
				(best_width_ratio 0.9)
				(max_width 2)
				(curved_edges yes)
				(filter_ratio 0.9)
				(enabled yes)
				(allow_two_segments yes)
				(prefer_zone_connections yes)
			)
		)
		(pad "J3" smd circle
			(at -3.5 2.5 270)
			(size 0.5 0.5)
			(layers "F.Cu" "F.Mask" "F.Paste")
			(net 851 "unconnected-(U45B-OUTB0+-PadJ3)")
			(pinfunction "OUTB0+")
			(pintype "output+no_connect")
			(solder_mask_margin 0.05)
			(teardrops
				(best_length_ratio 0.4)
				(max_length 1)
				(best_width_ratio 0.9)
				(max_width 2)
				(curved_edges yes)
				(filter_ratio 0.9)
				(enabled yes)
				(allow_two_segments yes)
				(prefer_zone_connections yes)
			)
		)
		(pad "J4" smd circle
			(at -2.5 2.5 270)
			(size 0.5 0.5)
			(layers "F.Cu" "F.Mask" "F.Paste")
			(net 681 "Net-(U45B-~{PDTRXB})")
			(pinfunction "~{PDTRXB}")
			(pintype "input")
			(solder_mask_margin 0.05)
			(teardrops
				(best_length_ratio 0.4)
				(max_length 1)
				(best_width_ratio 0.9)
				(max_width 2)
				(curved_edges yes)
				(filter_ratio 0.9)
				(enabled yes)
				(allow_two_segments yes)
				(prefer_zone_connections yes)
			)
		)
		(pad "J5" smd circle
			(at -1.5 2.5 270)
			(size 0.5 0.5)
			(layers "F.Cu" "F.Mask" "F.Paste")
			(net 1 "GND")
			(pinfunction "GND")
			(pintype "passive")
			(solder_mask_margin 0.05)
			(teardrops
				(best_length_ratio 0.4)
				(max_length 1)
				(best_width_ratio 0.9)
				(max_width 2)
				(curved_edges yes)
				(filter_ratio 0.9)
				(enabled yes)
				(allow_two_segments yes)
				(prefer_zone_connections yes)
			)
		)
		(pad "J6" smd circle
			(at -0.5 2.5 270)
			(size 0.5 0.5)
			(layers "F.Cu" "F.Mask" "F.Paste")
			(net 680 "Net-(U45C-PRTAD3)")
			(pinfunction "PRTAD3")
			(pintype "input")
			(solder_mask_margin 0.05)
			(teardrops
				(best_length_ratio 0.4)
				(max_length 1)
				(best_width_ratio 0.9)
				(max_width 2)
				(curved_edges yes)
				(filter_ratio 0.9)
				(enabled yes)
				(allow_two_segments yes)
				(prefer_zone_connections yes)
			)
		)
		(pad "J7" smd circle
			(at 0.5 2.5 270)
			(size 0.5 0.5)
			(layers "F.Cu" "F.Mask" "F.Paste")
			(net 670 "/2xSFP+/KR to SFI #2/MDIO")
			(pinfunction "MDIO")
			(pintype "bidirectional")
			(solder_mask_margin 0.05)
			(teardrops
				(best_length_ratio 0.4)
				(max_length 1)
				(best_width_ratio 0.9)
				(max_width 2)
				(curved_edges yes)
				(filter_ratio 0.9)
				(enabled yes)
				(allow_two_segments yes)
				(prefer_zone_connections yes)
			)
		)
		(pad "J8" smd circle
			(at 1.5 2.5 270)
			(size 0.5 0.5)
			(layers "F.Cu" "F.Mask" "F.Paste")
			(net 672 "/2xSFP+/KR to SFI #2/MDC")
			(pinfunction "MDC")
			(pintype "input")
			(solder_mask_margin 0.05)
			(teardrops
				(best_length_ratio 0.4)
				(max_length 1)
				(best_width_ratio 0.9)
				(max_width 2)
				(curved_edges yes)
				(filter_ratio 0.9)
				(enabled yes)
				(allow_two_segments yes)
				(prefer_zone_connections yes)
			)
		)
		(pad "J9" smd circle
			(at 2.5 2.5 270)
			(size 0.5 0.5)
			(layers "F.Cu" "F.Mask" "F.Paste")
			(net 747 "Net-(U45C-PRBS_{PASS})")
			(pinfunction "PRBS_{PASS}")
			(pintype "output")
			(solder_mask_margin 0.05)
			(teardrops
				(best_length_ratio 0.4)
				(max_length 1)
				(best_width_ratio 0.9)
				(max_width 2)
				(curved_edges yes)
				(filter_ratio 0.9)
				(enabled yes)
				(allow_two_segments yes)
				(prefer_zone_connections yes)
			)
		)
		(pad "J10" smd circle
			(at 3.5 2.5 270)
			(size 0.5 0.5)
			(layers "F.Cu" "F.Mask" "F.Paste")
			(net 675 "Net-(U45C-GPI0)")
			(pinfunction "GPI0")
			(pintype "input")
			(solder_mask_margin 0.05)
			(teardrops
				(best_length_ratio 0.4)
				(max_length 1)
				(best_width_ratio 0.9)
				(max_width 2)
				(curved_edges yes)
				(filter_ratio 0.9)
				(enabled yes)
				(allow_two_segments yes)
				(prefer_zone_connections yes)
			)
		)
		(pad "J11" smd circle
			(at 4.5 2.5 270)
			(size 0.5 0.5)
			(layers "F.Cu" "F.Mask" "F.Paste")
			(net 78 "+1V8")
			(pinfunction "VDDRB_{LS/HS}")
			(pintype "power_in")
			(solder_mask_margin 0.05)
			(teardrops
				(best_length_ratio 0.4)
				(max_length 1)
				(best_width_ratio 0.9)
				(max_width 2)
				(curved_edges yes)
				(filter_ratio 0.9)
				(enabled yes)
				(allow_two_segments yes)
				(prefer_zone_connections yes)
			)
		)
		(pad "J12" smd circle
			(at 5.5 2.5 270)
			(size 0.5 0.5)
			(layers "F.Cu" "F.Mask" "F.Paste")
			(net 1 "GND")
			(pinfunction "GND")
			(pintype "passive")
			(solder_mask_margin 0.05)
			(teardrops
				(best_length_ratio 0.4)
				(max_length 1)
				(best_width_ratio 0.9)
				(max_width 2)
				(curved_edges yes)
				(filter_ratio 0.9)
				(enabled yes)
				(allow_two_segments yes)
				(prefer_zone_connections yes)
			)
		)
		(pad "K1" smd circle
			(at -5.5 3.5 270)
			(size 0.5 0.5)
			(layers "F.Cu" "F.Mask" "F.Paste")
			(net 1 "GND")
			(pinfunction "GND")
			(pintype "passive")
			(solder_mask_margin 0.05)
			(teardrops
				(best_length_ratio 0.4)
				(max_length 1)
				(best_width_ratio 0.9)
				(max_width 2)
				(curved_edges yes)
				(filter_ratio 0.9)
				(enabled yes)
				(allow_two_segments yes)
				(prefer_zone_connections yes)
			)
		)
		(pad "K2" smd circle
			(at -4.5 3.5 270)
			(size 0.5 0.5)
			(layers "F.Cu" "F.Mask" "F.Paste")
			(net 852 "unconnected-(U45B-INB1+-PadK2)")
			(pinfunction "INB1+")
			(pintype "input+no_connect")
			(solder_mask_margin 0.05)
			(teardrops
				(best_length_ratio 0.4)
				(max_length 1)
				(best_width_ratio 0.9)
				(max_width 2)
				(curved_edges yes)
				(filter_ratio 0.9)
				(enabled yes)
				(allow_two_segments yes)
				(prefer_zone_connections yes)
			)
		)
		(pad "K3" smd circle
			(at -3.5 3.5 270)
			(size 0.5 0.5)
			(layers "F.Cu" "F.Mask" "F.Paste")
			(net 78 "+1V8")
			(pinfunction "VDDRB_{LS/HS}")
			(pintype "passive")
			(solder_mask_margin 0.05)
			(teardrops
				(best_length_ratio 0.4)
				(max_length 1)
				(best_width_ratio 0.9)
				(max_width 2)
				(curved_edges yes)
				(filter_ratio 0.9)
				(enabled yes)
				(allow_two_segments yes)
				(prefer_zone_connections yes)
			)
		)
		(pad "K4" smd circle
			(at -2.5 3.5 270)
			(size 0.5 0.5)
			(layers "F.Cu" "F.Mask" "F.Paste")
			(net 853 "unconnected-(U45B-OUTB1--PadK4)")
			(pinfunction "OUTB1-")
			(pintype "output+no_connect")
			(solder_mask_margin 0.05)
			(teardrops
				(best_length_ratio 0.4)
				(max_length 1)
				(best_width_ratio 0.9)
				(max_width 2)
				(curved_edges yes)
				(filter_ratio 0.9)
				(enabled yes)
				(allow_two_segments yes)
				(prefer_zone_connections yes)
			)
		)
		(pad "K5" smd circle
			(at -1.5 3.5 270)
			(size 0.5 0.5)
			(layers "F.Cu" "F.Mask" "F.Paste")
			(net 854 "unconnected-(U45B-OUTB1+-PadK5)")
			(pinfunction "OUTB1+")
			(pintype "output+no_connect")
			(solder_mask_margin 0.05)
			(teardrops
				(best_length_ratio 0.4)
				(max_length 1)
				(best_width_ratio 0.9)
				(max_width 2)
				(curved_edges yes)
				(filter_ratio 0.9)
				(enabled yes)
				(allow_two_segments yes)
				(prefer_zone_connections yes)
			)
		)
		(pad "K6" smd circle
			(at -0.5 3.5 270)
			(size 0.5 0.5)
			(layers "F.Cu" "F.Mask" "F.Paste")
			(net 1 "GND")
			(pinfunction "GND")
			(pintype "passive")
			(solder_mask_margin 0.05)
			(teardrops
				(best_length_ratio 0.4)
				(max_length 1)
				(best_width_ratio 0.9)
				(max_width 2)
				(curved_edges yes)
				(filter_ratio 0.9)
				(enabled yes)
				(allow_two_segments yes)
				(prefer_zone_connections yes)
			)
		)
		(pad "K7" smd circle
			(at 0.5 3.5 270)
			(size 0.5 0.5)
			(layers "F.Cu" "F.Mask" "F.Paste")
			(net 74 "+1V0")
			(pinfunction "VDDO1")
			(pintype "power_in")
			(solder_mask_margin 0.05)
			(teardrops
				(best_length_ratio 0.4)
				(max_length 1)
				(best_width_ratio 0.9)
				(max_width 2)
				(curved_edges yes)
				(filter_ratio 0.9)
				(enabled yes)
				(allow_two_segments yes)
				(prefer_zone_connections yes)
			)
		)
		(pad "K8" smd circle
			(at 1.5 3.5 270)
			(size 0.5 0.5)
			(layers "F.Cu" "F.Mask" "F.Paste")
			(net 757 "Net-(U45B-LOSB)")
			(pinfunction "LOSB")
			(pintype "output")
			(solder_mask_margin 0.05)
			(teardrops
				(best_length_ratio 0.4)
				(max_length 1)
				(best_width_ratio 0.9)
				(max_width 2)
				(curved_edges yes)
				(filter_ratio 0.9)
				(enabled yes)
				(allow_two_segments yes)
				(prefer_zone_connections yes)
			)
		)
		(pad "K9" smd circle
			(at 2.5 3.5 270)
			(size 0.5 0.5)
			(layers "F.Cu" "F.Mask" "F.Paste")
			(net 740 "Net-(U45C-REFCLK1+)")
			(pinfunction "REFCLK1+")
			(pintype "input")
			(solder_mask_margin 0.05)
			(teardrops
				(best_length_ratio 0.4)
				(max_length 1)
				(best_width_ratio 0.9)
				(max_width 2)
				(curved_edges yes)
				(filter_ratio 0.9)
				(enabled yes)
				(allow_two_segments yes)
				(prefer_zone_connections yes)
			)
		)
		(pad "K10" smd circle
			(at 3.5 3.5 270)
			(size 0.5 0.5)
			(layers "F.Cu" "F.Mask" "F.Paste")
			(net 741 "Net-(U45C-REFCLK1-)")
			(pinfunction "REFCLK1-")
			(pintype "input")
			(solder_mask_margin 0.05)
			(teardrops
				(best_length_ratio 0.4)
				(max_length 1)
				(best_width_ratio 0.9)
				(max_width 2)
				(curved_edges yes)
				(filter_ratio 0.9)
				(enabled yes)
				(allow_two_segments yes)
				(prefer_zone_connections yes)
			)
		)
		(pad "K11" smd circle
			(at 4.5 3.5 270)
			(size 0.5 0.5)
			(layers "F.Cu" "F.Mask" "F.Paste")
			(net 1 "GND")
			(pinfunction "GND")
			(pintype "passive")
			(solder_mask_margin 0.05)
			(teardrops
				(best_length_ratio 0.4)
				(max_length 1)
				(best_width_ratio 0.9)
				(max_width 2)
				(curved_edges yes)
				(filter_ratio 0.9)
				(enabled yes)
				(allow_two_segments yes)
				(prefer_zone_connections yes)
			)
		)
		(pad "K12" smd circle
			(at 5.5 3.5 270)
			(size 0.5 0.5)
			(layers "F.Cu" "F.Mask" "F.Paste")
			(net 947 "/2xSFP+/KR to SFI #2/SFI_R.TX+")
			(pinfunction "HSTXB+")
			(pintype "output")
			(solder_mask_margin 0.05)
			(teardrops
				(best_length_ratio 0.4)
				(max_length 1)
				(best_width_ratio 0.9)
				(max_width 2)
				(curved_edges yes)
				(filter_ratio 0.9)
				(enabled yes)
				(allow_two_segments yes)
				(prefer_zone_connections yes)
			)
		)
		(pad "L1" smd circle
			(at -5.5 4.5 270)
			(size 0.5 0.5)
			(layers "F.Cu" "F.Mask" "F.Paste")
			(net 855 "unconnected-(U45B-INB2+-PadL1)")
			(pinfunction "INB2+")
			(pintype "input+no_connect")
			(solder_mask_margin 0.05)
			(teardrops
				(best_length_ratio 0.4)
				(max_length 1)
				(best_width_ratio 0.9)
				(max_width 2)
				(curved_edges yes)
				(filter_ratio 0.9)
				(enabled yes)
				(allow_two_segments yes)
				(prefer_zone_connections yes)
			)
		)
		(pad "L2" smd circle
			(at -4.5 4.5 270)
			(size 0.5 0.5)
			(layers "F.Cu" "F.Mask" "F.Paste")
			(net 856 "unconnected-(U45B-INB1--PadL2)")
			(pinfunction "INB1-")
			(pintype "input+no_connect")
			(solder_mask_margin 0.05)
			(teardrops
				(best_length_ratio 0.4)
				(max_length 1)
				(best_width_ratio 0.9)
				(max_width 2)
				(curved_edges yes)
				(filter_ratio 0.9)
				(enabled yes)
				(allow_two_segments yes)
				(prefer_zone_connections yes)
			)
		)
		(pad "L3" smd circle
			(at -3.5 4.5 270)
			(size 0.5 0.5)
			(layers "F.Cu" "F.Mask" "F.Paste")
			(net 1 "GND")
			(pinfunction "GND")
			(pintype "passive")
			(solder_mask_margin 0.05)
			(teardrops
				(best_length_ratio 0.4)
				(max_length 1)
				(best_width_ratio 0.9)
				(max_width 2)
				(curved_edges yes)
				(filter_ratio 0.9)
				(enabled yes)
				(allow_two_segments yes)
				(prefer_zone_connections yes)
			)
		)
		(pad "L4" smd circle
			(at -2.5 4.5 270)
			(size 0.5 0.5)
			(layers "F.Cu" "F.Mask" "F.Paste")
			(net 1 "GND")
			(pinfunction "GND")
			(pintype "passive")
			(solder_mask_margin 0.05)
			(teardrops
				(best_length_ratio 0.4)
				(max_length 1)
				(best_width_ratio 0.9)
				(max_width 2)
				(curved_edges yes)
				(filter_ratio 0.9)
				(enabled yes)
				(allow_two_segments yes)
				(prefer_zone_connections yes)
			)
		)
		(pad "L5" smd circle
			(at -1.5 4.5 270)
			(size 0.5 0.5)
			(layers "F.Cu" "F.Mask" "F.Paste")
			(net 857 "unconnected-(U45B-OUTB2--PadL5)")
			(pinfunction "OUTB2-")
			(pintype "output+no_connect")
			(solder_mask_margin 0.05)
			(teardrops
				(best_length_ratio 0.4)
				(max_length 1)
				(best_width_ratio 0.9)
				(max_width 2)
				(curved_edges yes)
				(filter_ratio 0.9)
				(enabled yes)
				(allow_two_segments yes)
				(prefer_zone_connections yes)
			)
		)
		(pad "L6" smd circle
			(at -0.5 4.5 270)
			(size 0.5 0.5)
			(layers "F.Cu" "F.Mask" "F.Paste")
			(net 858 "unconnected-(U45B-OUTB2+-PadL6)")
			(pinfunction "OUTB2+")
			(pintype "output+no_connect")
			(solder_mask_margin 0.05)
			(teardrops
				(best_length_ratio 0.4)
				(max_length 1)
				(best_width_ratio 0.9)
				(max_width 2)
				(curved_edges yes)
				(filter_ratio 0.9)
				(enabled yes)
				(allow_two_segments yes)
				(prefer_zone_connections yes)
			)
		)
		(pad "L7" smd circle
			(at 0.5 4.5 270)
			(size 0.5 0.5)
			(layers "F.Cu" "F.Mask" "F.Paste")
			(net 1 "GND")
			(pinfunction "GND")
			(pintype "passive")
			(solder_mask_margin 0.05)
			(teardrops
				(best_length_ratio 0.4)
				(max_length 1)
				(best_width_ratio 0.9)
				(max_width 2)
				(curved_edges yes)
				(filter_ratio 0.9)
				(enabled yes)
				(allow_two_segments yes)
				(prefer_zone_connections yes)
			)
		)
		(pad "L8" smd circle
			(at 1.5 4.5 270)
			(size 0.5 0.5)
			(layers "F.Cu" "F.Mask" "F.Paste")
			(net 758 "Net-(U45B-LS_OK_{IN_B})")
			(pinfunction "LS_OK_{IN_B}")
			(pintype "input")
			(solder_mask_margin 0.05)
			(teardrops
				(best_length_ratio 0.4)
				(max_length 1)
				(best_width_ratio 0.9)
				(max_width 2)
				(curved_edges yes)
				(filter_ratio 0.9)
				(enabled yes)
				(allow_two_segments yes)
				(prefer_zone_connections yes)
			)
		)
		(pad "L9" smd circle
			(at 2.5 4.5 270)
			(size 0.5 0.5)
			(layers "F.Cu" "F.Mask" "F.Paste")
			(net 679 "Net-(U45C-PRTAD2)")
			(pinfunction "PRTAD2")
			(pintype "input")
			(solder_mask_margin 0.05)
			(teardrops
				(best_length_ratio 0.4)
				(max_length 1)
				(best_width_ratio 0.9)
				(max_width 2)
				(curved_edges yes)
				(filter_ratio 0.9)
				(enabled yes)
				(allow_two_segments yes)
				(prefer_zone_connections yes)
			)
		)
		(pad "L10" smd circle
			(at 3.5 4.5 270)
			(size 0.5 0.5)
			(layers "F.Cu" "F.Mask" "F.Paste")
			(net 674 "Net-(U45C-TESTEN)")
			(pinfunction "TESTEN")
			(pintype "input")
			(solder_mask_margin 0.05)
			(teardrops
				(best_length_ratio 0.4)
				(max_length 1)
				(best_width_ratio 0.9)
				(max_width 2)
				(curved_edges yes)
				(filter_ratio 0.9)
				(enabled yes)
				(allow_two_segments yes)
				(prefer_zone_connections yes)
			)
		)
		(pad "L11" smd circle
			(at 4.5 4.5 270)
			(size 0.5 0.5)
			(layers "F.Cu" "F.Mask" "F.Paste")
			(net 1 "GND")
			(pinfunction "GND")
			(pintype "passive")
			(solder_mask_margin 0.05)
			(teardrops
				(best_length_ratio 0.4)
				(max_length 1)
				(best_width_ratio 0.9)
				(max_width 2)
				(curved_edges yes)
				(filter_ratio 0.9)
				(enabled yes)
				(allow_two_segments yes)
				(prefer_zone_connections yes)
			)
		)
		(pad "L12" smd circle
			(at 5.5 4.5 270)
			(size 0.5 0.5)
			(layers "F.Cu" "F.Mask" "F.Paste")
			(net 952 "/2xSFP+/KR to SFI #2/SFI_R.TX-")
			(pinfunction "HSTXB-")
			(pintype "output")
			(solder_mask_margin 0.05)
			(teardrops
				(best_length_ratio 0.4)
				(max_length 1)
				(best_width_ratio 0.9)
				(max_width 2)
				(curved_edges yes)
				(filter_ratio 0.9)
				(enabled yes)
				(allow_two_segments yes)
				(prefer_zone_connections yes)
			)
		)
		(pad "M1" smd circle
			(at -5.5 5.5 270)
			(size 0.5 0.5)
			(layers "F.Cu" "F.Mask" "F.Paste")
			(net 859 "unconnected-(U45B-INB2--PadM1)")
			(pinfunction "INB2-")
			(pintype "input+no_connect")
			(solder_mask_margin 0.05)
			(teardrops
				(best_length_ratio 0.4)
				(max_length 1)
				(best_width_ratio 0.9)
				(max_width 2)
				(curved_edges yes)
				(filter_ratio 0.9)
				(enabled yes)
				(allow_two_segments yes)
				(prefer_zone_connections yes)
			)
		)
		(pad "M2" smd circle
			(at -4.5 5.5 270)
			(size 0.5 0.5)
			(layers "F.Cu" "F.Mask" "F.Paste")
			(net 1 "GND")
			(pinfunction "GND")
			(pintype "passive")
			(solder_mask_margin 0.05)
			(teardrops
				(best_length_ratio 0.4)
				(max_length 1)
				(best_width_ratio 0.9)
				(max_width 2)
				(curved_edges yes)
				(filter_ratio 0.9)
				(enabled yes)
				(allow_two_segments yes)
				(prefer_zone_connections yes)
			)
		)
		(pad "M3" smd circle
			(at -3.5 5.5 270)
			(size 0.5 0.5)
			(layers "F.Cu" "F.Mask" "F.Paste")
			(net 860 "unconnected-(U45B-INB3+-PadM3)")
			(pinfunction "INB3+")
			(pintype "input+no_connect")
			(solder_mask_margin 0.05)
			(teardrops
				(best_length_ratio 0.4)
				(max_length 1)
				(best_width_ratio 0.9)
				(max_width 2)
				(curved_edges yes)
				(filter_ratio 0.9)
				(enabled yes)
				(allow_two_segments yes)
				(prefer_zone_connections yes)
			)
		)
		(pad "M4" smd circle
			(at -2.5 5.5 270)
			(size 0.5 0.5)
			(layers "F.Cu" "F.Mask" "F.Paste")
			(net 861 "unconnected-(U45B-INB3--PadM4)")
			(pinfunction "INB3-")
			(pintype "input+no_connect")
			(solder_mask_margin 0.05)
			(teardrops
				(best_length_ratio 0.4)
				(max_length 1)
				(best_width_ratio 0.9)
				(max_width 2)
				(curved_edges yes)
				(filter_ratio 0.9)
				(enabled yes)
				(allow_two_segments yes)
				(prefer_zone_connections yes)
			)
		)
		(pad "M5" smd circle
			(at -1.5 5.5 270)
			(size 0.5 0.5)
			(layers "F.Cu" "F.Mask" "F.Paste")
			(net 1 "GND")
			(pinfunction "GND")
			(pintype "passive")
			(solder_mask_margin 0.05)
			(teardrops
				(best_length_ratio 0.4)
				(max_length 1)
				(best_width_ratio 0.9)
				(max_width 2)
				(curved_edges yes)
				(filter_ratio 0.9)
				(enabled yes)
				(allow_two_segments yes)
				(prefer_zone_connections yes)
			)
		)
		(pad "M6" smd circle
			(at -0.5 5.5 270)
			(size 0.5 0.5)
			(layers "F.Cu" "F.Mask" "F.Paste")
			(net 862 "unconnected-(U45B-OUTB3--PadM6)")
			(pinfunction "OUTB3-")
			(pintype "output+no_connect")
			(solder_mask_margin 0.05)
			(teardrops
				(best_length_ratio 0.4)
				(max_length 1)
				(best_width_ratio 0.9)
				(max_width 2)
				(curved_edges yes)
				(filter_ratio 0.9)
				(enabled yes)
				(allow_two_segments yes)
				(prefer_zone_connections yes)
			)
		)
		(pad "M7" smd circle
			(at 0.5 5.5 270)
			(size 0.5 0.5)
			(layers "F.Cu" "F.Mask" "F.Paste")
			(net 863 "unconnected-(U45B-OUTB3+-PadM7)")
			(pinfunction "OUTB3+")
			(pintype "output+no_connect")
			(solder_mask_margin 0.05)
			(teardrops
				(best_length_ratio 0.4)
				(max_length 1)
				(best_width_ratio 0.9)
				(max_width 2)
				(curved_edges yes)
				(filter_ratio 0.9)
				(enabled yes)
				(allow_two_segments yes)
				(prefer_zone_connections yes)
			)
		)
		(pad "M8" smd circle
			(at 1.5 5.5 270)
			(size 0.5 0.5)
			(layers "F.Cu" "F.Mask" "F.Paste")
			(net 682 "Net-(U45C-PRTAD4)")
			(pinfunction "PRTAD4")
			(pintype "input")
			(solder_mask_margin 0.05)
			(teardrops
				(best_length_ratio 0.4)
				(max_length 1)
				(best_width_ratio 0.9)
				(max_width 2)
				(curved_edges yes)
				(filter_ratio 0.9)
				(enabled yes)
				(allow_two_segments yes)
				(prefer_zone_connections yes)
			)
		)
		(pad "M9" smd circle
			(at 2.5 5.5 270)
			(size 0.5 0.5)
			(layers "F.Cu" "F.Mask" "F.Paste")
			(net 684 "Net-(U45C-ST)")
			(pinfunction "ST")
			(pintype "input")
			(solder_mask_margin 0.05)
			(teardrops
				(best_length_ratio 0.4)
				(max_length 1)
				(best_width_ratio 0.9)
				(max_width 2)
				(curved_edges yes)
				(filter_ratio 0.9)
				(enabled yes)
				(allow_two_segments yes)
				(prefer_zone_connections yes)
			)
		)
		(pad "M10" smd circle
			(at 3.5 5.5 270)
			(size 0.5 0.5)
			(layers "F.Cu" "F.Mask" "F.Paste")
			(net 116 "/2xSFP+/KR to SFI #2/REFCLK+")
			(pinfunction "REFCLK0+")
			(pintype "input")
			(solder_mask_margin 0.05)
			(teardrops
				(best_length_ratio 0.4)
				(max_length 1)
				(best_width_ratio 0.9)
				(max_width 2)
				(curved_edges yes)
				(filter_ratio 0.9)
				(enabled yes)
				(allow_two_segments yes)
				(prefer_zone_connections yes)
			)
		)
		(pad "M11" smd circle
			(at 4.5 5.5 270)
			(size 0.5 0.5)
			(layers "F.Cu" "F.Mask" "F.Paste")
			(net 118 "/2xSFP+/KR to SFI #2/REFCLK-")
			(pinfunction "REFCLK0-")
			(pintype "input")
			(solder_mask_margin 0.05)
			(teardrops
				(best_length_ratio 0.4)
				(max_length 1)
				(best_width_ratio 0.9)
				(max_width 2)
				(curved_edges yes)
				(filter_ratio 0.9)
				(enabled yes)
				(allow_two_segments yes)
				(prefer_zone_connections yes)
			)
		)
		(pad "M12" smd circle
			(at 5.5 5.5 270)
			(size 0.5 0.5)
			(layers "F.Cu" "F.Mask" "F.Paste")
			(net 1 "GND")
			(pinfunction "GND")
			(pintype "passive")
			(solder_mask_margin 0.05)
			(teardrops
				(best_length_ratio 0.4)
				(max_length 1)
				(best_width_ratio 0.9)
				(max_width 2)
				(curved_edges yes)
				(filter_ratio 0.9)
				(enabled yes)
				(allow_two_segments yes)
				(prefer_zone_connections yes)
			)
		)
	)
	(footprint "antmicro-footprints:R_0402_1005Metric"
		(layer "F.Cu")
		(at 122.05 86.06)
		(descr "Resistor SMD 0402")
		(tags "resistor SMD 0402")
		(property "Reference" "R24"
			(at 0.75 0.4 0)
			(layer "F.SilkS")
			(effects
				(font
					(size 0.7 0.7)
					(thickness 0.15)
				)
				(justify left bottom)
			)
		)
		(property "Value" "R_10k_0402"
			(at -1.011843 1.772047 0)
			(layer "F.Fab")
			(effects
				(font
					(size 0.7 0.7)
					(thickness 0.15)
				)
				(justify left bottom)
			)
		)
		(property "Datasheet" "https://www.bourns.com/docs/product-datasheets/cr.pdf"
			(at 0 0 0)
			(layer "F.Fab")
			(hide yes)
			(effects
				(font
					(size 1.27 1.27)
					(thickness 0.15)
				)
			)
		)
		(property "Author" "Antmicro"
			(at 0 0 0)
			(layer "F.Fab")
			(hide yes)
			(effects
				(font
					(size 1 1)
					(thickness 0.15)
				)
			)
		)
		(property "License" "Apache-2.0"
			(at 0 0 0)
			(layer "F.Fab")
			(hide yes)
			(effects
				(font
					(size 1 1)
					(thickness 0.15)
				)
			)
		)
		(property "MPN" "CR0402-FX-1002GLF"
			(at 0 0 0)
			(layer "F.Fab")
			(hide yes)
			(effects
				(font
					(size 1 1)
					(thickness 0.15)
				)
			)
		)
		(property "Manufacturer" "Bourns"
			(at 0 0 0)
			(layer "F.Fab")
			(hide yes)
			(effects
				(font
					(size 1 1)
					(thickness 0.15)
				)
			)
		)
		(property "Public" "False"
			(at 0 0 0)
			(layer "F.Fab")
			(hide yes)
			(effects
				(font
					(size 1 1)
					(thickness 0.15)
				)
			)
		)
		(property "Tolerance" "1%"
			(at 0 0 0)
			(layer "F.Fab")
			(hide yes)
			(effects
				(font
					(size 1 1)
					(thickness 0.15)
				)
			)
		)
		(property "Val" "10k"
			(at 0 0 0)
			(layer "F.Fab")
			(hide yes)
			(effects
				(font
					(size 1 1)
					(thickness 0.15)
				)
			)
		)
		(sheetname "2xUSB3.0+RJ45")
		(sheetfile "usb3+rj45.kicad_sch")
		(attr smd)
		(fp_rect
			(start -0.925 -0.47)
			(end 0.925 0.47)
			(stroke
				(width 0.05)
				(type default)
			)
			(fill no)
			(layer "F.CrtYd")
		)
		(fp_rect
			(start -0.5 -0.25)
			(end 0.5 0.25)
			(stroke
				(width 0.15)
				(type solid)
			)
			(fill no)
			(layer "F.Fab")
		)
		(pad "1" smd roundrect
			(at -0.48 0)
			(size 0.59 0.64)
			(layers "F.Cu" "F.Mask" "F.Paste")
			(roundrect_rratio 0.25)
			(net 555 "/2xUSB3.0+RJ45/EN_1B")
			(pintype "passive")
			(teardrops
				(best_length_ratio 0.2)
				(max_length 1)
				(best_width_ratio 0.9)
				(max_width 2)
				(curved_edges yes)
				(filter_ratio 0.9)
				(enabled yes)
				(allow_two_segments yes)
				(prefer_zone_connections yes)
			)
		)
		(pad "2" smd roundrect
			(at 0.48 0)
			(size 0.59 0.64)
			(layers "F.Cu" "F.Mask" "F.Paste")
			(roundrect_rratio 0.25)
			(net 2 "+3V3")
			(pintype "passive")
			(teardrops
				(best_length_ratio 0.2)
				(max_length 1)
				(best_width_ratio 0.9)
				(max_width 2)
				(curved_edges yes)
				(filter_ratio 0.9)
				(enabled yes)
				(allow_two_segments yes)
				(prefer_zone_connections yes)
			)
		)
	)
	(footprint "antmicro-footprints:TP_SMD_0.75mm"
		(layer "F.Cu")
		(at 196.8 133 45)
		(property "Reference" "TP54"
			(at 0.4 0.45 45)
			(layer "F.SilkS")
			(effects
				(font
					(size 0.7 0.7)
					(thickness 0.15)
				)
				(justify left bottom)
			)
		)
		(property "Value" "TP_0.75mm_SMD"
			(at 0 1.2 45)
			(layer "F.Fab")
			(effects
				(font
					(size 0.7 0.7)
					(thickness 0.15)
				)
				(justify left bottom)
			)
		)
		(property "Author" "Antmicro"
			(at 369.6 -271.22 45)
			(layer "F.Fab")
			(hide yes)
			(effects
				(font
					(size 1 1)
					(thickness 0.15)
				)
			)
		)
		(property "License" "Apache-2.0"
			(at 369.6 -271.22 45)
			(layer "F.Fab")
			(hide yes)
			(effects
				(font
					(size 1 1)
					(thickness 0.15)
				)
			)
		)
		(property "MPN" ""
			(at 369.6 -271.22 45)
			(layer "F.Fab")
			(hide yes)
			(effects
				(font
					(size 1 1)
					(thickness 0.15)
				)
			)
		)
		(property "Manufacturer" ""
			(at 369.6 -271.22 45)
			(layer "F.Fab")
			(hide yes)
			(effects
				(font
					(size 1 1)
					(thickness 0.15)
				)
			)
		)
		(property "Public" "False"
			(at 369.6 -271.22 45)
			(layer "F.Fab")
			(hide yes)
			(effects
				(font
					(size 1 1)
					(thickness 0.15)
				)
			)
		)
		(sheetname "PCIe redriver")
		(sheetfile "pcie_redriver.kicad_sch")
		(attr exclude_from_pos_files exclude_from_bom)
		(fp_circle
			(center 0 0)
			(end 0.475 0)
			(stroke
				(width 0.05)
				(type default)
			)
			(fill no)
			(layer "F.CrtYd")
		)
		(pad "1" smd circle
			(at 0 0 45)
			(size 0.75 0.75)
			(layers "F.Cu" "F.Mask")
			(net 717 "Net-(U40-SCL)")
			(pinfunction "1")
			(pintype "passive")
			(teardrops
				(best_length_ratio 0.4)
				(max_length 1)
				(best_width_ratio 0.9)
				(max_width 2)
				(curved_edges yes)
				(filter_ratio 0.9)
				(enabled yes)
				(allow_two_segments yes)
				(prefer_zone_connections yes)
			)
		)
	)
	(footprint "antmicro-footprints:EPT_401-51501-51"
		(layer "F.Cu")
		(at 203.275 159.81)
		(property "Reference" "J12"
			(at 30.975 -10.45 0)
			(layer "F.SilkS")
			(effects
				(font
					(size 0.7 0.7)
					(thickness 0.15)
				)
				(justify right top)
			)
		)
		(property "Value" "Plug_Bus_CE7_EPT_401-51501-51"
			(at -3.225 52.665 0)
			(layer "F.Fab")
			(hide yes)
			(effects
				(font
					(size 0.7 0.7)
					(thickness 0.15)
				)
				(justify left top)
			)
		)
		(property "Datasheet" "https://www.farnell.com/datasheets/1905093.pdf"
			(at 0 0 0)
			(layer "F.Fab")
			(hide yes)
			(effects
				(font
					(size 1.27 1.27)
					(thickness 0.15)
				)
			)
		)
		(property "Author" "Antmicro"
			(at 406.55 319.62 0)
			(layer "F.Fab")
			(hide yes)
			(effects
				(font
					(size 1 1)
					(thickness 0.15)
				)
			)
		)
		(property "License" "Apache-2.0"
			(at 406.55 319.62 0)
			(layer "F.Fab")
			(hide yes)
			(effects
				(font
					(size 1 1)
					(thickness 0.15)
				)
			)
		)
		(property "MPN" "401-51501-51"
			(at 406.55 319.62 0)
			(layer "F.Fab")
			(hide yes)
			(effects
				(font
					(size 1 1)
					(thickness 0.15)
				)
			)
		)
		(property "Manufacturer" "ept"
			(at 406.55 319.62 0)
			(layer "F.Fab")
			(hide yes)
			(effects
				(font
					(size 1 1)
					(thickness 0.15)
				)
			)
		)
		(sheetname "Com Express 7 Interfaces")
		(sheetfile "com_express_7_interfaces.kicad_sch")
		(attr smd)
		(fp_line
			(start -24.638 -1.524)
			(end -30.226 -1.524)
			(stroke
				(width 0.1)
				(type default)
			)
			(layer "F.SilkS")
		)
		(fp_line
			(start -24.638 10.414)
			(end -30.226 10.414)
			(stroke
				(width 0.1)
				(type default)
			)
			(layer "F.SilkS")
		)
		(fp_rect
			(start -31.6 -9.75)
			(end 31.58 -1.95)
			(stroke
				(width 0.05)
				(type solid)
			)
			(fill no)
			(layer "F.CrtYd")
		)
		(fp_rect
			(start -31.58 2.2)
			(end 31.6 10)
			(stroke
				(width 0.05)
				(type solid)
			)
			(fill no)
			(layer "F.CrtYd")
		)
		(fp_rect
			(start -31.496 -9.652)
			(end 31.496 -2.032)
			(stroke
				(width 0.1)
				(type default)
			)
			(fill no)
			(layer "F.Fab")
		)
		(fp_rect
			(start -31.496 2.286)
			(end 31.496 9.906)
			(stroke
				(width 0.1)
				(type default)
			)
			(fill no)
			(layer "F.Fab")
		)
		(pad "" np_thru_hole circle
			(at -28.85 -6)
			(size 0.9 0.9)
			(drill 0.9)
			(layers "F&B.Cu" "*.Mask")
		)
		(pad "" smd rect
			(at -28.85 6 270)
			(size 0.001 0.001)
			(layers "F.Cu" "F.Mask" "F.Paste")
			(teardrops
				(best_length_ratio 0.2)
				(max_length 1)
				(best_width_ratio 0.9)
				(max_width 2)
				(curved_edges yes)
				(filter_ratio 0.9)
				(enabled yes)
				(allow_two_segments yes)
				(prefer_zone_connections yes)
			)
		)
		(pad "" np_thru_hole circle
			(at -28.85 6)
			(size 0.9 0.9)
			(drill 0.9)
			(layers "F&B.Cu" "*.Mask")
		)
		(pad "" np_thru_hole circle
			(at 28.85 -6)
			(size 1.6 1.6)
			(drill 1.6)
			(layers "F&B.Cu" "*.Mask")
		)
		(pad "" np_thru_hole circle
			(at 28.85 6)
			(size 1.6 1.6)
			(drill 1.6)
			(layers "F&B.Cu" "*.Mask")
		)
		(pad "A1" smd rect
			(at -27.25 8.875)
			(size 0.3 1.75)
			(layers "F.Cu" "F.Mask" "F.Paste")
			(net 1 "GND")
			(pinfunction "GND(FIXED)")
			(pintype "power_in")
			(teardrops
				(best_length_ratio 0.2)
				(max_length 1)
				(best_width_ratio 0.9)
				(max_width 2)
				(curved_edges yes)
				(filter_ratio 0.9)
				(enabled yes)
				(allow_two_segments yes)
				(prefer_zone_connections yes)
			)
		)
		(pad "A2" smd rect
			(at -26.75 8.875)
			(size 0.3 1.75)
			(layers "F.Cu" "F.Mask" "F.Paste")
			(net 285 "/2xUSB3.0+RJ45/GbE.MDI3-")
			(pinfunction "GBE0_MDI3-")
			(pintype "bidirectional")
			(teardrops
				(best_length_ratio 0.2)
				(max_length 1)
				(best_width_ratio 0.9)
				(max_width 2)
				(curved_edges yes)
				(filter_ratio 0.9)
				(enabled yes)
				(allow_two_segments yes)
				(prefer_zone_connections yes)
			)
		)
		(pad "A3" smd rect
			(at -26.25 8.875)
			(size 0.3 1.75)
			(layers "F.Cu" "F.Mask" "F.Paste")
			(net 286 "/2xUSB3.0+RJ45/GbE.MDI3+")
			(pinfunction "GBE0_MDI3+")
			(pintype "bidirectional")
			(teardrops
				(best_length_ratio 0.2)
				(max_length 1)
				(best_width_ratio 0.9)
				(max_width 2)
				(curved_edges yes)
				(filter_ratio 0.9)
				(enabled yes)
				(allow_two_segments yes)
				(prefer_zone_connections yes)
			)
		)
		(pad "A4" smd rect
			(at -25.75 8.875)
			(size 0.3 1.75)
			(layers "F.Cu" "F.Mask" "F.Paste")
			(net 287 "unconnected-(J12B-~{GBE0_LINK100}-PadA4)")
			(pinfunction "~{GBE0_LINK100}")
			(pintype "output+no_connect")
			(teardrops
				(best_length_ratio 0.2)
				(max_length 1)
				(best_width_ratio 0.9)
				(max_width 2)
				(curved_edges yes)
				(filter_ratio 0.9)
				(enabled yes)
				(allow_two_segments yes)
				(prefer_zone_connections yes)
			)
		)
		(pad "A5" smd rect
			(at -25.25 8.875)
			(size 0.3 1.75)
			(layers "F.Cu" "F.Mask" "F.Paste")
			(net 288 "/2xUSB3.0+RJ45/~{GBE0_LINK_1000}")
			(pinfunction "~{GBE0_LINK1000}")
			(pintype "output")
			(teardrops
				(best_length_ratio 0.2)
				(max_length 1)
				(best_width_ratio 0.9)
				(max_width 2)
				(curved_edges yes)
				(filter_ratio 0.9)
				(enabled yes)
				(allow_two_segments yes)
				(prefer_zone_connections yes)
			)
		)
		(pad "A6" smd rect
			(at -24.75 8.875)
			(size 0.3 1.75)
			(layers "F.Cu" "F.Mask" "F.Paste")
			(net 289 "/2xUSB3.0+RJ45/GbE.MDI2-")
			(pinfunction "GBE0_MDI2-")
			(pintype "bidirectional")
			(teardrops
				(best_length_ratio 0.2)
				(max_length 1)
				(best_width_ratio 0.9)
				(max_width 2)
				(curved_edges yes)
				(filter_ratio 0.9)
				(enabled yes)
				(allow_two_segments yes)
				(prefer_zone_connections yes)
			)
		)
		(pad "A7" smd rect
			(at -24.25 8.875)
			(size 0.3 1.75)
			(layers "F.Cu" "F.Mask" "F.Paste")
			(net 290 "/2xUSB3.0+RJ45/GbE.MDI2+")
			(pinfunction "GBE0_MDI2+")
			(pintype "bidirectional")
			(teardrops
				(best_length_ratio 0.2)
				(max_length 1)
				(best_width_ratio 0.9)
				(max_width 2)
				(curved_edges yes)
				(filter_ratio 0.9)
				(enabled yes)
				(allow_two_segments yes)
				(prefer_zone_connections yes)
			)
		)
		(pad "A8" smd rect
			(at -23.75 8.875)
			(size 0.3 1.75)
			(layers "F.Cu" "F.Mask" "F.Paste")
			(net 291 "/2xUSB3.0+RJ45/~{GBE0_LINK}")
			(pinfunction "~{GBE0_LINK}")
			(pintype "output")
			(teardrops
				(best_length_ratio 0.2)
				(max_length 1)
				(best_width_ratio 0.9)
				(max_width 2)
				(curved_edges yes)
				(filter_ratio 0.9)
				(enabled yes)
				(allow_two_segments yes)
				(prefer_zone_connections yes)
			)
		)
		(pad "A9" smd rect
			(at -23.25 8.875)
			(size 0.3 1.75)
			(layers "F.Cu" "F.Mask" "F.Paste")
			(net 292 "/2xUSB3.0+RJ45/GbE.MDI1-")
			(pinfunction "GBE0_MDI1-")
			(pintype "bidirectional")
			(teardrops
				(best_length_ratio 0.2)
				(max_length 1)
				(best_width_ratio 0.9)
				(max_width 2)
				(curved_edges yes)
				(filter_ratio 0.9)
				(enabled yes)
				(allow_two_segments yes)
				(prefer_zone_connections yes)
			)
		)
		(pad "A10" smd rect
			(at -22.75 8.875)
			(size 0.3 1.75)
			(layers "F.Cu" "F.Mask" "F.Paste")
			(net 293 "/2xUSB3.0+RJ45/GbE.MDI1+")
			(pinfunction "GBE0_MDI1+")
			(pintype "bidirectional")
			(teardrops
				(best_length_ratio 0.2)
				(max_length 1)
				(best_width_ratio 0.9)
				(max_width 2)
				(curved_edges yes)
				(filter_ratio 0.9)
				(enabled yes)
				(allow_two_segments yes)
				(prefer_zone_connections yes)
			)
		)
		(pad "A11" smd rect
			(at -22.25 8.875)
			(size 0.3 1.75)
			(layers "F.Cu" "F.Mask" "F.Paste")
			(net 1 "GND")
			(pinfunction "GND(FIXED)")
			(pintype "passive")
			(teardrops
				(best_length_ratio 0.2)
				(max_length 1)
				(best_width_ratio 0.9)
				(max_width 2)
				(curved_edges yes)
				(filter_ratio 0.9)
				(enabled yes)
				(allow_two_segments yes)
				(prefer_zone_connections yes)
			)
		)
		(pad "A12" smd rect
			(at -21.75 8.875)
			(size 0.3 1.75)
			(layers "F.Cu" "F.Mask" "F.Paste")
			(net 294 "/2xUSB3.0+RJ45/GbE.MDI0-")
			(pinfunction "GBE0_MDI0-")
			(pintype "bidirectional")
			(teardrops
				(best_length_ratio 0.2)
				(max_length 1)
				(best_width_ratio 0.9)
				(max_width 2)
				(curved_edges yes)
				(filter_ratio 0.9)
				(enabled yes)
				(allow_two_segments yes)
				(prefer_zone_connections yes)
			)
		)
		(pad "A13" smd rect
			(at -21.25 8.875)
			(size 0.3 1.75)
			(layers "F.Cu" "F.Mask" "F.Paste")
			(net 295 "/2xUSB3.0+RJ45/GbE.MDI0+")
			(pinfunction "GBE0_MDI0+")
			(pintype "bidirectional")
			(teardrops
				(best_length_ratio 0.2)
				(max_length 1)
				(best_width_ratio 0.9)
				(max_width 2)
				(curved_edges yes)
				(filter_ratio 0.9)
				(enabled yes)
				(allow_two_segments yes)
				(prefer_zone_connections yes)
			)
		)
		(pad "A14" smd rect
			(at -20.75 8.875)
			(size 0.3 1.75)
			(layers "F.Cu" "F.Mask" "F.Paste")
			(net 296 "/2xUSB3.0+RJ45/GbE.CTREF")
			(pinfunction "GBE0_CTREF")
			(pintype "passive")
			(teardrops
				(best_length_ratio 0.2)
				(max_length 1)
				(best_width_ratio 0.9)
				(max_width 2)
				(curved_edges yes)
				(filter_ratio 0.9)
				(enabled yes)
				(allow_two_segments yes)
				(prefer_zone_connections yes)
			)
		)
		(pad "A15" smd rect
			(at -20.25 8.875)
			(size 0.3 1.75)
			(layers "F.Cu" "F.Mask" "F.Paste")
			(net 297 "Net-(J12D-~{SUS_S3})")
			(pinfunction "~{SUS_S3}")
			(pintype "output")
			(teardrops
				(best_length_ratio 0.2)
				(max_length 1)
				(best_width_ratio 0.9)
				(max_width 2)
				(curved_edges yes)
				(filter_ratio 0.9)
				(enabled yes)
				(allow_two_segments yes)
				(prefer_zone_connections yes)
			)
		)
		(pad "A16" smd rect
			(at -19.75 8.875)
			(size 0.3 1.75)
			(layers "F.Cu" "F.Mask" "F.Paste")
			(net 298 "unconnected-(J12F-SATA0_TX+-PadA16)")
			(pinfunction "SATA0_TX+")
			(pintype "output+no_connect")
			(teardrops
				(best_length_ratio 0.2)
				(max_length 1)
				(best_width_ratio 0.9)
				(max_width 2)
				(curved_edges yes)
				(filter_ratio 0.9)
				(enabled yes)
				(allow_two_segments yes)
				(prefer_zone_connections yes)
			)
		)
		(pad "A17" smd rect
			(at -19.25 8.875)
			(size 0.3 1.75)
			(layers "F.Cu" "F.Mask" "F.Paste")
			(net 299 "unconnected-(J12F-SATA0_TX--PadA17)")
			(pinfunction "SATA0_TX-")
			(pintype "output+no_connect")
			(teardrops
				(best_length_ratio 0.2)
				(max_length 1)
				(best_width_ratio 0.9)
				(max_width 2)
				(curved_edges yes)
				(filter_ratio 0.9)
				(enabled yes)
				(allow_two_segments yes)
				(prefer_zone_connections yes)
			)
		)
		(pad "A18" smd rect
			(at -18.75 8.875)
			(size 0.3 1.75)
			(layers "F.Cu" "F.Mask" "F.Paste")
			(net 300 "Net-(J12D-~{SUS_S4})")
			(pinfunction "~{SUS_S4}")
			(pintype "output")
			(teardrops
				(best_length_ratio 0.2)
				(max_length 1)
				(best_width_ratio 0.9)
				(max_width 2)
				(curved_edges yes)
				(filter_ratio 0.9)
				(enabled yes)
				(allow_two_segments yes)
				(prefer_zone_connections yes)
			)
		)
		(pad "A19" smd rect
			(at -18.25 8.875)
			(size 0.3 1.75)
			(layers "F.Cu" "F.Mask" "F.Paste")
			(net 301 "unconnected-(J12F-SATA0_RX+-PadA19)")
			(pinfunction "SATA0_RX+")
			(pintype "input+no_connect")
			(teardrops
				(best_length_ratio 0.2)
				(max_length 1)
				(best_width_ratio 0.9)
				(max_width 2)
				(curved_edges yes)
				(filter_ratio 0.9)
				(enabled yes)
				(allow_two_segments yes)
				(prefer_zone_connections yes)
			)
		)
		(pad "A20" smd rect
			(at -17.75 8.875)
			(size 0.3 1.75)
			(layers "F.Cu" "F.Mask" "F.Paste")
			(net 302 "unconnected-(J12F-SATA0_RX--PadA20)")
			(pinfunction "SATA0_RX-")
			(pintype "input+no_connect")
			(teardrops
				(best_length_ratio 0.2)
				(max_length 1)
				(best_width_ratio 0.9)
				(max_width 2)
				(curved_edges yes)
				(filter_ratio 0.9)
				(enabled yes)
				(allow_two_segments yes)
				(prefer_zone_connections yes)
			)
		)
		(pad "A21" smd rect
			(at -17.25 8.875)
			(size 0.3 1.75)
			(layers "F.Cu" "F.Mask" "F.Paste")
			(net 1 "GND")
			(pinfunction "GND(FIXED)")
			(pintype "passive")
			(teardrops
				(best_length_ratio 0.2)
				(max_length 1)
				(best_width_ratio 0.9)
				(max_width 2)
				(curved_edges yes)
				(filter_ratio 0.9)
				(enabled yes)
				(allow_two_segments yes)
				(prefer_zone_connections yes)
			)
		)
		(pad "A22" smd rect
			(at -16.75 8.875)
			(size 0.3 1.75)
			(layers "F.Cu" "F.Mask" "F.Paste")
			(net 242 "/Com Express 7 Interfaces/PCIe_{B2Bx4}.TX3+")
			(pinfunction "PCIE_TX15+")
			(pintype "output")
			(teardrops
				(best_length_ratio 0.2)
				(max_length 1)
				(best_width_ratio 0.9)
				(max_width 2)
				(curved_edges yes)
				(filter_ratio 0.9)
				(enabled yes)
				(allow_two_segments yes)
				(prefer_zone_connections yes)
			)
		)
		(pad "A23" smd rect
			(at -16.25 8.875)
			(size 0.3 1.75)
			(layers "F.Cu" "F.Mask" "F.Paste")
			(net 241 "/Com Express 7 Interfaces/PCIe_{B2Bx4}.TX3-")
			(pinfunction "PCIE_TX15-")
			(pintype "output")
			(teardrops
				(best_length_ratio 0.2)
				(max_length 1)
				(best_width_ratio 0.9)
				(max_width 2)
				(curved_edges yes)
				(filter_ratio 0.9)
				(enabled yes)
				(allow_two_segments yes)
				(prefer_zone_connections yes)
			)
		)
		(pad "A24" smd rect
			(at -15.75 8.875)
			(size 0.3 1.75)
			(layers "F.Cu" "F.Mask" "F.Paste")
			(net 303 "/Com Express 7 MGMT/~{SUS_S5}")
			(pinfunction "~{SUS_S5}")
			(pintype "output")
			(teardrops
				(best_length_ratio 0.2)
				(max_length 1)
				(best_width_ratio 0.9)
				(max_width 2)
				(curved_edges yes)
				(filter_ratio 0.9)
				(enabled yes)
				(allow_two_segments yes)
				(prefer_zone_connections yes)
			)
		)
		(pad "A25" smd rect
			(at -15.25 8.875)
			(size 0.3 1.75)
			(layers "F.Cu" "F.Mask" "F.Paste")
			(net 249 "/Com Express 7 Interfaces/PCIe_{B2Bx4}.TX2+")
			(pinfunction "PCIE_TX14+")
			(pintype "output")
			(teardrops
				(best_length_ratio 0.2)
				(max_length 1)
				(best_width_ratio 0.9)
				(max_width 2)
				(curved_edges yes)
				(filter_ratio 0.9)
				(enabled yes)
				(allow_two_segments yes)
				(prefer_zone_connections yes)
			)
		)
		(pad "A26" smd rect
			(at -14.75 8.875)
			(size 0.3 1.75)
			(layers "F.Cu" "F.Mask" "F.Paste")
			(net 247 "/Com Express 7 Interfaces/PCIe_{B2Bx4}.TX2-")
			(pinfunction "PCIE_TX14-")
			(pintype "output")
			(teardrops
				(best_length_ratio 0.2)
				(max_length 1)
				(best_width_ratio 0.9)
				(max_width 2)
				(curved_edges yes)
				(filter_ratio 0.9)
				(enabled yes)
				(allow_two_segments yes)
				(prefer_zone_connections yes)
			)
		)
		(pad "A27" smd rect
			(at -14.25 8.875)
			(size 0.3 1.75)
			(layers "F.Cu" "F.Mask" "F.Paste")
			(net 304 "Net-(J12D-~{BATLOW})")
			(pinfunction "~{BATLOW}")
			(pintype "input")
			(teardrops
				(best_length_ratio 0.2)
				(max_length 1)
				(best_width_ratio 0.9)
				(max_width 2)
				(curved_edges yes)
				(filter_ratio 0.9)
				(enabled yes)
				(allow_two_segments yes)
				(prefer_zone_connections yes)
			)
		)
		(pad "A28" smd rect
			(at -13.75 8.875)
			(size 0.3 1.75)
			(layers "F.Cu" "F.Mask" "F.Paste")
			(net 305 "unconnected-(J12F-~{(S)ATA_ACT}-PadA28)")
			(pinfunction "~{(S)ATA_ACT}")
			(pintype "bidirectional+no_connect")
			(teardrops
				(best_length_ratio 0.2)
				(max_length 1)
				(best_width_ratio 0.9)
				(max_width 2)
				(curved_edges yes)
				(filter_ratio 0.9)
				(enabled yes)
				(allow_two_segments yes)
				(prefer_zone_connections yes)
			)
		)
		(pad "A29" smd rect
			(at -13.25 8.875)
			(size 0.3 1.75)
			(layers "F.Cu" "F.Mask" "F.Paste")
			(net 306 "unconnected-(J12H-RSVD-PadA29)")
			(pinfunction "RSVD")
			(pintype "no_connect")
			(teardrops
				(best_length_ratio 0.2)
				(max_length 1)
				(best_width_ratio 0.9)
				(max_width 2)
				(curved_edges yes)
				(filter_ratio 0.9)
				(enabled yes)
				(allow_two_segments yes)
				(prefer_zone_connections yes)
			)
		)
		(pad "A30" smd rect
			(at -12.75 8.875)
			(size 0.3 1.75)
			(layers "F.Cu" "F.Mask" "F.Paste")
			(net 307 "unconnected-(J12H-RSVD-PadA30)")
			(pinfunction "RSVD")
			(pintype "no_connect")
			(teardrops
				(best_length_ratio 0.2)
				(max_length 1)
				(best_width_ratio 0.9)
				(max_width 2)
				(curved_edges yes)
				(filter_ratio 0.9)
				(enabled yes)
				(allow_two_segments yes)
				(prefer_zone_connections yes)
			)
		)
		(pad "A31" smd rect
			(at -12.25 8.875)
			(size 0.3 1.75)
			(layers "F.Cu" "F.Mask" "F.Paste")
			(net 1 "GND")
			(pinfunction "GND(FIXED)")
			(pintype "passive")
			(teardrops
				(best_length_ratio 0.2)
				(max_length 1)
				(best_width_ratio 0.9)
				(max_width 2)
				(curved_edges yes)
				(filter_ratio 0.9)
				(enabled yes)
				(allow_two_segments yes)
				(prefer_zone_connections yes)
			)
		)
		(pad "A32" smd rect
			(at -11.75 8.875)
			(size 0.3 1.75)
			(layers "F.Cu" "F.Mask" "F.Paste")
			(net 308 "unconnected-(J12H-RSVD-PadA32)")
			(pinfunction "RSVD")
			(pintype "no_connect")
			(teardrops
				(best_length_ratio 0.2)
				(max_length 1)
				(best_width_ratio 0.9)
				(max_width 2)
				(curved_edges yes)
				(filter_ratio 0.9)
				(enabled yes)
				(allow_two_segments yes)
				(prefer_zone_connections yes)
			)
		)
		(pad "A33" smd rect
			(at -11.25 8.875)
			(size 0.3 1.75)
			(layers "F.Cu" "F.Mask" "F.Paste")
			(net 309 "unconnected-(J12H-RSVD-PadA33)")
			(pinfunction "RSVD")
			(pintype "no_connect")
			(teardrops
				(best_length_ratio 0.2)
				(max_length 1)
				(best_width_ratio 0.9)
				(max_width 2)
				(curved_edges yes)
				(filter_ratio 0.9)
				(enabled yes)
				(allow_two_segments yes)
				(prefer_zone_connections yes)
			)
		)
		(pad "A34" smd rect
			(at -10.75 8.875)
			(size 0.3 1.75)
			(layers "F.Cu" "F.Mask" "F.Paste")
			(net 310 "/Com Express 7 MGMT/~{BIOS_DIS0}")
			(pinfunction "~{BIOS_DIS0}/ESPI_SAFS")
			(pintype "input")
			(teardrops
				(best_length_ratio 0.2)
				(max_length 1)
				(best_width_ratio 0.9)
				(max_width 2)
				(curved_edges yes)
				(filter_ratio 0.9)
				(enabled yes)
				(allow_two_segments yes)
				(prefer_zone_connections yes)
			)
		)
		(pad "A35" smd rect
			(at -10.25 8.875)
			(size 0.3 1.75)
			(layers "F.Cu" "F.Mask" "F.Paste")
			(net 311 "Net-(J12D-~{THRMTRIP})")
			(pinfunction "~{THRMTRIP}")
			(pintype "output")
			(teardrops
				(best_length_ratio 0.2)
				(max_length 1)
				(best_width_ratio 0.9)
				(max_width 2)
				(curved_edges yes)
				(filter_ratio 0.9)
				(enabled yes)
				(allow_two_segments yes)
				(prefer_zone_connections yes)
			)
		)
		(pad "A36" smd rect
			(at -9.75 8.875)
			(size 0.3 1.75)
			(layers "F.Cu" "F.Mask" "F.Paste")
			(net 259 "/Com Express 7 Interfaces/PCIe_{B2Bx4}.TX1+")
			(pinfunction "PCIE_TX13+")
			(pintype "output")
			(teardrops
				(best_length_ratio 0.2)
				(max_length 1)
				(best_width_ratio 0.9)
				(max_width 2)
				(curved_edges yes)
				(filter_ratio 0.9)
				(enabled yes)
				(allow_two_segments yes)
				(prefer_zone_connections yes)
			)
		)
		(pad "A37" smd rect
			(at -9.25 8.875)
			(size 0.3 1.75)
			(layers "F.Cu" "F.Mask" "F.Paste")
			(net 257 "/Com Express 7 Interfaces/PCIe_{B2Bx4}.TX1-")
			(pinfunction "PCIE_TX13-")
			(pintype "output")
			(teardrops
				(best_length_ratio 0.2)
				(max_length 1)
				(best_width_ratio 0.9)
				(max_width 2)
				(curved_edges yes)
				(filter_ratio 0.9)
				(enabled yes)
				(allow_two_segments yes)
				(prefer_zone_connections yes)
			)
		)
		(pad "A38" smd rect
			(at -8.75 8.875)
			(size 0.3 1.75)
			(layers "F.Cu" "F.Mask" "F.Paste")
			(net 1 "GND")
			(pinfunction "GND")
			(pintype "power_in")
			(teardrops
				(best_length_ratio 0.2)
				(max_length 1)
				(best_width_ratio 0.9)
				(max_width 2)
				(curved_edges yes)
				(filter_ratio 0.9)
				(enabled yes)
				(allow_two_segments yes)
				(prefer_zone_connections yes)
			)
		)
		(pad "A39" smd rect
			(at -8.25 8.875)
			(size 0.3 1.75)
			(layers "F.Cu" "F.Mask" "F.Paste")
			(net 269 "/Com Express 7 Interfaces/PCIe_{B2Bx4}.TX0+")
			(pinfunction "PCIE_TX12+")
			(pintype "output")
			(teardrops
				(best_length_ratio 0.2)
				(max_length 1)
				(best_width_ratio 0.9)
				(max_width 2)
				(curved_edges yes)
				(filter_ratio 0.9)
				(enabled yes)
				(allow_two_segments yes)
				(prefer_zone_connections yes)
			)
		)
		(pad "A40" smd rect
			(at -7.75 8.875)
			(size 0.3 1.75)
			(layers "F.Cu" "F.Mask" "F.Paste")
			(net 267 "/Com Express 7 Interfaces/PCIe_{B2Bx4}.TX0-")
			(pinfunction "PCIE_TX12-")
			(pintype "output")
			(teardrops
				(best_length_ratio 0.2)
				(max_length 1)
				(best_width_ratio 0.9)
				(max_width 2)
				(curved_edges yes)
				(filter_ratio 0.9)
				(enabled yes)
				(allow_two_segments yes)
				(prefer_zone_connections yes)
			)
		)
		(pad "A41" smd rect
			(at -7.25 8.875)
			(size 0.3 1.75)
			(layers "F.Cu" "F.Mask" "F.Paste")
			(net 1 "GND")
			(pinfunction "GND(FIXED)")
			(pintype "passive")
			(teardrops
				(best_length_ratio 0.2)
				(max_length 1)
				(best_width_ratio 0.9)
				(max_width 2)
				(curved_edges yes)
				(filter_ratio 0.9)
				(enabled yes)
				(allow_two_segments yes)
				(prefer_zone_connections yes)
			)
		)
		(pad "A42" smd rect
			(at -6.75 8.875)
			(size 0.3 1.75)
			(layers "F.Cu" "F.Mask" "F.Paste")
			(net 312 "/2xUSB3.0+RJ45/USB_1.D-")
			(pinfunction "USB2-")
			(pintype "bidirectional")
			(teardrops
				(best_length_ratio 0.2)
				(max_length 1)
				(best_width_ratio 0.9)
				(max_width 2)
				(curved_edges yes)
				(filter_ratio 0.9)
				(enabled yes)
				(allow_two_segments yes)
				(prefer_zone_connections yes)
			)
		)
		(pad "A43" smd rect
			(at -6.25 8.875)
			(size 0.3 1.75)
			(layers "F.Cu" "F.Mask" "F.Paste")
			(net 313 "/2xUSB3.0+RJ45/USB_1.D+")
			(pinfunction "USB2+")
			(pintype "bidirectional")
			(teardrops
				(best_length_ratio 0.2)
				(max_length 1)
				(best_width_ratio 0.9)
				(max_width 2)
				(curved_edges yes)
				(filter_ratio 0.9)
				(enabled yes)
				(allow_two_segments yes)
				(prefer_zone_connections yes)
			)
		)
		(pad "A44" smd rect
			(at -5.75 8.875)
			(size 0.3 1.75)
			(layers "F.Cu" "F.Mask" "F.Paste")
			(net 314 "/2xUSB3.0+RJ45/FLG_1")
			(pinfunction "~{USB_2_3_OC}")
			(pintype "input")
			(teardrops
				(best_length_ratio 0.2)
				(max_length 1)
				(best_width_ratio 0.9)
				(max_width 2)
				(curved_edges yes)
				(filter_ratio 0.9)
				(enabled yes)
				(allow_two_segments yes)
				(prefer_zone_connections yes)
			)
		)
		(pad "A45" smd rect
			(at -5.25 8.875)
			(size 0.3 1.75)
			(layers "F.Cu" "F.Mask" "F.Paste")
			(net 204 "/Backplane/USB.D-")
			(pinfunction "USB0-")
			(pintype "bidirectional")
			(teardrops
				(best_length_ratio 0.2)
				(max_length 1)
				(best_width_ratio 0.9)
				(max_width 2)
				(curved_edges yes)
				(filter_ratio 0.9)
				(enabled yes)
				(allow_two_segments yes)
				(prefer_zone_connections yes)
			)
		)
		(pad "A46" smd rect
			(at -4.75 8.875)
			(size 0.3 1.75)
			(layers "F.Cu" "F.Mask" "F.Paste")
			(net 206 "/Backplane/USB.D+")
			(pinfunction "USB0+")
			(pintype "bidirectional")
			(teardrops
				(best_length_ratio 0.2)
				(max_length 1)
				(best_width_ratio 0.9)
				(max_width 2)
				(curved_edges yes)
				(filter_ratio 0.9)
				(enabled yes)
				(allow_two_segments yes)
				(prefer_zone_connections yes)
			)
		)
		(pad "A47" smd rect
			(at -4.25 8.875)
			(size 0.3 1.75)
			(layers "F.Cu" "F.Mask" "F.Paste")
			(net 315 "Net-(J12H-VCC_RTC)")
			(pinfunction "VCC_RTC")
			(pintype "power_in")
			(teardrops
				(best_length_ratio 0.2)
				(max_length 1)
				(best_width_ratio 0.9)
				(max_width 2)
				(curved_edges yes)
				(filter_ratio 0.9)
				(enabled yes)
				(allow_two_segments yes)
				(prefer_zone_connections yes)
			)
		)
		(pad "A48" smd rect
			(at -3.75 8.875)
			(size 0.3 1.75)
			(layers "F.Cu" "F.Mask" "F.Paste")
			(net 316 "unconnected-(J12H-RSVD-PadA48)")
			(pinfunction "RSVD")
			(pintype "no_connect")
			(teardrops
				(best_length_ratio 0.2)
				(max_length 1)
				(best_width_ratio 0.9)
				(max_width 2)
				(curved_edges yes)
				(filter_ratio 0.9)
				(enabled yes)
				(allow_two_segments yes)
				(prefer_zone_connections yes)
			)
		)
		(pad "A49" smd rect
			(at -3.25 8.875)
			(size 0.3 1.75)
			(layers "F.Cu" "F.Mask" "F.Paste")
			(net 317 "unconnected-(J12B-GBE0_SDP-PadA49)")
			(pinfunction "GBE0_SDP")
			(pintype "bidirectional+no_connect")
			(teardrops
				(best_length_ratio 0.2)
				(max_length 1)
				(best_width_ratio 0.9)
				(max_width 2)
				(curved_edges yes)
				(filter_ratio 0.9)
				(enabled yes)
				(allow_two_segments yes)
				(prefer_zone_connections yes)
			)
		)
		(pad "A50" smd rect
			(at -2.75 8.875)
			(size 0.3 1.75)
			(layers "F.Cu" "F.Mask" "F.Paste")
			(net 318 "Net-(J12D-LPC_SERIRQ{slash}~{ESPI_CS1})")
			(pinfunction "LPC_SERIRQ/~{ESPI_CS1}")
			(pintype "bidirectional")
			(teardrops
				(best_length_ratio 0.2)
				(max_length 1)
				(best_width_ratio 0.9)
				(max_width 2)
				(curved_edges yes)
				(filter_ratio 0.9)
				(enabled yes)
				(allow_two_segments yes)
				(prefer_zone_connections yes)
			)
		)
		(pad "A51" smd rect
			(at -2.25 8.875)
			(size 0.3 1.75)
			(layers "F.Cu" "F.Mask" "F.Paste")
			(net 1 "GND")
			(pinfunction "GND(FIXED)")
			(pintype "passive")
			(teardrops
				(best_length_ratio 0.2)
				(max_length 1)
				(best_width_ratio 0.9)
				(max_width 2)
				(curved_edges yes)
				(filter_ratio 0.9)
				(enabled yes)
				(allow_two_segments yes)
				(prefer_zone_connections yes)
			)
		)
		(pad "A52" smd rect
			(at -1.75 8.875)
			(size 0.3 1.75)
			(layers "F.Cu" "F.Mask" "F.Paste")
			(net 319 "/Com Express 7 Interfaces/PCIe_{B1x2}.TX1+")
			(pinfunction "PCIE_TX5+")
			(pintype "output+no_connect")
			(teardrops
				(best_length_ratio 0.2)
				(max_length 1)
				(best_width_ratio 0.9)
				(max_width 2)
				(curved_edges yes)
				(filter_ratio 0.9)
				(enabled yes)
				(allow_two_segments yes)
				(prefer_zone_connections yes)
			)
		)
		(pad "A53" smd rect
			(at -1.25 8.875)
			(size 0.3 1.75)
			(layers "F.Cu" "F.Mask" "F.Paste")
			(net 320 "/Com Express 7 Interfaces/PCIe_{B1x2}.TX1-")
			(pinfunction "PCIE_TX5-")
			(pintype "output+no_connect")
			(teardrops
				(best_length_ratio 0.2)
				(max_length 1)
				(best_width_ratio 0.9)
				(max_width 2)
				(curved_edges yes)
				(filter_ratio 0.9)
				(enabled yes)
				(allow_two_segments yes)
				(prefer_zone_connections yes)
			)
		)
		(pad "A54" smd rect
			(at -0.75 8.875)
			(size 0.3 1.75)
			(layers "F.Cu" "F.Mask" "F.Paste")
			(net 321 "/Com Express 7 Interfaces/SDIO.DAT0")
			(pinfunction "GPI0")
			(pintype "input")
			(teardrops
				(best_length_ratio 0.2)
				(max_length 1)
				(best_width_ratio 0.9)
				(max_width 2)
				(curved_edges yes)
				(filter_ratio 0.9)
				(enabled yes)
				(allow_two_segments yes)
				(prefer_zone_connections yes)
			)
		)
		(pad "A55" smd rect
			(at -0.25 8.875)
			(size 0.3 1.75)
			(layers "F.Cu" "F.Mask" "F.Paste")
			(net 9 "/Com Express 7 Interfaces/PCIe_{B1x2}.TX0+")
			(pinfunction "PCIE_TX4+")
			(pintype "output")
			(teardrops
				(best_length_ratio 0.2)
				(max_length 1)
				(best_width_ratio 0.9)
				(max_width 2)
				(curved_edges yes)
				(filter_ratio 0.9)
				(enabled yes)
				(allow_two_segments yes)
				(prefer_zone_connections yes)
			)
		)
		(pad "A56" smd rect
			(at 0.25 8.875)
			(size 0.3 1.75)
			(layers "F.Cu" "F.Mask" "F.Paste")
			(net 11 "/Com Express 7 Interfaces/PCIe_{B1x2}.TX0-")
			(pinfunction "PCIE_TX4-")
			(pintype "output")
			(teardrops
				(best_length_ratio 0.2)
				(max_length 1)
				(best_width_ratio 0.9)
				(max_width 2)
				(curved_edges yes)
				(filter_ratio 0.9)
				(enabled yes)
				(allow_two_segments yes)
				(prefer_zone_connections yes)
			)
		)
		(pad "A57" smd rect
			(at 0.75 8.875)
			(size 0.3 1.75)
			(layers "F.Cu" "F.Mask" "F.Paste")
			(net 1 "GND")
			(pinfunction "GND")
			(pintype "passive")
			(teardrops
				(best_length_ratio 0.2)
				(max_length 1)
				(best_width_ratio 0.9)
				(max_width 2)
				(curved_edges yes)
				(filter_ratio 0.9)
				(enabled yes)
				(allow_two_segments yes)
				(prefer_zone_connections yes)
			)
		)
		(pad "A58" smd rect
			(at 1.25 8.875)
			(size 0.3 1.75)
			(layers "F.Cu" "F.Mask" "F.Paste")
			(net 212 "/Com Express 7 Interfaces/PCIe_{B1x4}.TX3+")
			(pinfunction "PCIE_TX3+")
			(pintype "output")
			(teardrops
				(best_length_ratio 0.2)
				(max_length 1)
				(best_width_ratio 0.9)
				(max_width 2)
				(curved_edges yes)
				(filter_ratio 0.9)
				(enabled yes)
				(allow_two_segments yes)
				(prefer_zone_connections yes)
			)
		)
		(pad "A59" smd rect
			(at 1.75 8.875)
			(size 0.3 1.75)
			(layers "F.Cu" "F.Mask" "F.Paste")
			(net 211 "/Com Express 7 Interfaces/PCIe_{B1x4}.TX3-")
			(pinfunction "PCIE_TX3-")
			(pintype "output")
			(teardrops
				(best_length_ratio 0.2)
				(max_length 1)
				(best_width_ratio 0.9)
				(max_width 2)
				(curved_edges yes)
				(filter_ratio 0.9)
				(enabled yes)
				(allow_two_segments yes)
				(prefer_zone_connections yes)
			)
		)
		(pad "A60" smd rect
			(at 2.25 8.875)
			(size 0.3 1.75)
			(layers "F.Cu" "F.Mask" "F.Paste")
			(net 1 "GND")
			(pinfunction "GND(FIXED)")
			(pintype "passive")
			(teardrops
				(best_length_ratio 0.2)
				(max_length 1)
				(best_width_ratio 0.9)
				(max_width 2)
				(curved_edges yes)
				(filter_ratio 0.9)
				(enabled yes)
				(allow_two_segments yes)
				(prefer_zone_connections yes)
			)
		)
		(pad "A61" smd rect
			(at 2.75 8.875)
			(size 0.3 1.75)
			(layers "F.Cu" "F.Mask" "F.Paste")
			(net 216 "/Com Express 7 Interfaces/PCIe_{B1x4}.TX2+")
			(pinfunction "PCIE_TX2+")
			(pintype "output")
			(teardrops
				(best_length_ratio 0.2)
				(max_length 1)
				(best_width_ratio 0.9)
				(max_width 2)
				(curved_edges yes)
				(filter_ratio 0.9)
				(enabled yes)
				(allow_two_segments yes)
				(prefer_zone_connections yes)
			)
		)
		(pad "A62" smd rect
			(at 3.25 8.875)
			(size 0.3 1.75)
			(layers "F.Cu" "F.Mask" "F.Paste")
			(net 215 "/Com Express 7 Interfaces/PCIe_{B1x4}.TX2-")
			(pinfunction "PCIE_TX2-")
			(pintype "output")
			(teardrops
				(best_length_ratio 0.2)
				(max_length 1)
				(best_width_ratio 0.9)
				(max_width 2)
				(curved_edges yes)
				(filter_ratio 0.9)
				(enabled yes)
				(allow_two_segments yes)
				(prefer_zone_connections yes)
			)
		)
		(pad "A63" smd rect
			(at 3.75 8.875)
			(size 0.3 1.75)
			(layers "F.Cu" "F.Mask" "F.Paste")
			(net 322 "/Com Express 7 Interfaces/SDIO.DAT1")
			(pinfunction "GPI1")
			(pintype "input")
			(teardrops
				(best_length_ratio 0.2)
				(max_length 1)
				(best_width_ratio 0.9)
				(max_width 2)
				(curved_edges yes)
				(filter_ratio 0.9)
				(enabled yes)
				(allow_two_segments yes)
				(prefer_zone_connections yes)
			)
		)
		(pad "A64" smd rect
			(at 4.25 8.875)
			(size 0.3 1.75)
			(layers "F.Cu" "F.Mask" "F.Paste")
			(net 220 "/Com Express 7 Interfaces/PCIe_{B1x4}.TX1+")
			(pinfunction "PCIE_TX1+")
			(pintype "output")
			(teardrops
				(best_length_ratio 0.2)
				(max_length 1)
				(best_width_ratio 0.9)
				(max_width 2)
				(curved_edges yes)
				(filter_ratio 0.9)
				(enabled yes)
				(allow_two_segments yes)
				(prefer_zone_connections yes)
			)
		)
		(pad "A65" smd rect
			(at 4.75 8.875)
			(size 0.3 1.75)
			(layers "F.Cu" "F.Mask" "F.Paste")
			(net 219 "/Com Express 7 Interfaces/PCIe_{B1x4}.TX1-")
			(pinfunction "PCIE_TX1-")
			(pintype "output")
			(teardrops
				(best_length_ratio 0.2)
				(max_length 1)
				(best_width_ratio 0.9)
				(max_width 2)
				(curved_edges yes)
				(filter_ratio 0.9)
				(enabled yes)
				(allow_two_segments yes)
				(prefer_zone_connections yes)
			)
		)
		(pad "A66" smd rect
			(at 5.25 8.875)
			(size 0.3 1.75)
			(layers "F.Cu" "F.Mask" "F.Paste")
			(net 1 "GND")
			(pinfunction "GND")
			(pintype "passive")
			(teardrops
				(best_length_ratio 0.2)
				(max_length 1)
				(best_width_ratio 0.9)
				(max_width 2)
				(curved_edges yes)
				(filter_ratio 0.9)
				(enabled yes)
				(allow_two_segments yes)
				(prefer_zone_connections yes)
			)
		)
		(pad "A67" smd rect
			(at 5.75 8.875)
			(size 0.3 1.75)
			(layers "F.Cu" "F.Mask" "F.Paste")
			(net 323 "/Com Express 7 Interfaces/SDIO.DAT2")
			(pinfunction "GPI2")
			(pintype "input")
			(teardrops
				(best_length_ratio 0.2)
				(max_length 1)
				(best_width_ratio 0.9)
				(max_width 2)
				(curved_edges yes)
				(filter_ratio 0.9)
				(enabled yes)
				(allow_two_segments yes)
				(prefer_zone_connections yes)
			)
		)
		(pad "A68" smd rect
			(at 6.25 8.875)
			(size 0.3 1.75)
			(layers "F.Cu" "F.Mask" "F.Paste")
			(net 227 "/Com Express 7 Interfaces/PCIe_{B1x4}.TX0+")
			(pinfunction "PCIE_TX0+")
			(pintype "output")
			(teardrops
				(best_length_ratio 0.2)
				(max_length 1)
				(best_width_ratio 0.9)
				(max_width 2)
				(curved_edges yes)
				(filter_ratio 0.9)
				(enabled yes)
				(allow_two_segments yes)
				(prefer_zone_connections yes)
			)
		)
		(pad "A69" smd rect
			(at 6.75 8.875)
			(size 0.3 1.75)
			(layers "F.Cu" "F.Mask" "F.Paste")
			(net 225 "/Com Express 7 Interfaces/PCIe_{B1x4}.TX0-")
			(pinfunction "PCIE_TX0-")
			(pintype "output")
			(teardrops
				(best_length_ratio 0.2)
				(max_length 1)
				(best_width_ratio 0.9)
				(max_width 2)
				(curved_edges yes)
				(filter_ratio 0.9)
				(enabled yes)
				(allow_two_segments yes)
				(prefer_zone_connections yes)
			)
		)
		(pad "A70" smd rect
			(at 7.25 8.875)
			(size 0.3 1.75)
			(layers "F.Cu" "F.Mask" "F.Paste")
			(net 1 "GND")
			(pinfunction "GND(FIXED)")
			(pintype "passive")
			(teardrops
				(best_length_ratio 0.2)
				(max_length 1)
				(best_width_ratio 0.9)
				(max_width 2)
				(curved_edges yes)
				(filter_ratio 0.9)
				(enabled yes)
				(allow_two_segments yes)
				(prefer_zone_connections yes)
			)
		)
		(pad "A71" smd rect
			(at 7.75 8.875)
			(size 0.3 1.75)
			(layers "F.Cu" "F.Mask" "F.Paste")
			(net 324 "/Com Express 7 Interfaces/PCIe_{B2Ax4}.TX0+")
			(pinfunction "PCIE_TX8+")
			(pintype "output")
			(teardrops
				(best_length_ratio 0.2)
				(max_length 1)
				(best_width_ratio 0.9)
				(max_width 2)
				(curved_edges yes)
				(filter_ratio 0.9)
				(enabled yes)
				(allow_two_segments yes)
				(prefer_zone_connections yes)
			)
		)
		(pad "A72" smd rect
			(at 8.25 8.875)
			(size 0.3 1.75)
			(layers "F.Cu" "F.Mask" "F.Paste")
			(net 325 "/Com Express 7 Interfaces/PCIe_{B2Ax4}.TX0-")
			(pinfunction "PCIE_TX8-")
			(pintype "output")
			(teardrops
				(best_length_ratio 0.2)
				(max_length 1)
				(best_width_ratio 0.9)
				(max_width 2)
				(curved_edges yes)
				(filter_ratio 0.9)
				(enabled yes)
				(allow_two_segments yes)
				(prefer_zone_connections yes)
			)
		)
		(pad "A73" smd rect
			(at 8.75 8.875)
			(size 0.3 1.75)
			(layers "F.Cu" "F.Mask" "F.Paste")
			(net 1 "GND")
			(pinfunction "GND")
			(pintype "passive")
			(teardrops
				(best_length_ratio 0.2)
				(max_length 1)
				(best_width_ratio 0.9)
				(max_width 2)
				(curved_edges yes)
				(filter_ratio 0.9)
				(enabled yes)
				(allow_two_segments yes)
				(prefer_zone_connections yes)
			)
		)
		(pad "A74" smd rect
			(at 9.25 8.875)
			(size 0.3 1.75)
			(layers "F.Cu" "F.Mask" "F.Paste")
			(net 326 "/Com Express 7 Interfaces/PCIe_{B2Ax4}.TX1+")
			(pinfunction "PCIE_TX9+")
			(pintype "output")
			(teardrops
				(best_length_ratio 0.2)
				(max_length 1)
				(best_width_ratio 0.9)
				(max_width 2)
				(curved_edges yes)
				(filter_ratio 0.9)
				(enabled yes)
				(allow_two_segments yes)
				(prefer_zone_connections yes)
			)
		)
		(pad "A75" smd rect
			(at 9.75 8.875)
			(size 0.3 1.75)
			(layers "F.Cu" "F.Mask" "F.Paste")
			(net 327 "/Com Express 7 Interfaces/PCIe_{B2Ax4}.TX1-")
			(pinfunction "PCIE_TX9-")
			(pintype "output")
			(teardrops
				(best_length_ratio 0.2)
				(max_length 1)
				(best_width_ratio 0.9)
				(max_width 2)
				(curved_edges yes)
				(filter_ratio 0.9)
				(enabled yes)
				(allow_two_segments yes)
				(prefer_zone_connections yes)
			)
		)
		(pad "A76" smd rect
			(at 10.25 8.875)
			(size 0.3 1.75)
			(layers "F.Cu" "F.Mask" "F.Paste")
			(net 1 "GND")
			(pinfunction "GND")
			(pintype "passive")
			(teardrops
				(best_length_ratio 0.2)
				(max_length 1)
				(best_width_ratio 0.9)
				(max_width 2)
				(curved_edges yes)
				(filter_ratio 0.9)
				(enabled yes)
				(allow_two_segments yes)
				(prefer_zone_connections yes)
			)
		)
		(pad "A77" smd rect
			(at 10.75 8.875)
			(size 0.3 1.75)
			(layers "F.Cu" "F.Mask" "F.Paste")
			(net 328 "/Com Express 7 Interfaces/PCIe_{B2Ax4}.TX2+")
			(pinfunction "PCIE_TX10+")
			(pintype "output")
			(teardrops
				(best_length_ratio 0.2)
				(max_length 1)
				(best_width_ratio 0.9)
				(max_width 2)
				(curved_edges yes)
				(filter_ratio 0.9)
				(enabled yes)
				(allow_two_segments yes)
				(prefer_zone_connections yes)
			)
		)
		(pad "A78" smd rect
			(at 11.25 8.875)
			(size 0.3 1.75)
			(layers "F.Cu" "F.Mask" "F.Paste")
			(net 329 "/Com Express 7 Interfaces/PCIe_{B2Ax4}.TX2-")
			(pinfunction "PCIE_TX10-")
			(pintype "output")
			(teardrops
				(best_length_ratio 0.2)
				(max_length 1)
				(best_width_ratio 0.9)
				(max_width 2)
				(curved_edges yes)
				(filter_ratio 0.9)
				(enabled yes)
				(allow_two_segments yes)
				(prefer_zone_connections yes)
			)
		)
		(pad "A79" smd rect
			(at 11.75 8.875)
			(size 0.3 1.75)
			(layers "F.Cu" "F.Mask" "F.Paste")
			(net 1 "GND")
			(pinfunction "GND")
			(pintype "passive")
			(teardrops
				(best_length_ratio 0.2)
				(max_length 1)
				(best_width_ratio 0.9)
				(max_width 2)
				(curved_edges yes)
				(filter_ratio 0.9)
				(enabled yes)
				(allow_two_segments yes)
				(prefer_zone_connections yes)
			)
		)
		(pad "A80" smd rect
			(at 12.25 8.875)
			(size 0.3 1.75)
			(layers "F.Cu" "F.Mask" "F.Paste")
			(net 1 "GND")
			(pinfunction "GND(FIXED)")
			(pintype "passive")
			(teardrops
				(best_length_ratio 0.2)
				(max_length 1)
				(best_width_ratio 0.9)
				(max_width 2)
				(curved_edges yes)
				(filter_ratio 0.9)
				(enabled yes)
				(allow_two_segments yes)
				(prefer_zone_connections yes)
			)
		)
		(pad "A81" smd rect
			(at 12.75 8.875)
			(size 0.3 1.75)
			(layers "F.Cu" "F.Mask" "F.Paste")
			(net 330 "/Com Express 7 Interfaces/PCIe_{B2Ax4}.TX3+")
			(pinfunction "PCIE_TX11+")
			(pintype "output")
			(teardrops
				(best_length_ratio 0.2)
				(max_length 1)
				(best_width_ratio 0.9)
				(max_width 2)
				(curved_edges yes)
				(filter_ratio 0.9)
				(enabled yes)
				(allow_two_segments yes)
				(prefer_zone_connections yes)
			)
		)
		(pad "A82" smd rect
			(at 13.25 8.875)
			(size 0.3 1.75)
			(layers "F.Cu" "F.Mask" "F.Paste")
			(net 331 "/Com Express 7 Interfaces/PCIe_{B2Ax4}.TX3-")
			(pinfunction "PCIE_TX11-")
			(pintype "output")
			(teardrops
				(best_length_ratio 0.2)
				(max_length 1)
				(best_width_ratio 0.9)
				(max_width 2)
				(curved_edges yes)
				(filter_ratio 0.9)
				(enabled yes)
				(allow_two_segments yes)
				(prefer_zone_connections yes)
			)
		)
		(pad "A83" smd rect
			(at 13.75 8.875)
			(size 0.3 1.75)
			(layers "F.Cu" "F.Mask" "F.Paste")
			(net 1 "GND")
			(pinfunction "GND")
			(pintype "passive")
			(teardrops
				(best_length_ratio 0.2)
				(max_length 1)
				(best_width_ratio 0.9)
				(max_width 2)
				(curved_edges yes)
				(filter_ratio 0.9)
				(enabled yes)
				(allow_two_segments yes)
				(prefer_zone_connections yes)
			)
		)
		(pad "A84" smd rect
			(at 14.25 8.875)
			(size 0.3 1.75)
			(layers "F.Cu" "F.Mask" "F.Paste")
			(net 332 "unconnected-(J12A-NCSI_TX_EN-PadA84)")
			(pinfunction "NCSI_TX_EN")
			(pintype "output+no_connect")
			(teardrops
				(best_length_ratio 0.2)
				(max_length 1)
				(best_width_ratio 0.9)
				(max_width 2)
				(curved_edges yes)
				(filter_ratio 0.9)
				(enabled yes)
				(allow_two_segments yes)
				(prefer_zone_connections yes)
			)
		)
		(pad "A85" smd rect
			(at 14.75 8.875)
			(size 0.3 1.75)
			(layers "F.Cu" "F.Mask" "F.Paste")
			(net 333 "/Com Express 7 Interfaces/SDIO.DAT3")
			(pinfunction "GPI3")
			(pintype "input")
			(teardrops
				(best_length_ratio 0.2)
				(max_length 1)
				(best_width_ratio 0.9)
				(max_width 2)
				(curved_edges yes)
				(filter_ratio 0.9)
				(enabled yes)
				(allow_two_segments yes)
				(prefer_zone_connections yes)
			)
		)
		(pad "A86" smd rect
			(at 15.25 8.875)
			(size 0.3 1.75)
			(layers "F.Cu" "F.Mask" "F.Paste")
			(net 334 "unconnected-(J12H-RSVD-PadA86)")
			(pinfunction "RSVD")
			(pintype "no_connect")
			(teardrops
				(best_length_ratio 0.2)
				(max_length 1)
				(best_width_ratio 0.9)
				(max_width 2)
				(curved_edges yes)
				(filter_ratio 0.9)
				(enabled yes)
				(allow_two_segments yes)
				(prefer_zone_connections yes)
			)
		)
		(pad "A87" smd rect
			(at 15.75 8.875)
			(size 0.3 1.75)
			(layers "F.Cu" "F.Mask" "F.Paste")
			(net 335 "unconnected-(J12H-RSVD-PadA87)")
			(pinfunction "RSVD")
			(pintype "no_connect")
			(teardrops
				(best_length_ratio 0.2)
				(max_length 1)
				(best_width_ratio 0.9)
				(max_width 2)
				(curved_edges yes)
				(filter_ratio 0.9)
				(enabled yes)
				(allow_two_segments yes)
				(prefer_zone_connections yes)
			)
		)
		(pad "A88" smd rect
			(at 16.25 8.875)
			(size 0.3 1.75)
			(layers "F.Cu" "F.Mask" "F.Paste")
			(net 336 "/Com Express 7 Interfaces/PCIE_{REF}.CK+")
			(pinfunction "PCIE_CK_REF+")
			(pintype "output")
			(teardrops
				(best_length_ratio 0.2)
				(max_length 1)
				(best_width_ratio 0.9)
				(max_width 2)
				(curved_edges yes)
				(filter_ratio 0.9)
				(enabled yes)
				(allow_two_segments yes)
				(prefer_zone_connections yes)
			)
		)
		(pad "A89" smd rect
			(at 16.75 8.875)
			(size 0.3 1.75)
			(layers "F.Cu" "F.Mask" "F.Paste")
			(net 337 "/Com Express 7 Interfaces/PCIE_{REF}.CK-")
			(pinfunction "PCIE_CK_REF-")
			(pintype "output")
			(teardrops
				(best_length_ratio 0.2)
				(max_length 1)
				(best_width_ratio 0.9)
				(max_width 2)
				(curved_edges yes)
				(filter_ratio 0.9)
				(enabled yes)
				(allow_two_segments yes)
				(prefer_zone_connections yes)
			)
		)
		(pad "A90" smd rect
			(at 17.25 8.875)
			(size 0.3 1.75)
			(layers "F.Cu" "F.Mask" "F.Paste")
			(net 1 "GND")
			(pinfunction "GND(FIXED)")
			(pintype "passive")
			(teardrops
				(best_length_ratio 0.2)
				(max_length 1)
				(best_width_ratio 0.9)
				(max_width 2)
				(curved_edges yes)
				(filter_ratio 0.9)
				(enabled yes)
				(allow_two_segments yes)
				(prefer_zone_connections yes)
			)
		)
		(pad "A91" smd rect
			(at 17.75 8.875)
			(size 0.3 1.75)
			(layers "F.Cu" "F.Mask" "F.Paste")
			(net 139 "/Com Express 7 MGMT/SPI_POWER")
			(pinfunction "SPI_POWER")
			(pintype "power_out")
			(teardrops
				(best_length_ratio 0.2)
				(max_length 1)
				(best_width_ratio 0.9)
				(max_width 2)
				(curved_edges yes)
				(filter_ratio 0.9)
				(enabled yes)
				(allow_two_segments yes)
				(prefer_zone_connections yes)
			)
		)
		(pad "A92" smd rect
			(at 18.25 8.875)
			(size 0.3 1.75)
			(layers "F.Cu" "F.Mask" "F.Paste")
			(net 338 "/Com Express 7 MGMT/SPI.MISO")
			(pinfunction "SPI_MISO")
			(pintype "input")
			(teardrops
				(best_length_ratio 0.2)
				(max_length 1)
				(best_width_ratio 0.9)
				(max_width 2)
				(curved_edges yes)
				(filter_ratio 0.9)
				(enabled yes)
				(allow_two_segments yes)
				(prefer_zone_connections yes)
			)
		)
		(pad "A93" smd rect
			(at 18.75 8.875)
			(size 0.3 1.75)
			(layers "F.Cu" "F.Mask" "F.Paste")
			(net 339 "/Com Express 7 Interfaces/SDIO.CLK")
			(pinfunction "GPO0")
			(pintype "output")
			(teardrops
				(best_length_ratio 0.2)
				(max_length 1)
				(best_width_ratio 0.9)
				(max_width 2)
				(curved_edges yes)
				(filter_ratio 0.9)
				(enabled yes)
				(allow_two_segments yes)
				(prefer_zone_connections yes)
			)
		)
		(pad "A94" smd rect
			(at 19.25 8.875)
			(size 0.3 1.75)
			(layers "F.Cu" "F.Mask" "F.Paste")
			(net 340 "/Com Express 7 MGMT/SPI.CLK")
			(pinfunction "SPI_CLK")
			(pintype "output")
			(teardrops
				(best_length_ratio 0.2)
				(max_length 1)
				(best_width_ratio 0.9)
				(max_width 2)
				(curved_edges yes)
				(filter_ratio 0.9)
				(enabled yes)
				(allow_two_segments yes)
				(prefer_zone_connections yes)
			)
		)
		(pad "A95" smd rect
			(at 19.75 8.875)
			(size 0.3 1.75)
			(layers "F.Cu" "F.Mask" "F.Paste")
			(net 341 "/Com Express 7 MGMT/SPI.MOSI")
			(pinfunction "SPI_MOSI")
			(pintype "output")
			(teardrops
				(best_length_ratio 0.2)
				(max_length 1)
				(best_width_ratio 0.9)
				(max_width 2)
				(curved_edges yes)
				(filter_ratio 0.9)
				(enabled yes)
				(allow_two_segments yes)
				(prefer_zone_connections yes)
			)
		)
		(pad "A96" smd rect
			(at 20.25 8.875)
			(size 0.3 1.75)
			(layers "F.Cu" "F.Mask" "F.Paste")
			(net 342 "Net-(J12D-TPM_PP)")
			(pinfunction "TPM_PP")
			(pintype "input")
			(teardrops
				(best_length_ratio 0.2)
				(max_length 1)
				(best_width_ratio 0.9)
				(max_width 2)
				(curved_edges yes)
				(filter_ratio 0.9)
				(enabled yes)
				(allow_two_segments yes)
				(prefer_zone_connections yes)
			)
		)
		(pad "A97" smd rect
			(at 20.75 8.875)
			(size 0.3 1.75)
			(layers "F.Cu" "F.Mask" "F.Paste")
			(net 343 "Net-(J12D-~{TYPE10})")
			(pinfunction "~{TYPE10}")
			(pintype "passive")
			(teardrops
				(best_length_ratio 0.2)
				(max_length 1)
				(best_width_ratio 0.9)
				(max_width 2)
				(curved_edges yes)
				(filter_ratio 0.9)
				(enabled yes)
				(allow_two_segments yes)
				(prefer_zone_connections yes)
			)
		)
		(pad "A98" smd rect
			(at 21.25 8.875)
			(size 0.3 1.75)
			(layers "F.Cu" "F.Mask" "F.Paste")
			(net 344 "/Com Express 7 MGMT/SER0.TX")
			(pinfunction "SER0_TX")
			(pintype "output")
			(teardrops
				(best_length_ratio 0.2)
				(max_length 1)
				(best_width_ratio 0.9)
				(max_width 2)
				(curved_edges yes)
				(filter_ratio 0.9)
				(enabled yes)
				(allow_two_segments yes)
				(prefer_zone_connections yes)
			)
		)
		(pad "A99" smd rect
			(at 21.75 8.875)
			(size 0.3 1.75)
			(layers "F.Cu" "F.Mask" "F.Paste")
			(net 345 "/Com Express 7 MGMT/SER0.RX")
			(pinfunction "SER0_RX")
			(pintype "input")
			(teardrops
				(best_length_ratio 0.2)
				(max_length 1)
				(best_width_ratio 0.9)
				(max_width 2)
				(curved_edges yes)
				(filter_ratio 0.9)
				(enabled yes)
				(allow_two_segments yes)
				(prefer_zone_connections yes)
			)
		)
		(pad "A100" smd rect
			(at 22.25 8.875)
			(size 0.3 1.75)
			(layers "F.Cu" "F.Mask" "F.Paste")
			(net 1 "GND")
			(pinfunction "GND(FIXED)")
			(pintype "passive")
			(teardrops
				(best_length_ratio 0.2)
				(max_length 1)
				(best_width_ratio 0.9)
				(max_width 2)
				(curved_edges yes)
				(filter_ratio 0.9)
				(enabled yes)
				(allow_two_segments yes)
				(prefer_zone_connections yes)
			)
		)
		(pad "A101" smd rect
			(at 22.75 8.875)
			(size 0.3 1.75)
			(layers "F.Cu" "F.Mask" "F.Paste")
			(net 207 "/Backplane/UART.TX")
			(pinfunction "SER1_TX")
			(pintype "output")
			(teardrops
				(best_length_ratio 0.2)
				(max_length 1)
				(best_width_ratio 0.9)
				(max_width 2)
				(curved_edges yes)
				(filter_ratio 0.9)
				(enabled yes)
				(allow_two_segments yes)
				(prefer_zone_connections yes)
			)
		)
		(pad "A102" smd rect
			(at 23.25 8.875)
			(size 0.3 1.75)
			(layers "F.Cu" "F.Mask" "F.Paste")
			(net 208 "/Backplane/UART.RX")
			(pinfunction "SER1_RX")
			(pintype "input")
			(teardrops
				(best_length_ratio 0.2)
				(max_length 1)
				(best_width_ratio 0.9)
				(max_width 2)
				(curved_edges yes)
				(filter_ratio 0.9)
				(enabled yes)
				(allow_two_segments yes)
				(prefer_zone_connections yes)
			)
		)
		(pad "A103" smd rect
			(at 23.75 8.875)
			(size 0.3 1.75)
			(layers "F.Cu" "F.Mask" "F.Paste")
			(net 346 "unconnected-(J12D-~{LID}-PadA103)")
			(pinfunction "~{LID}")
			(pintype "input+no_connect")
			(teardrops
				(best_length_ratio 0.2)
				(max_length 1)
				(best_width_ratio 0.9)
				(max_width 2)
				(curved_edges yes)
				(filter_ratio 0.9)
				(enabled yes)
				(allow_two_segments yes)
				(prefer_zone_connections yes)
			)
		)
		(pad "A104" smd rect
			(at 24.25 8.875)
			(size 0.3 1.75)
			(layers "F.Cu" "F.Mask" "F.Paste")
			(net 65 "+12V")
			(pinfunction "VCC_12V")
			(pintype "power_in")
			(teardrops
				(best_length_ratio 0.2)
				(max_length 1)
				(best_width_ratio 0.9)
				(max_width 2)
				(curved_edges yes)
				(filter_ratio 0.9)
				(enabled yes)
				(allow_two_segments yes)
				(prefer_zone_connections yes)
			)
		)
		(pad "A105" smd rect
			(at 24.75 8.875)
			(size 0.3 1.75)
			(layers "F.Cu" "F.Mask" "F.Paste")
			(net 65 "+12V")
			(pinfunction "VCC_12V")
			(pintype "passive")
			(teardrops
				(best_length_ratio 0.2)
				(max_length 1)
				(best_width_ratio 0.9)
				(max_width 2)
				(curved_edges yes)
				(filter_ratio 0.9)
				(enabled yes)
				(allow_two_segments yes)
				(prefer_zone_connections yes)
			)
		)
		(pad "A106" smd rect
			(at 25.25 8.875)
			(size 0.3 1.75)
			(layers "F.Cu" "F.Mask" "F.Paste")
			(net 65 "+12V")
			(pinfunction "VCC_12V")
			(pintype "passive")
			(teardrops
				(best_length_ratio 0.2)
				(max_length 1)
				(best_width_ratio 0.9)
				(max_width 2)
				(curved_edges yes)
				(filter_ratio 0.9)
				(enabled yes)
				(allow_two_segments yes)
				(prefer_zone_connections yes)
			)
		)
		(pad "A107" smd rect
			(at 25.75 8.875)
			(size 0.3 1.75)
			(layers "F.Cu" "F.Mask" "F.Paste")
			(net 65 "+12V")
			(pinfunction "VCC_12V")
			(pintype "passive")
			(teardrops
				(best_length_ratio 0.2)
				(max_length 1)
				(best_width_ratio 0.9)
				(max_width 2)
				(curved_edges yes)
				(filter_ratio 0.9)
				(enabled yes)
				(allow_two_segments yes)
				(prefer_zone_connections yes)
			)
		)
		(pad "A108" smd rect
			(at 26.25 8.875)
			(size 0.3 1.75)
			(layers "F.Cu" "F.Mask" "F.Paste")
			(net 65 "+12V")
			(pinfunction "VCC_12V")
			(pintype "passive")
			(teardrops
				(best_length_ratio 0.2)
				(max_length 1)
				(best_width_ratio 0.9)
				(max_width 2)
				(curved_edges yes)
				(filter_ratio 0.9)
				(enabled yes)
				(allow_two_segments yes)
				(prefer_zone_connections yes)
			)
		)
		(pad "A109" smd rect
			(at 26.75 8.875)
			(size 0.3 1.75)
			(layers "F.Cu" "F.Mask" "F.Paste")
			(net 65 "+12V")
			(pinfunction "VCC_12V")
			(pintype "passive")
			(teardrops
				(best_length_ratio 0.2)
				(max_length 1)
				(best_width_ratio 0.9)
				(max_width 2)
				(curved_edges yes)
				(filter_ratio 0.9)
				(enabled yes)
				(allow_two_segments yes)
				(prefer_zone_connections yes)
			)
		)
		(pad "A110" smd rect
			(at 27.25 8.875)
			(size 0.3 1.75)
			(layers "F.Cu" "F.Mask" "F.Paste")
			(net 1 "GND")
			(pinfunction "GND(FIXED)")
			(pintype "passive")
			(teardrops
				(best_length_ratio 0.2)
				(max_length 1)
				(best_width_ratio 0.9)
				(max_width 2)
				(curved_edges yes)
				(filter_ratio 0.9)
				(enabled yes)
				(allow_two_segments yes)
				(prefer_zone_connections yes)
			)
		)
		(pad "B1" smd rect
			(at -27.25 3.325)
			(size 0.3 1.75)
			(layers "F.Cu" "F.Mask" "F.Paste")
			(net 1 "GND")
			(pinfunction "GND(FIXED)")
			(pintype "passive")
			(teardrops
				(best_length_ratio 0.2)
				(max_length 1)
				(best_width_ratio 0.9)
				(max_width 2)
				(curved_edges yes)
				(filter_ratio 0.9)
				(enabled yes)
				(allow_two_segments yes)
				(prefer_zone_connections yes)
			)
		)
		(pad "B2" smd rect
			(at -26.75 3.325)
			(size 0.3 1.75)
			(layers "F.Cu" "F.Mask" "F.Paste")
			(net 347 "/2xUSB3.0+RJ45/~{GBE0_ACT}")
			(pinfunction "~{GBE0_ACT}")
			(pintype "output")
			(teardrops
				(best_length_ratio 0.2)
				(max_length 1)
				(best_width_ratio 0.9)
				(max_width 2)
				(curved_edges yes)
				(filter_ratio 0.9)
				(enabled yes)
				(allow_two_segments yes)
				(prefer_zone_connections yes)
			)
		)
		(pad "B3" smd rect
			(at -26.25 3.325)
			(size 0.3 1.75)
			(layers "F.Cu" "F.Mask" "F.Paste")
			(net 348 "Net-(J12D-~{LPC_FRAME}{slash}~{ESPI_CS0})")
			(pinfunction "~{LPC_FRAME}/~{ESPI_CS0}")
			(pintype "bidirectional")
			(teardrops
				(best_length_ratio 0.2)
				(max_length 1)
				(best_width_ratio 0.9)
				(max_width 2)
				(curved_edges yes)
				(filter_ratio 0.9)
				(enabled yes)
				(allow_two_segments yes)
				(prefer_zone_connections yes)
			)
		)
		(pad "B4" smd rect
			(at -25.75 3.325)
			(size 0.3 1.75)
			(layers "F.Cu" "F.Mask" "F.Paste")
			(net 349 "Net-(J12D-LPC_AD0{slash}ESPI_IO_0)")
			(pinfunction "LPC_AD0/ESPI_IO_0")
			(pintype "bidirectional")
			(teardrops
				(best_length_ratio 0.2)
				(max_length 1)
				(best_width_ratio 0.9)
				(max_width 2)
				(curved_edges yes)
				(filter_ratio 0.9)
				(enabled yes)
				(allow_two_segments yes)
				(prefer_zone_connections yes)
			)
		)
		(pad "B5" smd rect
			(at -25.25 3.325)
			(size 0.3 1.75)
			(layers "F.Cu" "F.Mask" "F.Paste")
			(net 350 "Net-(J12D-LPC_AD1{slash}ESPI_IO_1)")
			(pinfunction "LPC_AD1/ESPI_IO_1")
			(pintype "bidirectional")
			(teardrops
				(best_length_ratio 0.2)
				(max_length 1)
				(best_width_ratio 0.9)
				(max_width 2)
				(curved_edges yes)
				(filter_ratio 0.9)
				(enabled yes)
				(allow_two_segments yes)
				(prefer_zone_connections yes)
			)
		)
		(pad "B6" smd rect
			(at -24.75 3.325)
			(size 0.3 1.75)
			(layers "F.Cu" "F.Mask" "F.Paste")
			(net 351 "Net-(J12D-LPC_AD2{slash}ESPI_IO_2)")
			(pinfunction "LPC_AD2/ESPI_IO_2")
			(pintype "bidirectional")
			(teardrops
				(best_length_ratio 0.2)
				(max_length 1)
				(best_width_ratio 0.9)
				(max_width 2)
				(curved_edges yes)
				(filter_ratio 0.9)
				(enabled yes)
				(allow_two_segments yes)
				(prefer_zone_connections yes)
			)
		)
		(pad "B7" smd rect
			(at -24.25 3.325)
			(size 0.3 1.75)
			(layers "F.Cu" "F.Mask" "F.Paste")
			(net 352 "Net-(J12D-LPC_AD3{slash}ESPI_IO_3)")
			(pinfunction "LPC_AD3/ESPI_IO_3")
			(pintype "bidirectional")
			(teardrops
				(best_length_ratio 0.2)
				(max_length 1)
				(best_width_ratio 0.9)
				(max_width 2)
				(curved_edges yes)
				(filter_ratio 0.9)
				(enabled yes)
				(allow_two_segments yes)
				(prefer_zone_connections yes)
			)
		)
		(pad "B8" smd rect
			(at -23.75 3.325)
			(size 0.3 1.75)
			(layers "F.Cu" "F.Mask" "F.Paste")
			(net 353 "Net-(J12D-~{LPC_DRQ0}{slash}~{ESPI_ALERT0})")
			(pinfunction "~{LPC_DRQ0}/~{ESPI_ALERT0}")
			(pintype "input")
			(teardrops
				(best_length_ratio 0.2)
				(max_length 1)
				(best_width_ratio 0.9)
				(max_width 2)
				(curved_edges yes)
				(filter_ratio 0.9)
				(enabled yes)
				(allow_two_segments yes)
				(prefer_zone_connections yes)
			)
		)
		(pad "B9" smd rect
			(at -23.25 3.325)
			(size 0.3 1.75)
			(layers "F.Cu" "F.Mask" "F.Paste")
			(net 354 "Net-(J12D-~{LPC_DRQ1}{slash}~{ESPI_ALERT1})")
			(pinfunction "~{LPC_DRQ1}/~{ESPI_ALERT1}")
			(pintype "input")
			(teardrops
				(best_length_ratio 0.2)
				(max_length 1)
				(best_width_ratio 0.9)
				(max_width 2)
				(curved_edges yes)
				(filter_ratio 0.9)
				(enabled yes)
				(allow_two_segments yes)
				(prefer_zone_connections yes)
			)
		)
		(pad "B10" smd rect
			(at -22.75 3.325)
			(size 0.3 1.75)
			(layers "F.Cu" "F.Mask" "F.Paste")
			(net 355 "Net-(J12D-LPC_CLK{slash}ESPI_CK)")
			(pinfunction "LPC_CLK/ESPI_CK")
			(pintype "output")
			(teardrops
				(best_length_ratio 0.2)
				(max_length 1)
				(best_width_ratio 0.9)
				(max_width 2)
				(curved_edges yes)
				(filter_ratio 0.9)
				(enabled yes)
				(allow_two_segments yes)
				(prefer_zone_connections yes)
			)
		)
		(pad "B11" smd rect
			(at -22.25 3.325)
			(size 0.3 1.75)
			(layers "F.Cu" "F.Mask" "F.Paste")
			(net 1 "GND")
			(pinfunction "GND(FIXED)")
			(pintype "passive")
			(teardrops
				(best_length_ratio 0.2)
				(max_length 1)
				(best_width_ratio 0.9)
				(max_width 2)
				(curved_edges yes)
				(filter_ratio 0.9)
				(enabled yes)
				(allow_two_segments yes)
				(prefer_zone_connections yes)
			)
		)
		(pad "B12" smd rect
			(at -21.75 3.325)
			(size 0.3 1.75)
			(layers "F.Cu" "F.Mask" "F.Paste")
			(net 356 "/Com Express 7 MGMT/~{CW_PWRBTN}")
			(pinfunction "~{PWRBTN}")
			(pintype "input")
			(teardrops
				(best_length_ratio 0.2)
				(max_length 1)
				(best_width_ratio 0.9)
				(max_width 2)
				(curved_edges yes)
				(filter_ratio 0.9)
				(enabled yes)
				(allow_two_segments yes)
				(prefer_zone_connections yes)
			)
		)
		(pad "B13" smd rect
			(at -21.25 3.325)
			(size 0.3 1.75)
			(layers "F.Cu" "F.Mask" "F.Paste")
			(net 357 "/Com Express 7 MGMT/SMBus.SCL")
			(pinfunction "SMB_CK")
			(pintype "open_collector")
			(teardrops
				(best_length_ratio 0.2)
				(max_length 1)
				(best_width_ratio 0.9)
				(max_width 2)
				(curved_edges yes)
				(filter_ratio 0.9)
				(enabled yes)
				(allow_two_segments yes)
				(prefer_zone_connections yes)
			)
		)
		(pad "B14" smd rect
			(at -20.75 3.325)
			(size 0.3 1.75)
			(layers "F.Cu" "F.Mask" "F.Paste")
			(net 358 "/Com Express 7 MGMT/SMBus.SDA")
			(pinfunction "SMB_DAT")
			(pintype "open_collector")
			(teardrops
				(best_length_ratio 0.2)
				(max_length 1)
				(best_width_ratio 0.9)
				(max_width 2)
				(curved_edges yes)
				(filter_ratio 0.9)
				(enabled yes)
				(allow_two_segments yes)
				(prefer_zone_connections yes)
			)
		)
		(pad "B15" smd rect
			(at -20.25 3.325)
			(size 0.3 1.75)
			(layers "F.Cu" "F.Mask" "F.Paste")
			(net 359 "/Com Express 7 MGMT/SMBus.~{INT}")
			(pinfunction "~{SMB_ALERT}")
			(pintype "input")
			(teardrops
				(best_length_ratio 0.2)
				(max_length 1)
				(best_width_ratio 0.9)
				(max_width 2)
				(curved_edges yes)
				(filter_ratio 0.9)
				(enabled yes)
				(allow_two_segments yes)
				(prefer_zone_connections yes)
			)
		)
		(pad "B16" smd rect
			(at -19.75 3.325)
			(size 0.3 1.75)
			(layers "F.Cu" "F.Mask" "F.Paste")
			(net 360 "unconnected-(J12F-SATA1_TX+-PadB16)")
			(pinfunction "SATA1_TX+")
			(pintype "output+no_connect")
			(teardrops
				(best_length_ratio 0.2)
				(max_length 1)
				(best_width_ratio 0.9)
				(max_width 2)
				(curved_edges yes)
				(filter_ratio 0.9)
				(enabled yes)
				(allow_two_segments yes)
				(prefer_zone_connections yes)
			)
		)
		(pad "B17" smd rect
			(at -19.25 3.325)
			(size 0.3 1.75)
			(layers "F.Cu" "F.Mask" "F.Paste")
			(net 361 "unconnected-(J12F-SATA1_TX--PadB17)")
			(pinfunction "SATA1_TX-")
			(pintype "output+no_connect")
			(teardrops
				(best_length_ratio 0.2)
				(max_length 1)
				(best_width_ratio 0.9)
				(max_width 2)
				(curved_edges yes)
				(filter_ratio 0.9)
				(enabled yes)
				(allow_two_segments yes)
				(prefer_zone_connections yes)
			)
		)
		(pad "B18" smd rect
			(at -18.75 3.325)
			(size 0.3 1.75)
			(layers "F.Cu" "F.Mask" "F.Paste")
			(net 362 "Net-(J12D-~{SUS_STAT}{slash}~{ESPI_RESET})")
			(pinfunction "~{SUS_STAT}/~{ESPI_RESET}")
			(pintype "output")
			(teardrops
				(best_length_ratio 0.2)
				(max_length 1)
				(best_width_ratio 0.9)
				(max_width 2)
				(curved_edges yes)
				(filter_ratio 0.9)
				(enabled yes)
				(allow_two_segments yes)
				(prefer_zone_connections yes)
			)
		)
		(pad "B19" smd rect
			(at -18.25 3.325)
			(size 0.3 1.75)
			(layers "F.Cu" "F.Mask" "F.Paste")
			(net 363 "unconnected-(J12F-SATA1_RX+-PadB19)")
			(pinfunction "SATA1_RX+")
			(pintype "input+no_connect")
			(teardrops
				(best_length_ratio 0.2)
				(max_length 1)
				(best_width_ratio 0.9)
				(max_width 2)
				(curved_edges yes)
				(filter_ratio 0.9)
				(enabled yes)
				(allow_two_segments yes)
				(prefer_zone_connections yes)
			)
		)
		(pad "B20" smd rect
			(at -17.75 3.325)
			(size 0.3 1.75)
			(layers "F.Cu" "F.Mask" "F.Paste")
			(net 364 "unconnected-(J12F-SATA1_RX--PadB20)")
			(pinfunction "SATA1_RX-")
			(pintype "input+no_connect")
			(teardrops
				(best_length_ratio 0.2)
				(max_length 1)
				(best_width_ratio 0.9)
				(max_width 2)
				(curved_edges yes)
				(filter_ratio 0.9)
				(enabled yes)
				(allow_two_segments yes)
				(prefer_zone_connections yes)
			)
		)
		(pad "B21" smd rect
			(at -17.25 3.325)
			(size 0.3 1.75)
			(layers "F.Cu" "F.Mask" "F.Paste")
			(net 1 "GND")
			(pinfunction "GND(FIXED)")
			(pintype "passive")
			(teardrops
				(best_length_ratio 0.2)
				(max_length 1)
				(best_width_ratio 0.9)
				(max_width 2)
				(curved_edges yes)
				(filter_ratio 0.9)
				(enabled yes)
				(allow_two_segments yes)
				(prefer_zone_connections yes)
			)
		)
		(pad "B22" smd rect
			(at -16.75 3.325)
			(size 0.3 1.75)
			(layers "F.Cu" "F.Mask" "F.Paste")
			(net 239 "/Com Express 7 Interfaces/PCIe_{B2Bx4}.RX3+")
			(pinfunction "PCIE_RX15+")
			(pintype "input")
			(teardrops
				(best_length_ratio 0.2)
				(max_length 1)
				(best_width_ratio 0.9)
				(max_width 2)
				(curved_edges yes)
				(filter_ratio 0.9)
				(enabled yes)
				(allow_two_segments yes)
				(prefer_zone_connections yes)
			)
		)
		(pad "B23" smd rect
			(at -16.25 3.325)
			(size 0.3 1.75)
			(layers "F.Cu" "F.Mask" "F.Paste")
			(net 237 "/Com Express 7 Interfaces/PCIe_{B2Bx4}.RX3-")
			(pinfunction "PCIE_RX15-")
			(pintype "input")
			(teardrops
				(best_length_ratio 0.2)
				(max_length 1)
				(best_width_ratio 0.9)
				(max_width 2)
				(curved_edges yes)
				(filter_ratio 0.9)
				(enabled yes)
				(allow_two_segments yes)
				(prefer_zone_connections yes)
			)
		)
		(pad "B24" smd rect
			(at -15.75 3.325)
			(size 0.3 1.75)
			(layers "F.Cu" "F.Mask" "F.Paste")
			(net 365 "/Com Express 7 MGMT/PWR_OK")
			(pinfunction "PWR_OK")
			(pintype "input")
			(teardrops
				(best_length_ratio 0.2)
				(max_length 1)
				(best_width_ratio 0.9)
				(max_width 2)
				(curved_edges yes)
				(filter_ratio 0.9)
				(enabled yes)
				(allow_two_segments yes)
				(prefer_zone_connections yes)
			)
		)
		(pad "B25" smd rect
			(at -15.25 3.325)
			(size 0.3 1.75)
			(layers "F.Cu" "F.Mask" "F.Paste")
			(net 244 "/Com Express 7 Interfaces/PCIe_{B2Bx4}.RX2+")
			(pinfunction "PCIE_RX14+")
			(pintype "input")
			(teardrops
				(best_length_ratio 0.2)
				(max_length 1)
				(best_width_ratio 0.9)
				(max_width 2)
				(curved_edges yes)
				(filter_ratio 0.9)
				(enabled yes)
				(allow_two_segments yes)
				(prefer_zone_connections yes)
			)
		)
		(pad "B26" smd rect
			(at -14.75 3.325)
			(size 0.3 1.75)
			(layers "F.Cu" "F.Mask" "F.Paste")
			(net 243 "/Com Express 7 Interfaces/PCIe_{B2Bx4}.RX2-")
			(pinfunction "PCIE_RX14-")
			(pintype "input")
			(teardrops
				(best_length_ratio 0.2)
				(max_length 1)
				(best_width_ratio 0.9)
				(max_width 2)
				(curved_edges yes)
				(filter_ratio 0.9)
				(enabled yes)
				(allow_two_segments yes)
				(prefer_zone_connections yes)
			)
		)
		(pad "B27" smd rect
			(at -14.25 3.325)
			(size 0.3 1.75)
			(layers "F.Cu" "F.Mask" "F.Paste")
			(net 366 "Net-(J12D-WDT)")
			(pinfunction "WDT")
			(pintype "output")
			(teardrops
				(best_length_ratio 0.2)
				(max_length 1)
				(best_width_ratio 0.9)
				(max_width 2)
				(curved_edges yes)
				(filter_ratio 0.9)
				(enabled yes)
				(allow_two_segments yes)
				(prefer_zone_connections yes)
			)
		)
		(pad "B28" smd rect
			(at -13.75 3.325)
			(size 0.3 1.75)
			(layers "F.Cu" "F.Mask" "F.Paste")
			(net 367 "unconnected-(J12H-RSVD-PadB28)")
			(pinfunction "RSVD")
			(pintype "no_connect")
			(teardrops
				(best_length_ratio 0.2)
				(max_length 1)
				(best_width_ratio 0.9)
				(max_width 2)
				(curved_edges yes)
				(filter_ratio 0.9)
				(enabled yes)
				(allow_two_segments yes)
				(prefer_zone_connections yes)
			)
		)
		(pad "B29" smd rect
			(at -13.25 3.325)
			(size 0.3 1.75)
			(layers "F.Cu" "F.Mask" "F.Paste")
			(net 368 "unconnected-(J12H-RSVD-PadB29)")
			(pinfunction "RSVD")
			(pintype "no_connect")
			(teardrops
				(best_length_ratio 0.2)
				(max_length 1)
				(best_width_ratio 0.9)
				(max_width 2)
				(curved_edges yes)
				(filter_ratio 0.9)
				(enabled yes)
				(allow_two_segments yes)
				(prefer_zone_connections yes)
			)
		)
		(pad "B30" smd rect
			(at -12.75 3.325)
			(size 0.3 1.75)
			(layers "F.Cu" "F.Mask" "F.Paste")
			(net 369 "unconnected-(J12H-RSVD-PadB30)")
			(pinfunction "RSVD")
			(pintype "no_connect")
			(teardrops
				(best_length_ratio 0.2)
				(max_length 1)
				(best_width_ratio 0.9)
				(max_width 2)
				(curved_edges yes)
				(filter_ratio 0.9)
				(enabled yes)
				(allow_two_segments yes)
				(prefer_zone_connections yes)
			)
		)
		(pad "B31" smd rect
			(at -12.25 3.325)
			(size 0.3 1.75)
			(layers "F.Cu" "F.Mask" "F.Paste")
			(net 1 "GND")
			(pinfunction "GND(FIXED)")
			(pintype "passive")
			(teardrops
				(best_length_ratio 0.2)
				(max_length 1)
				(best_width_ratio 0.9)
				(max_width 2)
				(curved_edges yes)
				(filter_ratio 0.9)
				(enabled yes)
				(allow_two_segments yes)
				(prefer_zone_connections yes)
			)
		)
		(pad "B32" smd rect
			(at -11.75 3.325)
			(size 0.3 1.75)
			(layers "F.Cu" "F.Mask" "F.Paste")
			(net 370 "Net-(J12D-SPKR)")
			(pinfunction "SPKR")
			(pintype "output")
			(teardrops
				(best_length_ratio 0.2)
				(max_length 1)
				(best_width_ratio 0.9)
				(max_width 2)
				(curved_edges yes)
				(filter_ratio 0.9)
				(enabled yes)
				(allow_two_segments yes)
				(prefer_zone_connections yes)
			)
		)
		(pad "B33" smd rect
			(at -11.25 3.325)
			(size 0.3 1.75)
			(layers "F.Cu" "F.Mask" "F.Paste")
			(net 371 "/Com Express 7 MGMT/I2C.SCL")
			(pinfunction "I2C_CK")
			(pintype "open_collector")
			(teardrops
				(best_length_ratio 0.2)
				(max_length 1)
				(best_width_ratio 0.9)
				(max_width 2)
				(curved_edges yes)
				(filter_ratio 0.9)
				(enabled yes)
				(allow_two_segments yes)
				(prefer_zone_connections yes)
			)
		)
		(pad "B34" smd rect
			(at -10.75 3.325)
			(size 0.3 1.75)
			(layers "F.Cu" "F.Mask" "F.Paste")
			(net 372 "/Com Express 7 MGMT/I2C.SDA")
			(pinfunction "I2C_DAT")
			(pintype "open_collector")
			(teardrops
				(best_length_ratio 0.2)
				(max_length 1)
				(best_width_ratio 0.9)
				(max_width 2)
				(curved_edges yes)
				(filter_ratio 0.9)
				(enabled yes)
				(allow_two_segments yes)
				(prefer_zone_connections yes)
			)
		)
		(pad "B35" smd rect
			(at -10.25 3.325)
			(size 0.3 1.75)
			(layers "F.Cu" "F.Mask" "F.Paste")
			(net 373 "Net-(J12D-~{THRM})")
			(pinfunction "~{THRM}")
			(pintype "input")
			(teardrops
				(best_length_ratio 0.2)
				(max_length 1)
				(best_width_ratio 0.9)
				(max_width 2)
				(curved_edges yes)
				(filter_ratio 0.9)
				(enabled yes)
				(allow_two_segments yes)
				(prefer_zone_connections yes)
			)
		)
		(pad "B36" smd rect
			(at -9.75 3.325)
			(size 0.3 1.75)
			(layers "F.Cu" "F.Mask" "F.Paste")
			(net 254 "/Com Express 7 Interfaces/PCIe_{B2Bx4}.RX1+")
			(pinfunction "PCIE_RX13+")
			(pintype "input")
			(teardrops
				(best_length_ratio 0.2)
				(max_length 1)
				(best_width_ratio 0.9)
				(max_width 2)
				(curved_edges yes)
				(filter_ratio 0.9)
				(enabled yes)
				(allow_two_segments yes)
				(prefer_zone_connections yes)
			)
		)
		(pad "B37" smd rect
			(at -9.25 3.325)
			(size 0.3 1.75)
			(layers "F.Cu" "F.Mask" "F.Paste")
			(net 252 "/Com Express 7 Interfaces/PCIe_{B2Bx4}.RX1-")
			(pinfunction "PCIE_RX13-")
			(pintype "input")
			(teardrops
				(best_length_ratio 0.2)
				(max_length 1)
				(best_width_ratio 0.9)
				(max_width 2)
				(curved_edges yes)
				(filter_ratio 0.9)
				(enabled yes)
				(allow_two_segments yes)
				(prefer_zone_connections yes)
			)
		)
		(pad "B38" smd rect
			(at -8.75 3.325)
			(size 0.3 1.75)
			(layers "F.Cu" "F.Mask" "F.Paste")
			(net 1 "GND")
			(pinfunction "GND")
			(pintype "passive")
			(teardrops
				(best_length_ratio 0.2)
				(max_length 1)
				(best_width_ratio 0.9)
				(max_width 2)
				(curved_edges yes)
				(filter_ratio 0.9)
				(enabled yes)
				(allow_two_segments yes)
				(prefer_zone_connections yes)
			)
		)
		(pad "B39" smd rect
			(at -8.25 3.325)
			(size 0.3 1.75)
			(layers "F.Cu" "F.Mask" "F.Paste")
			(net 264 "/Com Express 7 Interfaces/PCIe_{B2Bx4}.RX0+")
			(pinfunction "PCIE_RX12+")
			(pintype "input")
			(teardrops
				(best_length_ratio 0.2)
				(max_length 1)
				(best_width_ratio 0.9)
				(max_width 2)
				(curved_edges yes)
				(filter_ratio 0.9)
				(enabled yes)
				(allow_two_segments yes)
				(prefer_zone_connections yes)
			)
		)
		(pad "B40" smd rect
			(at -7.75 3.325)
			(size 0.3 1.75)
			(layers "F.Cu" "F.Mask" "F.Paste")
			(net 262 "/Com Express 7 Interfaces/PCIe_{B2Bx4}.RX0-")
			(pinfunction "PCIE_RX12-")
			(pintype "input")
			(teardrops
				(best_length_ratio 0.2)
				(max_length 1)
				(best_width_ratio 0.9)
				(max_width 2)
				(curved_edges yes)
				(filter_ratio 0.9)
				(enabled yes)
				(allow_two_segments yes)
				(prefer_zone_connections yes)
			)
		)
		(pad "B41" smd rect
			(at -7.25 3.325)
			(size 0.3 1.75)
			(layers "F.Cu" "F.Mask" "F.Paste")
			(net 1 "GND")
			(pinfunction "GND(FIXED)")
			(pintype "passive")
			(teardrops
				(best_length_ratio 0.2)
				(max_length 1)
				(best_width_ratio 0.9)
				(max_width 2)
				(curved_edges yes)
				(filter_ratio 0.9)
				(enabled yes)
				(allow_two_segments yes)
				(prefer_zone_connections yes)
			)
		)
		(pad "B42" smd rect
			(at -6.75 3.325)
			(size 0.3 1.75)
			(layers "F.Cu" "F.Mask" "F.Paste")
			(net 374 "/2xUSB3.0+RJ45/USB_2.D-")
			(pinfunction "USB3-")
			(pintype "bidirectional")
			(teardrops
				(best_length_ratio 0.2)
				(max_length 1)
				(best_width_ratio 0.9)
				(max_width 2)
				(curved_edges yes)
				(filter_ratio 0.9)
				(enabled yes)
				(allow_two_segments yes)
				(prefer_zone_connections yes)
			)
		)
		(pad "B43" smd rect
			(at -6.25 3.325)
			(size 0.3 1.75)
			(layers "F.Cu" "F.Mask" "F.Paste")
			(net 375 "/2xUSB3.0+RJ45/USB_2.D+")
			(pinfunction "USB3+")
			(pintype "bidirectional")
			(teardrops
				(best_length_ratio 0.2)
				(max_length 1)
				(best_width_ratio 0.9)
				(max_width 2)
				(curved_edges yes)
				(filter_ratio 0.9)
				(enabled yes)
				(allow_two_segments yes)
				(prefer_zone_connections yes)
			)
		)
		(pad "B44" smd rect
			(at -5.75 3.325)
			(size 0.3 1.75)
			(layers "F.Cu" "F.Mask" "F.Paste")
			(net 376 "unconnected-(J12G-~{USB_0_1_OC}-PadB44)")
			(pinfunction "~{USB_0_1_OC}")
			(pintype "input+no_connect")
			(teardrops
				(best_length_ratio 0.2)
				(max_length 1)
				(best_width_ratio 0.9)
				(max_width 2)
				(curved_edges yes)
				(filter_ratio 0.9)
				(enabled yes)
				(allow_two_segments yes)
				(prefer_zone_connections yes)
			)
		)
		(pad "B45" smd rect
			(at -5.25 3.325)
			(size 0.3 1.75)
			(layers "F.Cu" "F.Mask" "F.Paste")
			(net 377 "/Com Express 7 Interfaces/USB1.D-")
			(pinfunction "USB1-")
			(pintype "bidirectional")
			(teardrops
				(best_length_ratio 0.2)
				(max_length 1)
				(best_width_ratio 0.9)
				(max_width 2)
				(curved_edges yes)
				(filter_ratio 0.9)
				(enabled yes)
				(allow_two_segments yes)
				(prefer_zone_connections yes)
			)
		)
		(pad "B46" smd rect
			(at -4.75 3.325)
			(size 0.3 1.75)
			(layers "F.Cu" "F.Mask" "F.Paste")
			(net 378 "/Com Express 7 Interfaces/USB1.D+")
			(pinfunction "USB1+")
			(pintype "bidirectional")
			(teardrops
				(best_length_ratio 0.2)
				(max_length 1)
				(best_width_ratio 0.9)
				(max_width 2)
				(curved_edges yes)
				(filter_ratio 0.9)
				(enabled yes)
				(allow_two_segments yes)
				(prefer_zone_connections yes)
			)
		)
		(pad "B47" smd rect
			(at -4.25 3.325)
			(size 0.3 1.75)
			(layers "F.Cu" "F.Mask" "F.Paste")
			(net 379 "Net-(J12D-~{ESPI_EN})")
			(pinfunction "~{ESPI_EN}")
			(pintype "input")
			(teardrops
				(best_length_ratio 0.2)
				(max_length 1)
				(best_width_ratio 0.9)
				(max_width 2)
				(curved_edges yes)
				(filter_ratio 0.9)
				(enabled yes)
				(allow_two_segments yes)
				(prefer_zone_connections yes)
			)
		)
		(pad "B48" smd rect
			(at -3.75 3.325)
			(size 0.3 1.75)
			(layers "F.Cu" "F.Mask" "F.Paste")
			(net 380 "Net-(J12G-USB0_HOST_PRSNT)")
			(pinfunction "USB0_HOST_PRSNT")
			(pintype "input")
			(teardrops
				(best_length_ratio 0.2)
				(max_length 1)
				(best_width_ratio 0.9)
				(max_width 2)
				(curved_edges yes)
				(filter_ratio 0.9)
				(enabled yes)
				(allow_two_segments yes)
				(prefer_zone_connections yes)
			)
		)
		(pad "B49" smd rect
			(at -3.25 3.325)
			(size 0.3 1.75)
			(layers "F.Cu" "F.Mask" "F.Paste")
			(net 381 "Net-(J12D-~{SYS_RESET})")
			(pinfunction "~{SYS_RESET}")
			(pintype "input")
			(teardrops
				(best_length_ratio 0.2)
				(max_length 1)
				(best_width_ratio 0.9)
				(max_width 2)
				(curved_edges yes)
				(filter_ratio 0.9)
				(enabled yes)
				(allow_two_segments yes)
				(prefer_zone_connections yes)
			)
		)
		(pad "B50" smd rect
			(at -2.75 3.325)
			(size 0.3 1.75)
			(layers "F.Cu" "F.Mask" "F.Paste")
			(net 382 "Net-(J12D-~{CB_RESET})")
			(pinfunction "~{CB_RESET}")
			(pintype "output")
			(teardrops
				(best_length_ratio 0.2)
				(max_length 1)
				(best_width_ratio 0.9)
				(max_width 2)
				(curved_edges yes)
				(filter_ratio 0.9)
				(enabled yes)
				(allow_two_segments yes)
				(prefer_zone_connections yes)
			)
		)
		(pad "B51" smd rect
			(at -2.25 3.325)
			(size 0.3 1.75)
			(layers "F.Cu" "F.Mask" "F.Paste")
			(net 1 "GND")
			(pinfunction "GND(FIXED)")
			(pintype "passive")
			(teardrops
				(best_length_ratio 0.2)
				(max_length 1)
				(best_width_ratio 0.9)
				(max_width 2)
				(curved_edges yes)
				(filter_ratio 0.9)
				(enabled yes)
				(allow_two_segments yes)
				(prefer_zone_connections yes)
			)
		)
		(pad "B52" smd rect
			(at -1.75 3.325)
			(size 0.3 1.75)
			(layers "F.Cu" "F.Mask" "F.Paste")
			(net 383 "/Com Express 7 Interfaces/PCIe_{B1x2}.RX1+")
			(pinfunction "PCIE_RX5+")
			(pintype "input+no_connect")
			(teardrops
				(best_length_ratio 0.2)
				(max_length 1)
				(best_width_ratio 0.9)
				(max_width 2)
				(curved_edges yes)
				(filter_ratio 0.9)
				(enabled yes)
				(allow_two_segments yes)
				(prefer_zone_connections yes)
			)
		)
		(pad "B53" smd rect
			(at -1.25 3.325)
			(size 0.3 1.75)
			(layers "F.Cu" "F.Mask" "F.Paste")
			(net 384 "/Com Express 7 Interfaces/PCIe_{B1x2}.RX1-")
			(pinfunction "PCIE_RX5-")
			(pintype "input+no_connect")
			(teardrops
				(best_length_ratio 0.2)
				(max_length 1)
				(best_width_ratio 0.9)
				(max_width 2)
				(curved_edges yes)
				(filter_ratio 0.9)
				(enabled yes)
				(allow_two_segments yes)
				(prefer_zone_connections yes)
			)
		)
		(pad "B54" smd rect
			(at -0.75 3.325)
			(size 0.3 1.75)
			(layers "F.Cu" "F.Mask" "F.Paste")
			(net 385 "/Com Express 7 Interfaces/SDIO.CMD")
			(pinfunction "GPO1")
			(pintype "output")
			(teardrops
				(best_length_ratio 0.2)
				(max_length 1)
				(best_width_ratio 0.9)
				(max_width 2)
				(curved_edges yes)
				(filter_ratio 0.9)
				(enabled yes)
				(allow_two_segments yes)
				(prefer_zone_connections yes)
			)
		)
		(pad "B55" smd rect
			(at -0.25 3.325)
			(size 0.3 1.75)
			(layers "F.Cu" "F.Mask" "F.Paste")
			(net 14 "/Com Express 7 Interfaces/PCIe_{B1x2}.RX0+")
			(pinfunction "PCIE_RX4+")
			(pintype "input")
			(teardrops
				(best_length_ratio 0.2)
				(max_length 1)
				(best_width_ratio 0.9)
				(max_width 2)
				(curved_edges yes)
				(filter_ratio 0.9)
				(enabled yes)
				(allow_two_segments yes)
				(prefer_zone_connections yes)
			)
		)
		(pad "B56" smd rect
			(at 0.25 3.325)
			(size 0.3 1.75)
			(layers "F.Cu" "F.Mask" "F.Paste")
			(net 16 "/Com Express 7 Interfaces/PCIe_{B1x2}.RX0-")
			(pinfunction "PCIE_RX4-")
			(pintype "input")
			(teardrops
				(best_length_ratio 0.2)
				(max_length 1)
				(best_width_ratio 0.9)
				(max_width 2)
				(curved_edges yes)
				(filter_ratio 0.9)
				(enabled yes)
				(allow_two_segments yes)
				(prefer_zone_connections yes)
			)
		)
		(pad "B57" smd rect
			(at 0.75 3.325)
			(size 0.3 1.75)
			(layers "F.Cu" "F.Mask" "F.Paste")
			(net 386 "/Com Express 7 Interfaces/SD_WP")
			(pinfunction "GPO2")
			(pintype "output")
			(teardrops
				(best_length_ratio 0.2)
				(max_length 1)
				(best_width_ratio 0.9)
				(max_width 2)
				(curved_edges yes)
				(filter_ratio 0.9)
				(enabled yes)
				(allow_two_segments yes)
				(prefer_zone_connections yes)
			)
		)
		(pad "B58" smd rect
			(at 1.25 3.325)
			(size 0.3 1.75)
			(layers "F.Cu" "F.Mask" "F.Paste")
			(net 210 "/Com Express 7 Interfaces/PCIe_{B1x4}.RX3+")
			(pinfunction "PCIE_RX3+")
			(pintype "input")
			(teardrops
				(best_length_ratio 0.2)
				(max_length 1)
				(best_width_ratio 0.9)
				(max_width 2)
				(curved_edges yes)
				(filter_ratio 0.9)
				(enabled yes)
				(allow_two_segments yes)
				(prefer_zone_connections yes)
			)
		)
		(pad "B59" smd rect
			(at 1.75 3.325)
			(size 0.3 1.75)
			(layers "F.Cu" "F.Mask" "F.Paste")
			(net 209 "/Com Express 7 Interfaces/PCIe_{B1x4}.RX3-")
			(pinfunction "PCIE_RX3-")
			(pintype "input")
			(teardrops
				(best_length_ratio 0.2)
				(max_length 1)
				(best_width_ratio 0.9)
				(max_width 2)
				(curved_edges yes)
				(filter_ratio 0.9)
				(enabled yes)
				(allow_two_segments yes)
				(prefer_zone_connections yes)
			)
		)
		(pad "B60" smd rect
			(at 2.25 3.325)
			(size 0.3 1.75)
			(layers "F.Cu" "F.Mask" "F.Paste")
			(net 1 "GND")
			(pinfunction "GND(FIXED)")
			(pintype "passive")
			(teardrops
				(best_length_ratio 0.2)
				(max_length 1)
				(best_width_ratio 0.9)
				(max_width 2)
				(curved_edges yes)
				(filter_ratio 0.9)
				(enabled yes)
				(allow_two_segments yes)
				(prefer_zone_connections yes)
			)
		)
		(pad "B61" smd rect
			(at 2.75 3.325)
			(size 0.3 1.75)
			(layers "F.Cu" "F.Mask" "F.Paste")
			(net 214 "/Com Express 7 Interfaces/PCIe_{B1x4}.RX2+")
			(pinfunction "PCIE_RX2+")
			(pintype "input")
			(teardrops
				(best_length_ratio 0.2)
				(max_length 1)
				(best_width_ratio 0.9)
				(max_width 2)
				(curved_edges yes)
				(filter_ratio 0.9)
				(enabled yes)
				(allow_two_segments yes)
				(prefer_zone_connections yes)
			)
		)
		(pad "B62" smd rect
			(at 3.25 3.325)
			(size 0.3 1.75)
			(layers "F.Cu" "F.Mask" "F.Paste")
			(net 213 "/Com Express 7 Interfaces/PCIe_{B1x4}.RX2-")
			(pinfunction "PCIE_RX2-")
			(pintype "input")
			(teardrops
				(best_length_ratio 0.2)
				(max_length 1)
				(best_width_ratio 0.9)
				(max_width 2)
				(curved_edges yes)
				(filter_ratio 0.9)
				(enabled yes)
				(allow_two_segments yes)
				(prefer_zone_connections yes)
			)
		)
		(pad "B63" smd rect
			(at 3.75 3.325)
			(size 0.3 1.75)
			(layers "F.Cu" "F.Mask" "F.Paste")
			(net 531 "/Com Express 7 Interfaces/SD_CD")
			(pinfunction "GPO3")
			(pintype "output")
			(teardrops
				(best_length_ratio 0.2)
				(max_length 1)
				(best_width_ratio 0.9)
				(max_width 2)
				(curved_edges yes)
				(filter_ratio 0.9)
				(enabled yes)
				(allow_two_segments yes)
				(prefer_zone_connections yes)
			)
		)
		(pad "B64" smd rect
			(at 4.25 3.325)
			(size 0.3 1.75)
			(layers "F.Cu" "F.Mask" "F.Paste")
			(net 218 "/Com Express 7 Interfaces/PCIe_{B1x4}.RX1+")
			(pinfunction "PCIE_RX1+")
			(pintype "input")
			(teardrops
				(best_length_ratio 0.2)
				(max_length 1)
				(best_width_ratio 0.9)
				(max_width 2)
				(curved_edges yes)
				(filter_ratio 0.9)
				(enabled yes)
				(allow_two_segments yes)
				(prefer_zone_connections yes)
			)
		)
		(pad "B65" smd rect
			(at 4.75 3.325)
			(size 0.3 1.75)
			(layers "F.Cu" "F.Mask" "F.Paste")
			(net 217 "/Com Express 7 Interfaces/PCIe_{B1x4}.RX1-")
			(pinfunction "PCIE_RX1-")
			(pintype "input")
			(teardrops
				(best_length_ratio 0.2)
				(max_length 1)
				(best_width_ratio 0.9)
				(max_width 2)
				(curved_edges yes)
				(filter_ratio 0.9)
				(enabled yes)
				(allow_two_segments yes)
				(prefer_zone_connections yes)
			)
		)
		(pad "B66" smd rect
			(at 5.25 3.325)
			(size 0.3 1.75)
			(layers "F.Cu" "F.Mask" "F.Paste")
			(net 387 "unconnected-(J12D-~{WAKE0}-PadB66)")
			(pinfunction "~{WAKE0}")
			(pintype "input+no_connect")
			(teardrops
				(best_length_ratio 0.2)
				(max_length 1)
				(best_width_ratio 0.9)
				(max_width 2)
				(curved_edges yes)
				(filter_ratio 0.9)
				(enabled yes)
				(allow_two_segments yes)
				(prefer_zone_connections yes)
			)
		)
		(pad "B67" smd rect
			(at 5.75 3.325)
			(size 0.3 1.75)
			(layers "F.Cu" "F.Mask" "F.Paste")
			(net 388 "unconnected-(J12D-~{WAKE1}-PadB67)")
			(pinfunction "~{WAKE1}")
			(pintype "input+no_connect")
			(teardrops
				(best_length_ratio 0.2)
				(max_length 1)
				(best_width_ratio 0.9)
				(max_width 2)
				(curved_edges yes)
				(filter_ratio 0.9)
				(enabled yes)
				(allow_two_segments yes)
				(prefer_zone_connections yes)
			)
		)
		(pad "B68" smd rect
			(at 6.25 3.325)
			(size 0.3 1.75)
			(layers "F.Cu" "F.Mask" "F.Paste")
			(net 222 "/Com Express 7 Interfaces/PCIe_{B1x4}.RX0+")
			(pinfunction "PCIE_RX0+")
			(pintype "input")
			(teardrops
				(best_length_ratio 0.2)
				(max_length 1)
				(best_width_ratio 0.9)
				(max_width 2)
				(curved_edges yes)
				(filter_ratio 0.9)
				(enabled yes)
				(allow_two_segments yes)
				(prefer_zone_connections yes)
			)
		)
		(pad "B69" smd rect
			(at 6.75 3.325)
			(size 0.3 1.75)
			(layers "F.Cu" "F.Mask" "F.Paste")
			(net 221 "/Com Express 7 Interfaces/PCIe_{B1x4}.RX0-")
			(pinfunction "PCIE_RX0-")
			(pintype "input")
			(teardrops
				(best_length_ratio 0.2)
				(max_length 1)
				(best_width_ratio 0.9)
				(max_width 2)
				(curved_edges yes)
				(filter_ratio 0.9)
				(enabled yes)
				(allow_two_segments yes)
				(prefer_zone_connections yes)
			)
		)
		(pad "B70" smd rect
			(at 7.25 3.325)
			(size 0.3 1.75)
			(layers "F.Cu" "F.Mask" "F.Paste")
			(net 1 "GND")
			(pinfunction "GND(FIXED)")
			(pintype "passive")
			(teardrops
				(best_length_ratio 0.2)
				(max_length 1)
				(best_width_ratio 0.9)
				(max_width 2)
				(curved_edges yes)
				(filter_ratio 0.9)
				(enabled yes)
				(allow_two_segments yes)
				(prefer_zone_connections yes)
			)
		)
		(pad "B71" smd rect
			(at 7.75 3.325)
			(size 0.3 1.75)
			(layers "F.Cu" "F.Mask" "F.Paste")
			(net 90 "/Com Express 7 Interfaces/PCIe_{B2Ax4}.RX0+")
			(pinfunction "PCIE_RX8+")
			(pintype "input")
			(teardrops
				(best_length_ratio 0.2)
				(max_length 1)
				(best_width_ratio 0.9)
				(max_width 2)
				(curved_edges yes)
				(filter_ratio 0.9)
				(enabled yes)
				(allow_two_segments yes)
				(prefer_zone_connections yes)
			)
		)
		(pad "B72" smd rect
			(at 8.25 3.325)
			(size 0.3 1.75)
			(layers "F.Cu" "F.Mask" "F.Paste")
			(net 86 "/Com Express 7 Interfaces/PCIe_{B2Ax4}.RX0-")
			(pinfunction "PCIE_RX8-")
			(pintype "input")
			(teardrops
				(best_length_ratio 0.2)
				(max_length 1)
				(best_width_ratio 0.9)
				(max_width 2)
				(curved_edges yes)
				(filter_ratio 0.9)
				(enabled yes)
				(allow_two_segments yes)
				(prefer_zone_connections yes)
			)
		)
		(pad "B73" smd rect
			(at 8.75 3.325)
			(size 0.3 1.75)
			(layers "F.Cu" "F.Mask" "F.Paste")
			(net 1 "GND")
			(pinfunction "GND")
			(pintype "passive")
			(teardrops
				(best_length_ratio 0.2)
				(max_length 1)
				(best_width_ratio 0.9)
				(max_width 2)
				(curved_edges yes)
				(filter_ratio 0.9)
				(enabled yes)
				(allow_two_segments yes)
				(prefer_zone_connections yes)
			)
		)
		(pad "B74" smd rect
			(at 9.25 3.325)
			(size 0.3 1.75)
			(layers "F.Cu" "F.Mask" "F.Paste")
			(net 91 "/Com Express 7 Interfaces/PCIe_{B2Ax4}.RX1+")
			(pinfunction "PCIE_RX9+")
			(pintype "input")
			(teardrops
				(best_length_ratio 0.2)
				(max_length 1)
				(best_width_ratio 0.9)
				(max_width 2)
				(curved_edges yes)
				(filter_ratio 0.9)
				(enabled yes)
				(allow_two_segments yes)
				(prefer_zone_connections yes)
			)
		)
		(pad "B75" smd rect
			(at 9.75 3.325)
			(size 0.3 1.75)
			(layers "F.Cu" "F.Mask" "F.Paste")
			(net 87 "/Com Express 7 Interfaces/PCIe_{B2Ax4}.RX1-")
			(pinfunction "PCIE_RX9-")
			(pintype "input")
			(teardrops
				(best_length_ratio 0.2)
				(max_length 1)
				(best_width_ratio 0.9)
				(max_width 2)
				(curved_edges yes)
				(filter_ratio 0.9)
				(enabled yes)
				(allow_two_segments yes)
				(prefer_zone_connections yes)
			)
		)
		(pad "B76" smd rect
			(at 10.25 3.325)
			(size 0.3 1.75)
			(layers "F.Cu" "F.Mask" "F.Paste")
			(net 1 "GND")
			(pinfunction "GND")
			(pintype "passive")
			(teardrops
				(best_length_ratio 0.2)
				(max_length 1)
				(best_width_ratio 0.9)
				(max_width 2)
				(curved_edges yes)
				(filter_ratio 0.9)
				(enabled yes)
				(allow_two_segments yes)
				(prefer_zone_connections yes)
			)
		)
		(pad "B77" smd rect
			(at 10.75 3.325)
			(size 0.3 1.75)
			(layers "F.Cu" "F.Mask" "F.Paste")
			(net 92 "/Com Express 7 Interfaces/PCIe_{B2Ax4}.RX2+")
			(pinfunction "PCIE_RX10+")
			(pintype "input")
			(teardrops
				(best_length_ratio 0.2)
				(max_length 1)
				(best_width_ratio 0.9)
				(max_width 2)
				(curved_edges yes)
				(filter_ratio 0.9)
				(enabled yes)
				(allow_two_segments yes)
				(prefer_zone_connections yes)
			)
		)
		(pad "B78" smd rect
			(at 11.25 3.325)
			(size 0.3 1.75)
			(layers "F.Cu" "F.Mask" "F.Paste")
			(net 88 "/Com Express 7 Interfaces/PCIe_{B2Ax4}.RX2-")
			(pinfunction "PCIE_RX10-")
			(pintype "input")
			(teardrops
				(best_length_ratio 0.2)
				(max_length 1)
				(best_width_ratio 0.9)
				(max_width 2)
				(curved_edges yes)
				(filter_ratio 0.9)
				(enabled yes)
				(allow_two_segments yes)
				(prefer_zone_connections yes)
			)
		)
		(pad "B79" smd rect
			(at 11.75 3.325)
			(size 0.3 1.75)
			(layers "F.Cu" "F.Mask" "F.Paste")
			(net 1 "GND")
			(pinfunction "GND")
			(pintype "passive")
			(teardrops
				(best_length_ratio 0.2)
				(max_length 1)
				(best_width_ratio 0.9)
				(max_width 2)
				(curved_edges yes)
				(filter_ratio 0.9)
				(enabled yes)
				(allow_two_segments yes)
				(prefer_zone_connections yes)
			)
		)
		(pad "B80" smd rect
			(at 12.25 3.325)
			(size 0.3 1.75)
			(layers "F.Cu" "F.Mask" "F.Paste")
			(net 1 "GND")
			(pinfunction "GND(FIXED)")
			(pintype "passive")
			(teardrops
				(best_length_ratio 0.2)
				(max_length 1)
				(best_width_ratio 0.9)
				(max_width 2)
				(curved_edges yes)
				(filter_ratio 0.9)
				(enabled yes)
				(allow_two_segments yes)
				(prefer_zone_connections yes)
			)
		)
		(pad "B81" smd rect
			(at 12.75 3.325)
			(size 0.3 1.75)
			(layers "F.Cu" "F.Mask" "F.Paste")
			(net 93 "/Com Express 7 Interfaces/PCIe_{B2Ax4}.RX3+")
			(pinfunction "PCIE_RX11+")
			(pintype "input")
			(teardrops
				(best_length_ratio 0.2)
				(max_length 1)
				(best_width_ratio 0.9)
				(max_width 2)
				(curved_edges yes)
				(filter_ratio 0.9)
				(enabled yes)
				(allow_two_segments yes)
				(prefer_zone_connections yes)
			)
		)
		(pad "B82" smd rect
			(at 13.25 3.325)
			(size 0.3 1.75)
			(layers "F.Cu" "F.Mask" "F.Paste")
			(net 89 "/Com Express 7 Interfaces/PCIe_{B2Ax4}.RX3-")
			(pinfunction "PCIE_RX11-")
			(pintype "input")
			(teardrops
				(best_length_ratio 0.2)
				(max_length 1)
				(best_width_ratio 0.9)
				(max_width 2)
				(curved_edges yes)
				(filter_ratio 0.9)
				(enabled yes)
				(allow_two_segments yes)
				(prefer_zone_connections yes)
			)
		)
		(pad "B83" smd rect
			(at 13.75 3.325)
			(size 0.3 1.75)
			(layers "F.Cu" "F.Mask" "F.Paste")
			(net 1 "GND")
			(pinfunction "GND")
			(pintype "passive")
			(teardrops
				(best_length_ratio 0.2)
				(max_length 1)
				(best_width_ratio 0.9)
				(max_width 2)
				(curved_edges yes)
				(filter_ratio 0.9)
				(enabled yes)
				(allow_two_segments yes)
				(prefer_zone_connections yes)
			)
		)
		(pad "B84" smd rect
			(at 14.25 3.325)
			(size 0.3 1.75)
			(layers "F.Cu" "F.Mask" "F.Paste")
			(net 77 "+5V_AON")
			(pinfunction "VCC_5V_SBY")
			(pintype "power_in")
			(teardrops
				(best_length_ratio 0.2)
				(max_length 1)
				(best_width_ratio 0.9)
				(max_width 2)
				(curved_edges yes)
				(filter_ratio 0.9)
				(enabled yes)
				(allow_two_segments yes)
				(prefer_zone_connections yes)
			)
		)
		(pad "B85" smd rect
			(at 14.75 3.325)
			(size 0.3 1.75)
			(layers "F.Cu" "F.Mask" "F.Paste")
			(net 77 "+5V_AON")
			(pinfunction "VCC_5V_SBY")
			(pintype "passive")
			(teardrops
				(best_length_ratio 0.2)
				(max_length 1)
				(best_width_ratio 0.9)
				(max_width 2)
				(curved_edges yes)
				(filter_ratio 0.9)
				(enabled yes)
				(allow_two_segments yes)
				(prefer_zone_connections yes)
			)
		)
		(pad "B86" smd rect
			(at 15.25 3.325)
			(size 0.3 1.75)
			(layers "F.Cu" "F.Mask" "F.Paste")
			(net 77 "+5V_AON")
			(pinfunction "VCC_5V_SBY")
			(pintype "passive")
			(teardrops
				(best_length_ratio 0.2)
				(max_length 1)
				(best_width_ratio 0.9)
				(max_width 2)
				(curved_edges yes)
				(filter_ratio 0.9)
				(enabled yes)
				(allow_two_segments yes)
				(prefer_zone_connections yes)
			)
		)
		(pad "B87" smd rect
			(at 15.75 3.325)
			(size 0.3 1.75)
			(layers "F.Cu" "F.Mask" "F.Paste")
			(net 77 "+5V_AON")
			(pinfunction "VCC_5V_SBY")
			(pintype "passive")
			(teardrops
				(best_length_ratio 0.2)
				(max_length 1)
				(best_width_ratio 0.9)
				(max_width 2)
				(curved_edges yes)
				(filter_ratio 0.9)
				(enabled yes)
				(allow_two_segments yes)
				(prefer_zone_connections yes)
			)
		)
		(pad "B88" smd rect
			(at 16.25 3.325)
			(size 0.3 1.75)
			(layers "F.Cu" "F.Mask" "F.Paste")
			(net 389 "Net-(J12D-~{BIOS_DIS1})")
			(pinfunction "~{BIOS_DIS1}")
			(pintype "input")
			(teardrops
				(best_length_ratio 0.2)
				(max_length 1)
				(best_width_ratio 0.9)
				(max_width 2)
				(curved_edges yes)
				(filter_ratio 0.9)
				(enabled yes)
				(allow_two_segments yes)
				(prefer_zone_connections yes)
			)
		)
		(pad "B89" smd rect
			(at 16.75 3.325)
			(size 0.3 1.75)
			(layers "F.Cu" "F.Mask" "F.Paste")
			(net 390 "unconnected-(J12A-NCSI_RX_ER-PadB89)")
			(pinfunction "NCSI_RX_ER")
			(pintype "input+no_connect")
			(teardrops
				(best_length_ratio 0.2)
				(max_length 1)
				(best_width_ratio 0.9)
				(max_width 2)
				(curved_edges yes)
				(filter_ratio 0.9)
				(enabled yes)
				(allow_two_segments yes)
				(prefer_zone_connections yes)
			)
		)
		(pad "B90" smd rect
			(at 17.25 3.325)
			(size 0.3 1.75)
			(layers "F.Cu" "F.Mask" "F.Paste")
			(net 1 "GND")
			(pinfunction "GND(FIXED)")
			(pintype "passive")
			(teardrops
				(best_length_ratio 0.2)
				(max_length 1)
				(best_width_ratio 0.9)
				(max_width 2)
				(curved_edges yes)
				(filter_ratio 0.9)
				(enabled yes)
				(allow_two_segments yes)
				(prefer_zone_connections yes)
			)
		)
		(pad "B91" smd rect
			(at 17.75 3.325)
			(size 0.3 1.75)
			(layers "F.Cu" "F.Mask" "F.Paste")
			(net 391 "unconnected-(J12A-NCSI_CLK_IN-PadB91)")
			(pinfunction "NCSI_CLK_IN")
			(pintype "input+no_connect")
			(teardrops
				(best_length_ratio 0.2)
				(max_length 1)
				(best_width_ratio 0.9)
				(max_width 2)
				(curved_edges yes)
				(filter_ratio 0.9)
				(enabled yes)
				(allow_two_segments yes)
				(prefer_zone_connections yes)
			)
		)
		(pad "B92" smd rect
			(at 18.25 3.325)
			(size 0.3 1.75)
			(layers "F.Cu" "F.Mask" "F.Paste")
			(net 392 "unconnected-(J12A-NCSI_RXD1-PadB92)")
			(pinfunction "NCSI_RXD1")
			(pintype "input+no_connect")
			(teardrops
				(best_length_ratio 0.2)
				(max_length 1)
				(best_width_ratio 0.9)
				(max_width 2)
				(curved_edges yes)
				(filter_ratio 0.9)
				(enabled yes)
				(allow_two_segments yes)
				(prefer_zone_connections yes)
			)
		)
		(pad "B93" smd rect
			(at 18.75 3.325)
			(size 0.3 1.75)
			(layers "F.Cu" "F.Mask" "F.Paste")
			(net 393 "unconnected-(J12A-NCSI_RXD0-PadB93)")
			(pinfunction "NCSI_RXD0")
			(pintype "input+no_connect")
			(teardrops
				(best_length_ratio 0.2)
				(max_length 1)
				(best_width_ratio 0.9)
				(max_width 2)
				(curved_edges yes)
				(filter_ratio 0.9)
				(enabled yes)
				(allow_two_segments yes)
				(prefer_zone_connections yes)
			)
		)
		(pad "B94" smd rect
			(at 19.25 3.325)
			(size 0.3 1.75)
			(layers "F.Cu" "F.Mask" "F.Paste")
			(net 394 "unconnected-(J12A-NCSI_CRS_DV-PadB94)")
			(pinfunction "NCSI_CRS_DV")
			(pintype "output+no_connect")
			(teardrops
				(best_length_ratio 0.2)
				(max_length 1)
				(best_width_ratio 0.9)
				(max_width 2)
				(curved_edges yes)
				(filter_ratio 0.9)
				(enabled yes)
				(allow_two_segments yes)
				(prefer_zone_connections yes)
			)
		)
		(pad "B95" smd rect
			(at 19.75 3.325)
			(size 0.3 1.75)
			(layers "F.Cu" "F.Mask" "F.Paste")
			(net 395 "unconnected-(J12A-NCSI_TXD1-PadB95)")
			(pinfunction "NCSI_TXD1")
			(pintype "output+no_connect")
			(teardrops
				(best_length_ratio 0.2)
				(max_length 1)
				(best_width_ratio 0.9)
				(max_width 2)
				(curved_edges yes)
				(filter_ratio 0.9)
				(enabled yes)
				(allow_two_segments yes)
				(prefer_zone_connections yes)
			)
		)
		(pad "B96" smd rect
			(at 20.25 3.325)
			(size 0.3 1.75)
			(layers "F.Cu" "F.Mask" "F.Paste")
			(net 396 "unconnected-(J12A-NCSI_TXD0-PadB96)")
			(pinfunction "NCSI_TXD0")
			(pintype "output+no_connect")
			(teardrops
				(best_length_ratio 0.2)
				(max_length 1)
				(best_width_ratio 0.9)
				(max_width 2)
				(curved_edges yes)
				(filter_ratio 0.9)
				(enabled yes)
				(allow_two_segments yes)
				(prefer_zone_connections yes)
			)
		)
		(pad "B97" smd rect
			(at 20.75 3.325)
			(size 0.3 1.75)
			(layers "F.Cu" "F.Mask" "F.Paste")
			(net 397 "/Com Express 7 MGMT/SPI.~{CS}")
			(pinfunction "~{SPI_CS}")
			(pintype "output")
			(teardrops
				(best_length_ratio 0.2)
				(max_length 1)
				(best_width_ratio 0.9)
				(max_width 2)
				(curved_edges yes)
				(filter_ratio 0.9)
				(enabled yes)
				(allow_two_segments yes)
				(prefer_zone_connections yes)
			)
		)
		(pad "B98" smd rect
			(at 21.25 3.325)
			(size 0.3 1.75)
			(layers "F.Cu" "F.Mask" "F.Paste")
			(net 398 "unconnected-(J12A-NCSI_ARB_IN-PadB98)")
			(pinfunction "NCSI_ARB_IN")
			(pintype "input+no_connect")
			(teardrops
				(best_length_ratio 0.2)
				(max_length 1)
				(best_width_ratio 0.9)
				(max_width 2)
				(curved_edges yes)
				(filter_ratio 0.9)
				(enabled yes)
				(allow_two_segments yes)
				(prefer_zone_connections yes)
			)
		)
		(pad "B99" smd rect
			(at 21.75 3.325)
			(size 0.3 1.75)
			(layers "F.Cu" "F.Mask" "F.Paste")
			(net 399 "unconnected-(J12A-NCSI_ARB_OUT-PadB99)")
			(pinfunction "NCSI_ARB_OUT")
			(pintype "output+no_connect")
			(teardrops
				(best_length_ratio 0.2)
				(max_length 1)
				(best_width_ratio 0.9)
				(max_width 2)
				(curved_edges yes)
				(filter_ratio 0.9)
				(enabled yes)
				(allow_two_segments yes)
				(prefer_zone_connections yes)
			)
		)
		(pad "B100" smd rect
			(at 22.25 3.325)
			(size 0.3 1.75)
			(layers "F.Cu" "F.Mask" "F.Paste")
			(net 1 "GND")
			(pinfunction "GND(FIXED)")
			(pintype "passive")
			(teardrops
				(best_length_ratio 0.2)
				(max_length 1)
				(best_width_ratio 0.9)
				(max_width 2)
				(curved_edges yes)
				(filter_ratio 0.9)
				(enabled yes)
				(allow_two_segments yes)
				(prefer_zone_connections yes)
			)
		)
		(pad "B101" smd rect
			(at 22.75 3.325)
			(size 0.3 1.75)
			(layers "F.Cu" "F.Mask" "F.Paste")
			(net 400 "/Com Express 7 MGMT/FAN_PWM")
			(pinfunction "FAN_PWMOUT")
			(pintype "output")
			(teardrops
				(best_length_ratio 0.2)
				(max_length 1)
				(best_width_ratio 0.9)
				(max_width 2)
				(curved_edges yes)
				(filter_ratio 0.9)
				(enabled yes)
				(allow_two_segments yes)
				(prefer_zone_connections yes)
			)
		)
		(pad "B102" smd rect
			(at 23.25 3.325)
			(size 0.3 1.75)
			(layers "F.Cu" "F.Mask" "F.Paste")
			(net 401 "/Com Express 7 MGMT/FAM_TACH")
			(pinfunction "FAN_TACHIN")
			(pintype "input")
			(teardrops
				(best_length_ratio 0.2)
				(max_length 1)
				(best_width_ratio 0.9)
				(max_width 2)
				(curved_edges yes)
				(filter_ratio 0.9)
				(enabled yes)
				(allow_two_segments yes)
				(prefer_zone_connections yes)
			)
		)
		(pad "B103" smd rect
			(at 23.75 3.325)
			(size 0.3 1.75)
			(layers "F.Cu" "F.Mask" "F.Paste")
			(net 402 "unconnected-(J12D-~{SLEEP}-PadB103)")
			(pinfunction "~{SLEEP}")
			(pintype "input+no_connect")
			(teardrops
				(best_length_ratio 0.2)
				(max_length 1)
				(best_width_ratio 0.9)
				(max_width 2)
				(curved_edges yes)
				(filter_ratio 0.9)
				(enabled yes)
				(allow_two_segments yes)
				(prefer_zone_connections yes)
			)
		)
		(pad "B104" smd rect
			(at 24.25 3.325)
			(size 0.3 1.75)
			(layers "F.Cu" "F.Mask" "F.Paste")
			(net 65 "+12V")
			(pinfunction "VCC_12V")
			(pintype "passive")
			(teardrops
				(best_length_ratio 0.2)
				(max_length 1)
				(best_width_ratio 0.9)
				(max_width 2)
				(curved_edges yes)
				(filter_ratio 0.9)
				(enabled yes)
				(allow_two_segments yes)
				(prefer_zone_connections yes)
			)
		)
		(pad "B105" smd rect
			(at 24.75 3.325)
			(size 0.3 1.75)
			(layers "F.Cu" "F.Mask" "F.Paste")
			(net 65 "+12V")
			(pinfunction "VCC_12V")
			(pintype "passive")
			(teardrops
				(best_length_ratio 0.2)
				(max_length 1)
				(best_width_ratio 0.9)
				(max_width 2)
				(curved_edges yes)
				(filter_ratio 0.9)
				(enabled yes)
				(allow_two_segments yes)
				(prefer_zone_connections yes)
			)
		)
		(pad "B106" smd rect
			(at 25.25 3.325)
			(size 0.3 1.75)
			(layers "F.Cu" "F.Mask" "F.Paste")
			(net 65 "+12V")
			(pinfunction "VCC_12V")
			(pintype "passive")
			(teardrops
				(best_length_ratio 0.2)
				(max_length 1)
				(best_width_ratio 0.9)
				(max_width 2)
				(curved_edges yes)
				(filter_ratio 0.9)
				(enabled yes)
				(allow_two_segments yes)
				(prefer_zone_connections yes)
			)
		)
		(pad "B107" smd rect
			(at 25.75 3.325)
			(size 0.3 1.75)
			(layers "F.Cu" "F.Mask" "F.Paste")
			(net 65 "+12V")
			(pinfunction "VCC_12V")
			(pintype "passive")
			(teardrops
				(best_length_ratio 0.2)
				(max_length 1)
				(best_width_ratio 0.9)
				(max_width 2)
				(curved_edges yes)
				(filter_ratio 0.9)
				(enabled yes)
				(allow_two_segments yes)
				(prefer_zone_connections yes)
			)
		)
		(pad "B108" smd rect
			(at 26.25 3.325)
			(size 0.3 1.75)
			(layers "F.Cu" "F.Mask" "F.Paste")
			(net 65 "+12V")
			(pinfunction "VCC_12V")
			(pintype "passive")
			(teardrops
				(best_length_ratio 0.2)
				(max_length 1)
				(best_width_ratio 0.9)
				(max_width 2)
				(curved_edges yes)
				(filter_ratio 0.9)
				(enabled yes)
				(allow_two_segments yes)
				(prefer_zone_connections yes)
			)
		)
		(pad "B109" smd rect
			(at 26.75 3.325)
			(size 0.3 1.75)
			(layers "F.Cu" "F.Mask" "F.Paste")
			(net 65 "+12V")
			(pinfunction "VCC_12V")
			(pintype "passive")
			(teardrops
				(best_length_ratio 0.2)
				(max_length 1)
				(best_width_ratio 0.9)
				(max_width 2)
				(curved_edges yes)
				(filter_ratio 0.9)
				(enabled yes)
				(allow_two_segments yes)
				(prefer_zone_connections yes)
			)
		)
		(pad "B110" smd rect
			(at 27.25 3.325)
			(size 0.3 1.75)
			(layers "F.Cu" "F.Mask" "F.Paste")
			(net 1 "GND")
			(pinfunction "GND(FIXED)")
			(pintype "passive")
			(teardrops
				(best_length_ratio 0.2)
				(max_length 1)
				(best_width_ratio 0.9)
				(max_width 2)
				(curved_edges yes)
				(filter_ratio 0.9)
				(enabled yes)
				(allow_two_segments yes)
				(prefer_zone_connections yes)
			)
		)
		(pad "C1" smd rect
			(at -27.25 -3.125)
			(size 0.3 1.75)
			(layers "F.Cu" "F.Mask" "F.Paste")
			(net 1 "GND")
			(pinfunction "GND(FIXED)")
			(pintype "power_in")
			(teardrops
				(best_length_ratio 0.2)
				(max_length 1)
				(best_width_ratio 0.9)
				(max_width 2)
				(curved_edges yes)
				(filter_ratio 0.9)
				(enabled yes)
				(allow_two_segments yes)
				(prefer_zone_connections yes)
			)
		)
		(pad "C2" smd rect
			(at -26.75 -3.125)
			(size 0.3 1.75)
			(layers "F.Cu" "F.Mask" "F.Paste")
			(net 1 "GND")
			(pinfunction "GND")
			(pintype "passive")
			(teardrops
				(best_length_ratio 0.2)
				(max_length 1)
				(best_width_ratio 0.9)
				(max_width 2)
				(curved_edges yes)
				(filter_ratio 0.9)
				(enabled yes)
				(allow_two_segments yes)
				(prefer_zone_connections yes)
			)
		)
		(pad "C3" smd rect
			(at -26.25 -3.125)
			(size 0.3 1.75)
			(layers "F.Cu" "F.Mask" "F.Paste")
			(net 403 "unconnected-(J12J-USB_SSRX0--PadC3)")
			(pinfunction "USB_SSRX0-")
			(pintype "input+no_connect")
			(teardrops
				(best_length_ratio 0.2)
				(max_length 1)
				(best_width_ratio 0.9)
				(max_width 2)
				(curved_edges yes)
				(filter_ratio 0.9)
				(enabled yes)
				(allow_two_segments yes)
				(prefer_zone_connections yes)
			)
		)
		(pad "C4" smd rect
			(at -25.75 -3.125)
			(size 0.3 1.75)
			(layers "F.Cu" "F.Mask" "F.Paste")
			(net 404 "unconnected-(J12J-USB_SSRX0+-PadC4)")
			(pinfunction "USB_SSRX0+")
			(pintype "input+no_connect")
			(teardrops
				(best_length_ratio 0.2)
				(max_length 1)
				(best_width_ratio 0.9)
				(max_width 2)
				(curved_edges yes)
				(filter_ratio 0.9)
				(enabled yes)
				(allow_two_segments yes)
				(prefer_zone_connections yes)
			)
		)
		(pad "C5" smd rect
			(at -25.25 -3.125)
			(size 0.3 1.75)
			(layers "F.Cu" "F.Mask" "F.Paste")
			(net 1 "GND")
			(pinfunction "GND")
			(pintype "passive")
			(teardrops
				(best_length_ratio 0.2)
				(max_length 1)
				(best_width_ratio 0.9)
				(max_width 2)
				(curved_edges yes)
				(filter_ratio 0.9)
				(enabled yes)
				(allow_two_segments yes)
				(prefer_zone_connections yes)
			)
		)
		(pad "C6" smd rect
			(at -24.75 -3.125)
			(size 0.3 1.75)
			(layers "F.Cu" "F.Mask" "F.Paste")
			(net 405 "unconnected-(J12J-USB_SSRX1--PadC6)")
			(pinfunction "USB_SSRX1-")
			(pintype "input+no_connect")
			(teardrops
				(best_length_ratio 0.2)
				(max_length 1)
				(best_width_ratio 0.9)
				(max_width 2)
				(curved_edges yes)
				(filter_ratio 0.9)
				(enabled yes)
				(allow_two_segments yes)
				(prefer_zone_connections yes)
			)
		)
		(pad "C7" smd rect
			(at -24.25 -3.125)
			(size 0.3 1.75)
			(layers "F.Cu" "F.Mask" "F.Paste")
			(net 406 "unconnected-(J12J-USB_SSRX1+-PadC7)")
			(pinfunction "USB_SSRX1+")
			(pintype "input+no_connect")
			(teardrops
				(best_length_ratio 0.2)
				(max_length 1)
				(best_width_ratio 0.9)
				(max_width 2)
				(curved_edges yes)
				(filter_ratio 0.9)
				(enabled yes)
				(allow_two_segments yes)
				(prefer_zone_connections yes)
			)
		)
		(pad "C8" smd rect
			(at -23.75 -3.125)
			(size 0.3 1.75)
			(layers "F.Cu" "F.Mask" "F.Paste")
			(net 1 "GND")
			(pinfunction "GND")
			(pintype "passive")
			(teardrops
				(best_length_ratio 0.2)
				(max_length 1)
				(best_width_ratio 0.9)
				(max_width 2)
				(curved_edges yes)
				(filter_ratio 0.9)
				(enabled yes)
				(allow_two_segments yes)
				(prefer_zone_connections yes)
			)
		)
		(pad "C9" smd rect
			(at -23.25 -3.125)
			(size 0.3 1.75)
			(layers "F.Cu" "F.Mask" "F.Paste")
			(net 158 "/2xUSB3.0+RJ45/USBSS_1.RX-")
			(pinfunction "USB_SSRX2-")
			(pintype "input")
			(teardrops
				(best_length_ratio 0.2)
				(max_length 1)
				(best_width_ratio 0.9)
				(max_width 2)
				(curved_edges yes)
				(filter_ratio 0.9)
				(enabled yes)
				(allow_two_segments yes)
				(prefer_zone_connections yes)
			)
		)
		(pad "C10" smd rect
			(at -22.75 -3.125)
			(size 0.3 1.75)
			(layers "F.Cu" "F.Mask" "F.Paste")
			(net 159 "/2xUSB3.0+RJ45/USBSS_1.RX+")
			(pinfunction "USB_SSRX2+")
			(pintype "input")
			(teardrops
				(best_length_ratio 0.2)
				(max_length 1)
				(best_width_ratio 0.9)
				(max_width 2)
				(curved_edges yes)
				(filter_ratio 0.9)
				(enabled yes)
				(allow_two_segments yes)
				(prefer_zone_connections yes)
			)
		)
		(pad "C11" smd rect
			(at -22.25 -3.125)
			(size 0.3 1.75)
			(layers "F.Cu" "F.Mask" "F.Paste")
			(net 1 "GND")
			(pinfunction "GND(FIXED)")
			(pintype "passive")
			(teardrops
				(best_length_ratio 0.2)
				(max_length 1)
				(best_width_ratio 0.9)
				(max_width 2)
				(curved_edges yes)
				(filter_ratio 0.9)
				(enabled yes)
				(allow_two_segments yes)
				(prefer_zone_connections yes)
			)
		)
		(pad "C12" smd rect
			(at -21.75 -3.125)
			(size 0.3 1.75)
			(layers "F.Cu" "F.Mask" "F.Paste")
			(net 160 "/2xUSB3.0+RJ45/USBSS_2.RX-")
			(pinfunction "USB_SSRX3-")
			(pintype "input")
			(teardrops
				(best_length_ratio 0.2)
				(max_length 1)
				(best_width_ratio 0.9)
				(max_width 2)
				(curved_edges yes)
				(filter_ratio 0.9)
				(enabled yes)
				(allow_two_segments yes)
				(prefer_zone_connections yes)
			)
		)
		(pad "C13" smd rect
			(at -21.25 -3.125)
			(size 0.3 1.75)
			(layers "F.Cu" "F.Mask" "F.Paste")
			(net 161 "/2xUSB3.0+RJ45/USBSS_2.RX+")
			(pinfunction "USB_SSRX3+")
			(pintype "input")
			(teardrops
				(best_length_ratio 0.2)
				(max_length 1)
				(best_width_ratio 0.9)
				(max_width 2)
				(curved_edges yes)
				(filter_ratio 0.9)
				(enabled yes)
				(allow_two_segments yes)
				(prefer_zone_connections yes)
			)
		)
		(pad "C14" smd rect
			(at -20.75 -3.125)
			(size 0.3 1.75)
			(layers "F.Cu" "F.Mask" "F.Paste")
			(net 1 "GND")
			(pinfunction "GND")
			(pintype "passive")
			(teardrops
				(best_length_ratio 0.2)
				(max_length 1)
				(best_width_ratio 0.9)
				(max_width 2)
				(curved_edges yes)
				(filter_ratio 0.9)
				(enabled yes)
				(allow_two_segments yes)
				(prefer_zone_connections yes)
			)
		)
		(pad "C15" smd rect
			(at -20.25 -3.125)
			(size 0.3 1.75)
			(layers "F.Cu" "F.Mask" "F.Paste")
			(net 407 "unconnected-(J12K-10G_PHY_MDC_SCL3-PadC15)")
			(pinfunction "10G_PHY_MDC_SCL3")
			(pintype "open_collector+no_connect")
			(teardrops
				(best_length_ratio 0.2)
				(max_length 1)
				(best_width_ratio 0.9)
				(max_width 2)
				(curved_edges yes)
				(filter_ratio 0.9)
				(enabled yes)
				(allow_two_segments yes)
				(prefer_zone_connections yes)
			)
		)
		(pad "C16" smd rect
			(at -19.75 -3.125)
			(size 0.3 1.75)
			(layers "F.Cu" "F.Mask" "F.Paste")
			(net 408 "unconnected-(J12K-10G_PHY_MDC_SCL2-PadC16)")
			(pinfunction "10G_PHY_MDC_SCL2")
			(pintype "open_collector+no_connect")
			(teardrops
				(best_length_ratio 0.2)
				(max_length 1)
				(best_width_ratio 0.9)
				(max_width 2)
				(curved_edges yes)
				(filter_ratio 0.9)
				(enabled yes)
				(allow_two_segments yes)
				(prefer_zone_connections yes)
			)
		)
		(pad "C17" smd rect
			(at -19.25 -3.125)
			(size 0.3 1.75)
			(layers "F.Cu" "F.Mask" "F.Paste")
			(net 409 "Net-(J12K-10G_SDP2)")
			(pinfunction "10G_SDP2")
			(pintype "bidirectional")
			(teardrops
				(best_length_ratio 0.2)
				(max_length 1)
				(best_width_ratio 0.9)
				(max_width 2)
				(curved_edges yes)
				(filter_ratio 0.9)
				(enabled yes)
				(allow_two_segments yes)
				(prefer_zone_connections yes)
			)
		)
		(pad "C18" smd rect
			(at -18.75 -3.125)
			(size 0.3 1.75)
			(layers "F.Cu" "F.Mask" "F.Paste")
			(net 1 "GND")
			(pinfunction "GND")
			(pintype "passive")
			(teardrops
				(best_length_ratio 0.2)
				(max_length 1)
				(best_width_ratio 0.9)
				(max_width 2)
				(curved_edges yes)
				(filter_ratio 0.9)
				(enabled yes)
				(allow_two_segments yes)
				(prefer_zone_connections yes)
			)
		)
		(pad "C19" smd rect
			(at -18.25 -3.125)
			(size 0.3 1.75)
			(layers "F.Cu" "F.Mask" "F.Paste")
			(net 410 "unconnected-(J12O-PCIE_RX6+-PadC19)")
			(pinfunction "PCIE_RX6+")
			(pintype "input+no_connect")
			(teardrops
				(best_length_ratio 0.2)
				(max_length 1)
				(best_width_ratio 0.9)
				(max_width 2)
				(curved_edges yes)
				(filter_ratio 0.9)
				(enabled yes)
				(allow_two_segments yes)
				(prefer_zone_connections yes)
			)
		)
		(pad "C20" smd rect
			(at -17.75 -3.125)
			(size 0.3 1.75)
			(layers "F.Cu" "F.Mask" "F.Paste")
			(net 411 "unconnected-(J12O-PCIE_RX6--PadC20)")
			(pinfunction "PCIE_RX6-")
			(pintype "input+no_connect")
			(teardrops
				(best_length_ratio 0.2)
				(max_length 1)
				(best_width_ratio 0.9)
				(max_width 2)
				(curved_edges yes)
				(filter_ratio 0.9)
				(enabled yes)
				(allow_two_segments yes)
				(prefer_zone_connections yes)
			)
		)
		(pad "C21" smd rect
			(at -17.25 -3.125)
			(size 0.3 1.75)
			(layers "F.Cu" "F.Mask" "F.Paste")
			(net 1 "GND")
			(pinfunction "GND(FIXED)")
			(pintype "passive")
			(teardrops
				(best_length_ratio 0.2)
				(max_length 1)
				(best_width_ratio 0.9)
				(max_width 2)
				(curved_edges yes)
				(filter_ratio 0.9)
				(enabled yes)
				(allow_two_segments yes)
				(prefer_zone_connections yes)
			)
		)
		(pad "C22" smd rect
			(at -16.75 -3.125)
			(size 0.3 1.75)
			(layers "F.Cu" "F.Mask" "F.Paste")
			(net 412 "unconnected-(J12O-PCIE_RX7+-PadC22)")
			(pinfunction "PCIE_RX7+")
			(pintype "input+no_connect")
			(teardrops
				(best_length_ratio 0.2)
				(max_length 1)
				(best_width_ratio 0.9)
				(max_width 2)
				(curved_edges yes)
				(filter_ratio 0.9)
				(enabled yes)
				(allow_two_segments yes)
				(prefer_zone_connections yes)
			)
		)
		(pad "C23" smd rect
			(at -16.25 -3.125)
			(size 0.3 1.75)
			(layers "F.Cu" "F.Mask" "F.Paste")
			(net 413 "unconnected-(J12O-PCIE_RX7--PadC23)")
			(pinfunction "PCIE_RX7-")
			(pintype "input+no_connect")
			(teardrops
				(best_length_ratio 0.2)
				(max_length 1)
				(best_width_ratio 0.9)
				(max_width 2)
				(curved_edges yes)
				(filter_ratio 0.9)
				(enabled yes)
				(allow_two_segments yes)
				(prefer_zone_connections yes)
			)
		)
		(pad "C24" smd rect
			(at -15.75 -3.125)
			(size 0.3 1.75)
			(layers "F.Cu" "F.Mask" "F.Paste")
			(net 414 "unconnected-(J12K-10G_INT2-PadC24)")
			(pinfunction "10G_INT2")
			(pintype "input+no_connect")
			(teardrops
				(best_length_ratio 0.2)
				(max_length 1)
				(best_width_ratio 0.9)
				(max_width 2)
				(curved_edges yes)
				(filter_ratio 0.9)
				(enabled yes)
				(allow_two_segments yes)
				(prefer_zone_connections yes)
			)
		)
		(pad "C25" smd rect
			(at -15.25 -3.125)
			(size 0.3 1.75)
			(layers "F.Cu" "F.Mask" "F.Paste")
			(net 1 "GND")
			(pinfunction "GND")
			(pintype "passive")
			(teardrops
				(best_length_ratio 0.2)
				(max_length 1)
				(best_width_ratio 0.9)
				(max_width 2)
				(curved_edges yes)
				(filter_ratio 0.9)
				(enabled yes)
				(allow_two_segments yes)
				(prefer_zone_connections yes)
			)
		)
		(pad "C26" smd rect
			(at -14.75 -3.125)
			(size 0.3 1.75)
			(layers "F.Cu" "F.Mask" "F.Paste")
			(net 415 "unconnected-(J12K-10G_KR_RX3+-PadC26)")
			(pinfunction "10G_KR_RX3+")
			(pintype "input+no_connect")
			(teardrops
				(best_length_ratio 0.2)
				(max_length 1)
				(best_width_ratio 0.9)
				(max_width 2)
				(curved_edges yes)
				(filter_ratio 0.9)
				(enabled yes)
				(allow_two_segments yes)
				(prefer_zone_connections yes)
			)
		)
		(pad "C27" smd rect
			(at -14.25 -3.125)
			(size 0.3 1.75)
			(layers "F.Cu" "F.Mask" "F.Paste")
			(net 416 "unconnected-(J12K-10G_KR_RX3--PadC27)")
			(pinfunction "10G_KR_RX3-")
			(pintype "input+no_connect")
			(teardrops
				(best_length_ratio 0.2)
				(max_length 1)
				(best_width_ratio 0.9)
				(max_width 2)
				(curved_edges yes)
				(filter_ratio 0.9)
				(enabled yes)
				(allow_two_segments yes)
				(prefer_zone_connections yes)
			)
		)
		(pad "C28" smd rect
			(at -13.75 -3.125)
			(size 0.3 1.75)
			(layers "F.Cu" "F.Mask" "F.Paste")
			(net 1 "GND")
			(pinfunction "GND")
			(pintype "passive")
			(teardrops
				(best_length_ratio 0.2)
				(max_length 1)
				(best_width_ratio 0.9)
				(max_width 2)
				(curved_edges yes)
				(filter_ratio 0.9)
				(enabled yes)
				(allow_two_segments yes)
				(prefer_zone_connections yes)
			)
		)
		(pad "C29" smd rect
			(at -13.25 -3.125)
			(size 0.3 1.75)
			(layers "F.Cu" "F.Mask" "F.Paste")
			(net 417 "unconnected-(J12K-10G_KR_RX2+-PadC29)")
			(pinfunction "10G_KR_RX2+")
			(pintype "input+no_connect")
			(teardrops
				(best_length_ratio 0.2)
				(max_length 1)
				(best_width_ratio 0.9)
				(max_width 2)
				(curved_edges yes)
				(filter_ratio 0.9)
				(enabled yes)
				(allow_two_segments yes)
				(prefer_zone_connections yes)
			)
		)
		(pad "C30" smd rect
			(at -12.75 -3.125)
			(size 0.3 1.75)
			(layers "F.Cu" "F.Mask" "F.Paste")
			(net 418 "unconnected-(J12K-10G_KR_RX2--PadC30)")
			(pinfunction "10G_KR_RX2-")
			(pintype "input+no_connect")
			(teardrops
				(best_length_ratio 0.2)
				(max_length 1)
				(best_width_ratio 0.9)
				(max_width 2)
				(curved_edges yes)
				(filter_ratio 0.9)
				(enabled yes)
				(allow_two_segments yes)
				(prefer_zone_connections yes)
			)
		)
		(pad "C31" smd rect
			(at -12.25 -3.125)
			(size 0.3 1.75)
			(layers "F.Cu" "F.Mask" "F.Paste")
			(net 1 "GND")
			(pinfunction "GND(FIXED)")
			(pintype "passive")
			(teardrops
				(best_length_ratio 0.2)
				(max_length 1)
				(best_width_ratio 0.9)
				(max_width 2)
				(curved_edges yes)
				(filter_ratio 0.9)
				(enabled yes)
				(allow_two_segments yes)
				(prefer_zone_connections yes)
			)
		)
		(pad "C32" smd rect
			(at -11.75 -3.125)
			(size 0.3 1.75)
			(layers "F.Cu" "F.Mask" "F.Paste")
			(net 419 "unconnected-(J12K-10G_SFP_SDA3-PadC32)")
			(pinfunction "10G_SFP_SDA3")
			(pintype "open_collector+no_connect")
			(teardrops
				(best_length_ratio 0.2)
				(max_length 1)
				(best_width_ratio 0.9)
				(max_width 2)
				(curved_edges yes)
				(filter_ratio 0.9)
				(enabled yes)
				(allow_two_segments yes)
				(prefer_zone_connections yes)
			)
		)
		(pad "C33" smd rect
			(at -11.25 -3.125)
			(size 0.3 1.75)
			(layers "F.Cu" "F.Mask" "F.Paste")
			(net 420 "unconnected-(J12K-10G_SFP_SDA2-PadC33)")
			(pinfunction "10G_SFP_SDA2")
			(pintype "open_collector+no_connect")
			(teardrops
				(best_length_ratio 0.2)
				(max_length 1)
				(best_width_ratio 0.9)
				(max_width 2)
				(curved_edges yes)
				(filter_ratio 0.9)
				(enabled yes)
				(allow_two_segments yes)
				(prefer_zone_connections yes)
			)
		)
		(pad "C34" smd rect
			(at -10.75 -3.125)
			(size 0.3 1.75)
			(layers "F.Cu" "F.Mask" "F.Paste")
			(net 421 "unconnected-(J12K-10G_PHY_RST_23-PadC34)")
			(pinfunction "10G_PHY_RST_23")
			(pintype "output+no_connect")
			(teardrops
				(best_length_ratio 0.2)
				(max_length 1)
				(best_width_ratio 0.9)
				(max_width 2)
				(curved_edges yes)
				(filter_ratio 0.9)
				(enabled yes)
				(allow_two_segments yes)
				(prefer_zone_connections yes)
			)
		)
		(pad "C35" smd rect
			(at -10.25 -3.125)
			(size 0.3 1.75)
			(layers "F.Cu" "F.Mask" "F.Paste")
			(net 142 "/2xSFP+/PHY0_{RESET}")
			(pinfunction "10G_PHY_RST_01")
			(pintype "output")
			(teardrops
				(best_length_ratio 0.2)
				(max_length 1)
				(best_width_ratio 0.9)
				(max_width 2)
				(curved_edges yes)
				(filter_ratio 0.9)
				(enabled yes)
				(allow_two_segments yes)
				(prefer_zone_connections yes)
			)
		)
		(pad "C36" smd rect
			(at -9.75 -3.125)
			(size 0.3 1.75)
			(layers "F.Cu" "F.Mask" "F.Paste")
			(net 422 "/2xSFP+/I2C_{LED}.SDA")
			(pinfunction "10G_LED_SDA")
			(pintype "open_collector")
			(teardrops
				(best_length_ratio 0.2)
				(max_length 1)
				(best_width_ratio 0.9)
				(max_width 2)
				(curved_edges yes)
				(filter_ratio 0.9)
				(enabled yes)
				(allow_two_segments yes)
				(prefer_zone_connections yes)
			)
		)
		(pad "C37" smd rect
			(at -9.25 -3.125)
			(size 0.3 1.75)
			(layers "F.Cu" "F.Mask" "F.Paste")
			(net 423 "/2xSFP+/I2C_{LED}.SCL")
			(pinfunction "10G_LED_SCL")
			(pintype "open_collector")
			(teardrops
				(best_length_ratio 0.2)
				(max_length 1)
				(best_width_ratio 0.9)
				(max_width 2)
				(curved_edges yes)
				(filter_ratio 0.9)
				(enabled yes)
				(allow_two_segments yes)
				(prefer_zone_connections yes)
			)
		)
		(pad "C38" smd rect
			(at -8.75 -3.125)
			(size 0.3 1.75)
			(layers "F.Cu" "F.Mask" "F.Paste")
			(net 424 "/2xSFP+/I2C_{SFP1}.SDA")
			(pinfunction "10G_SFP_SDA1")
			(pintype "open_collector")
			(teardrops
				(best_length_ratio 0.2)
				(max_length 1)
				(best_width_ratio 0.9)
				(max_width 2)
				(curved_edges yes)
				(filter_ratio 0.9)
				(enabled yes)
				(allow_two_segments yes)
				(prefer_zone_connections yes)
			)
		)
		(pad "C39" smd rect
			(at -8.25 -3.125)
			(size 0.3 1.75)
			(layers "F.Cu" "F.Mask" "F.Paste")
			(net 425 "/2xSFP+/I2C_{SFP0}.SDA")
			(pinfunction "10G_SFP_SDA0")
			(pintype "open_collector")
			(teardrops
				(best_length_ratio 0.2)
				(max_length 1)
				(best_width_ratio 0.9)
				(max_width 2)
				(curved_edges yes)
				(filter_ratio 0.9)
				(enabled yes)
				(allow_two_segments yes)
				(prefer_zone_connections yes)
			)
		)
		(pad "C40" smd rect
			(at -7.75 -3.125)
			(size 0.3 1.75)
			(layers "F.Cu" "F.Mask" "F.Paste")
			(net 426 "Net-(J12K-10G_SDP0)")
			(pinfunction "10G_SDP0")
			(pintype "bidirectional")
			(teardrops
				(best_length_ratio 0.2)
				(max_length 1)
				(best_width_ratio 0.9)
				(max_width 2)
				(curved_edges yes)
				(filter_ratio 0.9)
				(enabled yes)
				(allow_two_segments yes)
				(prefer_zone_connections yes)
			)
		)
		(pad "C41" smd rect
			(at -7.25 -3.125)
			(size 0.3 1.75)
			(layers "F.Cu" "F.Mask" "F.Paste")
			(net 1 "GND")
			(pinfunction "GND(FIXED)")
			(pintype "passive")
			(teardrops
				(best_length_ratio 0.2)
				(max_length 1)
				(best_width_ratio 0.9)
				(max_width 2)
				(curved_edges yes)
				(filter_ratio 0.9)
				(enabled yes)
				(allow_two_segments yes)
				(prefer_zone_connections yes)
			)
		)
		(pad "C42" smd rect
			(at -6.75 -3.125)
			(size 0.3 1.75)
			(layers "F.Cu" "F.Mask" "F.Paste")
			(net 427 "/2xSFP+/10GKR_SFP1.RX+")
			(pinfunction "10G_KR_RX1+")
			(pintype "input")
			(teardrops
				(best_length_ratio 0.2)
				(max_length 1)
				(best_width_ratio 0.9)
				(max_width 2)
				(curved_edges yes)
				(filter_ratio 0.9)
				(enabled yes)
				(allow_two_segments yes)
				(prefer_zone_connections yes)
			)
		)
		(pad "C43" smd rect
			(at -6.25 -3.125)
			(size 0.3 1.75)
			(layers "F.Cu" "F.Mask" "F.Paste")
			(net 428 "/2xSFP+/10GKR_SFP1.RX-")
			(pinfunction "10G_KR_RX1-")
			(pintype "input")
			(teardrops
				(best_length_ratio 0.2)
				(max_length 1)
				(best_width_ratio 0.9)
				(max_width 2)
				(curved_edges yes)
				(filter_ratio 0.9)
				(enabled yes)
				(allow_two_segments yes)
				(prefer_zone_connections yes)
			)
		)
		(pad "C44" smd rect
			(at -5.75 -3.125)
			(size 0.3 1.75)
			(layers "F.Cu" "F.Mask" "F.Paste")
			(net 1 "GND")
			(pinfunction "GND")
			(pintype "passive")
			(teardrops
				(best_length_ratio 0.2)
				(max_length 1)
				(best_width_ratio 0.9)
				(max_width 2)
				(curved_edges yes)
				(filter_ratio 0.9)
				(enabled yes)
				(allow_two_segments yes)
				(prefer_zone_connections yes)
			)
		)
		(pad "C45" smd rect
			(at -5.25 -3.125)
			(size 0.3 1.75)
			(layers "F.Cu" "F.Mask" "F.Paste")
			(net 429 "/2xSFP+/MDIO1.MDC")
			(pinfunction "10G_PHY_MDC_SCL1")
			(pintype "open_collector")
			(teardrops
				(best_length_ratio 0.2)
				(max_length 1)
				(best_width_ratio 0.9)
				(max_width 2)
				(curved_edges yes)
				(filter_ratio 0.9)
				(enabled yes)
				(allow_two_segments yes)
				(prefer_zone_connections yes)
			)
		)
		(pad "C46" smd rect
			(at -4.75 -3.125)
			(size 0.3 1.75)
			(layers "F.Cu" "F.Mask" "F.Paste")
			(net 430 "/2xSFP+/MDIO0.MDC")
			(pinfunction "10G_PHY_MDC_SCL0")
			(pintype "open_collector")
			(teardrops
				(best_length_ratio 0.2)
				(max_length 1)
				(best_width_ratio 0.9)
				(max_width 2)
				(curved_edges yes)
				(filter_ratio 0.9)
				(enabled yes)
				(allow_two_segments yes)
				(prefer_zone_connections yes)
			)
		)
		(pad "C47" smd rect
			(at -4.25 -3.125)
			(size 0.3 1.75)
			(layers "F.Cu" "F.Mask" "F.Paste")
			(net 431 "/2xSFP+/MOD0_ABS")
			(pinfunction "10G_INT0")
			(pintype "input")
			(teardrops
				(best_length_ratio 0.2)
				(max_length 1)
				(best_width_ratio 0.9)
				(max_width 2)
				(curved_edges yes)
				(filter_ratio 0.9)
				(enabled yes)
				(allow_two_segments yes)
				(prefer_zone_connections yes)
			)
		)
		(pad "C48" smd rect
			(at -3.75 -3.125)
			(size 0.3 1.75)
			(layers "F.Cu" "F.Mask" "F.Paste")
			(net 1 "GND")
			(pinfunction "GND")
			(pintype "passive")
			(teardrops
				(best_length_ratio 0.2)
				(max_length 1)
				(best_width_ratio 0.9)
				(max_width 2)
				(curved_edges yes)
				(filter_ratio 0.9)
				(enabled yes)
				(allow_two_segments yes)
				(prefer_zone_connections yes)
			)
		)
		(pad "C49" smd rect
			(at -3.25 -3.125)
			(size 0.3 1.75)
			(layers "F.Cu" "F.Mask" "F.Paste")
			(net 432 "/2xSFP+/10GKR_SFP0.RX+")
			(pinfunction "10G_KR_RX0+")
			(pintype "input")
			(teardrops
				(best_length_ratio 0.2)
				(max_length 1)
				(best_width_ratio 0.9)
				(max_width 2)
				(curved_edges yes)
				(filter_ratio 0.9)
				(enabled yes)
				(allow_two_segments yes)
				(prefer_zone_connections yes)
			)
		)
		(pad "C50" smd rect
			(at -2.75 -3.125)
			(size 0.3 1.75)
			(layers "F.Cu" "F.Mask" "F.Paste")
			(net 433 "/2xSFP+/10GKR_SFP0.RX-")
			(pinfunction "10G_KR_RX0-")
			(pintype "input")
			(teardrops
				(best_length_ratio 0.2)
				(max_length 1)
				(best_width_ratio 0.9)
				(max_width 2)
				(curved_edges yes)
				(filter_ratio 0.9)
				(enabled yes)
				(allow_two_segments yes)
				(prefer_zone_connections yes)
			)
		)
		(pad "C51" smd rect
			(at -2.25 -3.125)
			(size 0.3 1.75)
			(layers "F.Cu" "F.Mask" "F.Paste")
			(net 1 "GND")
			(pinfunction "GND(FIXED)")
			(pintype "passive")
			(teardrops
				(best_length_ratio 0.2)
				(max_length 1)
				(best_width_ratio 0.9)
				(max_width 2)
				(curved_edges yes)
				(filter_ratio 0.9)
				(enabled yes)
				(allow_two_segments yes)
				(prefer_zone_connections yes)
			)
		)
		(pad "C52" smd rect
			(at -1.75 -3.125)
			(size 0.3 1.75)
			(layers "F.Cu" "F.Mask" "F.Paste")
			(net 532 "/Backplane/PCIe_{x2}.RX0+")
			(pinfunction "PCIE_RX16+")
			(pintype "input")
			(teardrops
				(best_length_ratio 0.2)
				(max_length 1)
				(best_width_ratio 0.9)
				(max_width 2)
				(curved_edges yes)
				(filter_ratio 0.9)
				(enabled yes)
				(allow_two_segments yes)
				(prefer_zone_connections yes)
			)
		)
		(pad "C53" smd rect
			(at -1.25 -3.125)
			(size 0.3 1.75)
			(layers "F.Cu" "F.Mask" "F.Paste")
			(net 537 "/Backplane/PCIe_{x2}.RX0-")
			(pinfunction "PCIE_RX16-")
			(pintype "input")
			(teardrops
				(best_length_ratio 0.2)
				(max_length 1)
				(best_width_ratio 0.9)
				(max_width 2)
				(curved_edges yes)
				(filter_ratio 0.9)
				(enabled yes)
				(allow_two_segments yes)
				(prefer_zone_connections yes)
			)
		)
		(pad "C54" smd rect
			(at -0.75 -3.125)
			(size 0.3 1.75)
			(layers "F.Cu" "F.Mask" "F.Paste")
			(net 136 "/Com Express 7 MGMT/~{TYPE0}")
			(pinfunction "~{TYPE0}")
			(pintype "passive")
			(teardrops
				(best_length_ratio 0.2)
				(max_length 1)
				(best_width_ratio 0.9)
				(max_width 2)
				(curved_edges yes)
				(filter_ratio 0.9)
				(enabled yes)
				(allow_two_segments yes)
				(prefer_zone_connections yes)
			)
		)
		(pad "C55" smd rect
			(at -0.25 -3.125)
			(size 0.3 1.75)
			(layers "F.Cu" "F.Mask" "F.Paste")
			(net 771 "/Backplane/PCIe_{x2}.RX1+")
			(pinfunction "PCIE_RX17+")
			(pintype "input")
			(teardrops
				(best_length_ratio 0.2)
				(max_length 1)
				(best_width_ratio 0.9)
				(max_width 2)
				(curved_edges yes)
				(filter_ratio 0.9)
				(enabled yes)
				(allow_two_segments yes)
				(prefer_zone_connections yes)
			)
		)
		(pad "C56" smd rect
			(at 0.25 -3.125)
			(size 0.3 1.75)
			(layers "F.Cu" "F.Mask" "F.Paste")
			(net 772 "/Backplane/PCIe_{x2}.RX1-")
			(pinfunction "PCIE_RX17-")
			(pintype "input")
			(teardrops
				(best_length_ratio 0.2)
				(max_length 1)
				(best_width_ratio 0.9)
				(max_width 2)
				(curved_edges yes)
				(filter_ratio 0.9)
				(enabled yes)
				(allow_two_segments yes)
				(prefer_zone_connections yes)
			)
		)
		(pad "C57" smd rect
			(at 0.75 -3.125)
			(size 0.3 1.75)
			(layers "F.Cu" "F.Mask" "F.Paste")
			(net 434 "/Com Express 7 MGMT/~{TYPE1}")
			(pinfunction "~{TYPE1}")
			(pintype "passive")
			(teardrops
				(best_length_ratio 0.2)
				(max_length 1)
				(best_width_ratio 0.9)
				(max_width 2)
				(curved_edges yes)
				(filter_ratio 0.9)
				(enabled yes)
				(allow_two_segments yes)
				(prefer_zone_connections yes)
			)
		)
		(pad "C58" smd rect
			(at 1.25 -3.125)
			(size 0.3 1.75)
			(layers "F.Cu" "F.Mask" "F.Paste")
			(net 881 "unconnected-(J12N-PCIE_RX18+-PadC58)")
			(pinfunction "PCIE_RX18+")
			(pintype "input+no_connect")
			(teardrops
				(best_length_ratio 0.2)
				(max_length 1)
				(best_width_ratio 0.9)
				(max_width 2)
				(curved_edges yes)
				(filter_ratio 0.9)
				(enabled yes)
				(allow_two_segments yes)
				(prefer_zone_connections yes)
			)
		)
		(pad "C59" smd rect
			(at 1.75 -3.125)
			(size 0.3 1.75)
			(layers "F.Cu" "F.Mask" "F.Paste")
			(net 882 "unconnected-(J12N-PCIE_RX18--PadC59)")
			(pinfunction "PCIE_RX18-")
			(pintype "input+no_connect")
			(teardrops
				(best_length_ratio 0.2)
				(max_length 1)
				(best_width_ratio 0.9)
				(max_width 2)
				(curved_edges yes)
				(filter_ratio 0.9)
				(enabled yes)
				(allow_two_segments yes)
				(prefer_zone_connections yes)
			)
		)
		(pad "C60" smd rect
			(at 2.25 -3.125)
			(size 0.3 1.75)
			(layers "F.Cu" "F.Mask" "F.Paste")
			(net 1 "GND")
			(pinfunction "GND(FIXED)")
			(pintype "passive")
			(teardrops
				(best_length_ratio 0.2)
				(max_length 1)
				(best_width_ratio 0.9)
				(max_width 2)
				(curved_edges yes)
				(filter_ratio 0.9)
				(enabled yes)
				(allow_two_segments yes)
				(prefer_zone_connections yes)
			)
		)
		(pad "C61" smd rect
			(at 2.75 -3.125)
			(size 0.3 1.75)
			(layers "F.Cu" "F.Mask" "F.Paste")
			(net 883 "unconnected-(J12N-PCIE_RX19+-PadC61)")
			(pinfunction "PCIE_RX19+")
			(pintype "input+no_connect")
			(teardrops
				(best_length_ratio 0.2)
				(max_length 1)
				(best_width_ratio 0.9)
				(max_width 2)
				(curved_edges yes)
				(filter_ratio 0.9)
				(enabled yes)
				(allow_two_segments yes)
				(prefer_zone_connections yes)
			)
		)
		(pad "C62" smd rect
			(at 3.25 -3.125)
			(size 0.3 1.75)
			(layers "F.Cu" "F.Mask" "F.Paste")
			(net 884 "unconnected-(J12N-PCIE_RX19--PadC62)")
			(pinfunction "PCIE_RX19-")
			(pintype "input+no_connect")
			(teardrops
				(best_length_ratio 0.2)
				(max_length 1)
				(best_width_ratio 0.9)
				(max_width 2)
				(curved_edges yes)
				(filter_ratio 0.9)
				(enabled yes)
				(allow_two_segments yes)
				(prefer_zone_connections yes)
			)
		)
		(pad "C63" smd rect
			(at 3.75 -3.125)
			(size 0.3 1.75)
			(layers "F.Cu" "F.Mask" "F.Paste")
			(net 435 "unconnected-(J12M-RSVD-PadC63)")
			(pinfunction "RSVD")
			(pintype "no_connect")
			(teardrops
				(best_length_ratio 0.2)
				(max_length 1)
				(best_width_ratio 0.9)
				(max_width 2)
				(curved_edges yes)
				(filter_ratio 0.9)
				(enabled yes)
				(allow_two_segments yes)
				(prefer_zone_connections yes)
			)
		)
		(pad "C64" smd rect
			(at 4.25 -3.125)
			(size 0.3 1.75)
			(layers "F.Cu" "F.Mask" "F.Paste")
			(net 436 "unconnected-(J12M-RSVD-PadC64)")
			(pinfunction "RSVD")
			(pintype "no_connect")
			(teardrops
				(best_length_ratio 0.2)
				(max_length 1)
				(best_width_ratio 0.9)
				(max_width 2)
				(curved_edges yes)
				(filter_ratio 0.9)
				(enabled yes)
				(allow_two_segments yes)
				(prefer_zone_connections yes)
			)
		)
		(pad "C65" smd rect
			(at 4.75 -3.125)
			(size 0.3 1.75)
			(layers "F.Cu" "F.Mask" "F.Paste")
			(net 437 "unconnected-(J12N-PCIE_RX20+-PadC65)")
			(pinfunction "PCIE_RX20+")
			(pintype "input+no_connect")
			(teardrops
				(best_length_ratio 0.2)
				(max_length 1)
				(best_width_ratio 0.9)
				(max_width 2)
				(curved_edges yes)
				(filter_ratio 0.9)
				(enabled yes)
				(allow_two_segments yes)
				(prefer_zone_connections yes)
			)
		)
		(pad "C66" smd rect
			(at 5.25 -3.125)
			(size 0.3 1.75)
			(layers "F.Cu" "F.Mask" "F.Paste")
			(net 438 "unconnected-(J12N-PCIE_RX20--PadC66)")
			(pinfunction "PCIE_RX20-")
			(pintype "input+no_connect")
			(teardrops
				(best_length_ratio 0.2)
				(max_length 1)
				(best_width_ratio 0.9)
				(max_width 2)
				(curved_edges yes)
				(filter_ratio 0.9)
				(enabled yes)
				(allow_two_segments yes)
				(prefer_zone_connections yes)
			)
		)
		(pad "C67" smd rect
			(at 5.75 -3.125)
			(size 0.3 1.75)
			(layers "F.Cu" "F.Mask" "F.Paste")
			(net 439 "Net-(J12L-RAPID_SHUTDOWN)")
			(pinfunction "RAPID_SHUTDOWN")
			(pintype "input")
			(teardrops
				(best_length_ratio 0.2)
				(max_length 1)
				(best_width_ratio 0.9)
				(max_width 2)
				(curved_edges yes)
				(filter_ratio 0.9)
				(enabled yes)
				(allow_two_segments yes)
				(prefer_zone_connections yes)
			)
		)
		(pad "C68" smd rect
			(at 6.25 -3.125)
			(size 0.3 1.75)
			(layers "F.Cu" "F.Mask" "F.Paste")
			(net 440 "unconnected-(J12N-PCIE_RX21+-PadC68)")
			(pinfunction "PCIE_RX21+")
			(pintype "input+no_connect")
			(teardrops
				(best_length_ratio 0.2)
				(max_length 1)
				(best_width_ratio 0.9)
				(max_width 2)
				(curved_edges yes)
				(filter_ratio 0.9)
				(enabled yes)
				(allow_two_segments yes)
				(prefer_zone_connections yes)
			)
		)
		(pad "C69" smd rect
			(at 6.75 -3.125)
			(size 0.3 1.75)
			(layers "F.Cu" "F.Mask" "F.Paste")
			(net 441 "unconnected-(J12N-PCIE_RX21--PadC69)")
			(pinfunction "PCIE_RX21-")
			(pintype "input+no_connect")
			(teardrops
				(best_length_ratio 0.2)
				(max_length 1)
				(best_width_ratio 0.9)
				(max_width 2)
				(curved_edges yes)
				(filter_ratio 0.9)
				(enabled yes)
				(allow_two_segments yes)
				(prefer_zone_connections yes)
			)
		)
		(pad "C70" smd rect
			(at 7.25 -3.125)
			(size 0.3 1.75)
			(layers "F.Cu" "F.Mask" "F.Paste")
			(net 1 "GND")
			(pinfunction "GND(FIXED)")
			(pintype "passive")
			(teardrops
				(best_length_ratio 0.2)
				(max_length 1)
				(best_width_ratio 0.9)
				(max_width 2)
				(curved_edges yes)
				(filter_ratio 0.9)
				(enabled yes)
				(allow_two_segments yes)
				(prefer_zone_connections yes)
			)
		)
		(pad "C71" smd rect
			(at 7.75 -3.125)
			(size 0.3 1.75)
			(layers "F.Cu" "F.Mask" "F.Paste")
			(net 442 "unconnected-(J12N-PCIE_RX22+-PadC71)")
			(pinfunction "PCIE_RX22+")
			(pintype "input+no_connect")
			(teardrops
				(best_length_ratio 0.2)
				(max_length 1)
				(best_width_ratio 0.9)
				(max_width 2)
				(curved_edges yes)
				(filter_ratio 0.9)
				(enabled yes)
				(allow_two_segments yes)
				(prefer_zone_connections yes)
			)
		)
		(pad "C72" smd rect
			(at 8.25 -3.125)
			(size 0.3 1.75)
			(layers "F.Cu" "F.Mask" "F.Paste")
			(net 443 "unconnected-(J12N-PCIE_RX22--PadC72)")
			(pinfunction "PCIE_RX22-")
			(pintype "input+no_connect")
			(teardrops
				(best_length_ratio 0.2)
				(max_length 1)
				(best_width_ratio 0.9)
				(max_width 2)
				(curved_edges yes)
				(filter_ratio 0.9)
				(enabled yes)
				(allow_two_segments yes)
				(prefer_zone_connections yes)
			)
		)
		(pad "C73" smd rect
			(at 8.75 -3.125)
			(size 0.3 1.75)
			(layers "F.Cu" "F.Mask" "F.Paste")
			(net 1 "GND")
			(pinfunction "GND")
			(pintype "passive")
			(teardrops
				(best_length_ratio 0.2)
				(max_length 1)
				(best_width_ratio 0.9)
				(max_width 2)
				(curved_edges yes)
				(filter_ratio 0.9)
				(enabled yes)
				(allow_two_segments yes)
				(prefer_zone_connections yes)
			)
		)
		(pad "C74" smd rect
			(at 9.25 -3.125)
			(size 0.3 1.75)
			(layers "F.Cu" "F.Mask" "F.Paste")
			(net 444 "unconnected-(J12N-PCIE_RX23+-PadC74)")
			(pinfunction "PCIE_RX23+")
			(pintype "input+no_connect")
			(teardrops
				(best_length_ratio 0.2)
				(max_length 1)
				(best_width_ratio 0.9)
				(max_width 2)
				(curved_edges yes)
				(filter_ratio 0.9)
				(enabled yes)
				(allow_two_segments yes)
				(prefer_zone_connections yes)
			)
		)
		(pad "C75" smd rect
			(at 9.75 -3.125)
			(size 0.3 1.75)
			(layers "F.Cu" "F.Mask" "F.Paste")
			(net 445 "unconnected-(J12N-PCIE_RX23--PadC75)")
			(pinfunction "PCIE_RX23-")
			(pintype "input+no_connect")
			(teardrops
				(best_length_ratio 0.2)
				(max_length 1)
				(best_width_ratio 0.9)
				(max_width 2)
				(curved_edges yes)
				(filter_ratio 0.9)
				(enabled yes)
				(allow_two_segments yes)
				(prefer_zone_connections yes)
			)
		)
		(pad "C76" smd rect
			(at 10.25 -3.125)
			(size 0.3 1.75)
			(layers "F.Cu" "F.Mask" "F.Paste")
			(net 1 "GND")
			(pinfunction "GND")
			(pintype "passive")
			(teardrops
				(best_length_ratio 0.2)
				(max_length 1)
				(best_width_ratio 0.9)
				(max_width 2)
				(curved_edges yes)
				(filter_ratio 0.9)
				(enabled yes)
				(allow_two_segments yes)
				(prefer_zone_connections yes)
			)
		)
		(pad "C77" smd rect
			(at 10.75 -3.125)
			(size 0.3 1.75)
			(layers "F.Cu" "F.Mask" "F.Paste")
			(net 446 "unconnected-(J12M-RSVD-PadC77)")
			(pinfunction "RSVD")
			(pintype "no_connect")
			(teardrops
				(best_length_ratio 0.2)
				(max_length 1)
				(best_width_ratio 0.9)
				(max_width 2)
				(curved_edges yes)
				(filter_ratio 0.9)
				(enabled yes)
				(allow_two_segments yes)
				(prefer_zone_connections yes)
			)
		)
		(pad "C78" smd rect
			(at 11.25 -3.125)
			(size 0.3 1.75)
			(layers "F.Cu" "F.Mask" "F.Paste")
			(net 447 "unconnected-(J12N-PCIE_RX24+-PadC78)")
			(pinfunction "PCIE_RX24+")
			(pintype "input+no_connect")
			(teardrops
				(best_length_ratio 0.2)
				(max_length 1)
				(best_width_ratio 0.9)
				(max_width 2)
				(curved_edges yes)
				(filter_ratio 0.9)
				(enabled yes)
				(allow_two_segments yes)
				(prefer_zone_connections yes)
			)
		)
		(pad "C79" smd rect
			(at 11.75 -3.125)
			(size 0.3 1.75)
			(layers "F.Cu" "F.Mask" "F.Paste")
			(net 448 "unconnected-(J12N-PCIE_RX24--PadC79)")
			(pinfunction "PCIE_RX24-")
			(pintype "input+no_connect")
			(teardrops
				(best_length_ratio 0.2)
				(max_length 1)
				(best_width_ratio 0.9)
				(max_width 2)
				(curved_edges yes)
				(filter_ratio 0.9)
				(enabled yes)
				(allow_two_segments yes)
				(prefer_zone_connections yes)
			)
		)
		(pad "C80" smd rect
			(at 12.25 -3.125)
			(size 0.3 1.75)
			(layers "F.Cu" "F.Mask" "F.Paste")
			(net 1 "GND")
			(pinfunction "GND(FIXED)")
			(pintype "passive")
			(teardrops
				(best_length_ratio 0.2)
				(max_length 1)
				(best_width_ratio 0.9)
				(max_width 2)
				(curved_edges yes)
				(filter_ratio 0.9)
				(enabled yes)
				(allow_two_segments yes)
				(prefer_zone_connections yes)
			)
		)
		(pad "C81" smd rect
			(at 12.75 -3.125)
			(size 0.3 1.75)
			(layers "F.Cu" "F.Mask" "F.Paste")
			(net 449 "unconnected-(J12N-PCIE_RX25+-PadC81)")
			(pinfunction "PCIE_RX25+")
			(pintype "input+no_connect")
			(teardrops
				(best_length_ratio 0.2)
				(max_length 1)
				(best_width_ratio 0.9)
				(max_width 2)
				(curved_edges yes)
				(filter_ratio 0.9)
				(enabled yes)
				(allow_two_segments yes)
				(prefer_zone_connections yes)
			)
		)
		(pad "C82" smd rect
			(at 13.25 -3.125)
			(size 0.3 1.75)
			(layers "F.Cu" "F.Mask" "F.Paste")
			(net 450 "unconnected-(J12N-PCIE_RX25--PadC82)")
			(pinfunction "PCIE_RX25-")
			(pintype "input+no_connect")
			(teardrops
				(best_length_ratio 0.2)
				(max_length 1)
				(best_width_ratio 0.9)
				(max_width 2)
				(curved_edges yes)
				(filter_ratio 0.9)
				(enabled yes)
				(allow_two_segments yes)
				(prefer_zone_connections yes)
			)
		)
		(pad "C83" smd rect
			(at 13.75 -3.125)
			(size 0.3 1.75)
			(layers "F.Cu" "F.Mask" "F.Paste")
			(net 451 "unconnected-(J12M-RSVD-PadC83)")
			(pinfunction "RSVD")
			(pintype "no_connect")
			(teardrops
				(best_length_ratio 0.2)
				(max_length 1)
				(best_width_ratio 0.9)
				(max_width 2)
				(curved_edges yes)
				(filter_ratio 0.9)
				(enabled yes)
				(allow_two_segments yes)
				(prefer_zone_connections yes)
			)
		)
		(pad "C84" smd rect
			(at 14.25 -3.125)
			(size 0.3 1.75)
			(layers "F.Cu" "F.Mask" "F.Paste")
			(net 1 "GND")
			(pinfunction "GND")
			(pintype "passive")
			(teardrops
				(best_length_ratio 0.2)
				(max_length 1)
				(best_width_ratio 0.9)
				(max_width 2)
				(curved_edges yes)
				(filter_ratio 0.9)
				(enabled yes)
				(allow_two_segments yes)
				(prefer_zone_connections yes)
			)
		)
		(pad "C85" smd rect
			(at 14.75 -3.125)
			(size 0.3 1.75)
			(layers "F.Cu" "F.Mask" "F.Paste")
			(net 452 "unconnected-(J12N-PCIE_RX26+-PadC85)")
			(pinfunction "PCIE_RX26+")
			(pintype "input+no_connect")
			(teardrops
				(best_length_ratio 0.2)
				(max_length 1)
				(best_width_ratio 0.9)
				(max_width 2)
				(curved_edges yes)
				(filter_ratio 0.9)
				(enabled yes)
				(allow_two_segments yes)
				(prefer_zone_connections yes)
			)
		)
		(pad "C86" smd rect
			(at 15.25 -3.125)
			(size 0.3 1.75)
			(layers "F.Cu" "F.Mask" "F.Paste")
			(net 453 "unconnected-(J12N-PCIE_RX26--PadC86)")
			(pinfunction "PCIE_RX26-")
			(pintype "input+no_connect")
			(teardrops
				(best_length_ratio 0.2)
				(max_length 1)
				(best_width_ratio 0.9)
				(max_width 2)
				(curved_edges yes)
				(filter_ratio 0.9)
				(enabled yes)
				(allow_two_segments yes)
				(prefer_zone_connections yes)
			)
		)
		(pad "C87" smd rect
			(at 15.75 -3.125)
			(size 0.3 1.75)
			(layers "F.Cu" "F.Mask" "F.Paste")
			(net 1 "GND")
			(pinfunction "GND")
			(pintype "passive")
			(teardrops
				(best_length_ratio 0.2)
				(max_length 1)
				(best_width_ratio 0.9)
				(max_width 2)
				(curved_edges yes)
				(filter_ratio 0.9)
				(enabled yes)
				(allow_two_segments yes)
				(prefer_zone_connections yes)
			)
		)
		(pad "C88" smd rect
			(at 16.25 -3.125)
			(size 0.3 1.75)
			(layers "F.Cu" "F.Mask" "F.Paste")
			(net 454 "unconnected-(J12N-PCIE_RX27+-PadC88)")
			(pinfunction "PCIE_RX27+")
			(pintype "input+no_connect")
			(teardrops
				(best_length_ratio 0.2)
				(max_length 1)
				(best_width_ratio 0.9)
				(max_width 2)
				(curved_edges yes)
				(filter_ratio 0.9)
				(enabled yes)
				(allow_two_segments yes)
				(prefer_zone_connections yes)
			)
		)
		(pad "C89" smd rect
			(at 16.75 -3.125)
			(size 0.3 1.75)
			(layers "F.Cu" "F.Mask" "F.Paste")
			(net 455 "unconnected-(J12N-PCIE_RX27--PadC89)")
			(pinfunction "PCIE_RX27-")
			(pintype "input+no_connect")
			(teardrops
				(best_length_ratio 0.2)
				(max_length 1)
				(best_width_ratio 0.9)
				(max_width 2)
				(curved_edges yes)
				(filter_ratio 0.9)
				(enabled yes)
				(allow_two_segments yes)
				(prefer_zone_connections yes)
			)
		)
		(pad "C90" smd rect
			(at 17.25 -3.125)
			(size 0.3 1.75)
			(layers "F.Cu" "F.Mask" "F.Paste")
			(net 1 "GND")
			(pinfunction "GND(FIXED)")
			(pintype "passive")
			(teardrops
				(best_length_ratio 0.2)
				(max_length 1)
				(best_width_ratio 0.9)
				(max_width 2)
				(curved_edges yes)
				(filter_ratio 0.9)
				(enabled yes)
				(allow_two_segments yes)
				(prefer_zone_connections yes)
			)
		)
		(pad "C91" smd rect
			(at 17.75 -3.125)
			(size 0.3 1.75)
			(layers "F.Cu" "F.Mask" "F.Paste")
			(net 456 "unconnected-(J12N-PCIE_RX28+-PadC91)")
			(pinfunction "PCIE_RX28+")
			(pintype "input+no_connect")
			(teardrops
				(best_length_ratio 0.2)
				(max_length 1)
				(best_width_ratio 0.9)
				(max_width 2)
				(curved_edges yes)
				(filter_ratio 0.9)
				(enabled yes)
				(allow_two_segments yes)
				(prefer_zone_connections yes)
			)
		)
		(pad "C92" smd rect
			(at 18.25 -3.125)
			(size 0.3 1.75)
			(layers "F.Cu" "F.Mask" "F.Paste")
			(net 457 "unconnected-(J12N-PCIE_RX28--PadC92)")
			(pinfunction "PCIE_RX28-")
			(pintype "input+no_connect")
			(teardrops
				(best_length_ratio 0.2)
				(max_length 1)
				(best_width_ratio 0.9)
				(max_width 2)
				(curved_edges yes)
				(filter_ratio 0.9)
				(enabled yes)
				(allow_two_segments yes)
				(prefer_zone_connections yes)
			)
		)
		(pad "C93" smd rect
			(at 18.75 -3.125)
			(size 0.3 1.75)
			(layers "F.Cu" "F.Mask" "F.Paste")
			(net 1 "GND")
			(pinfunction "GND")
			(pintype "passive")
			(teardrops
				(best_length_ratio 0.2)
				(max_length 1)
				(best_width_ratio 0.9)
				(max_width 2)
				(curved_edges yes)
				(filter_ratio 0.9)
				(enabled yes)
				(allow_two_segments yes)
				(prefer_zone_connections yes)
			)
		)
		(pad "C94" smd rect
			(at 19.25 -3.125)
			(size 0.3 1.75)
			(layers "F.Cu" "F.Mask" "F.Paste")
			(net 458 "unconnected-(J12N-PCIE_RX29+-PadC94)")
			(pinfunction "PCIE_RX29+")
			(pintype "input+no_connect")
			(teardrops
				(best_length_ratio 0.2)
				(max_length 1)
				(best_width_ratio 0.9)
				(max_width 2)
				(curved_edges yes)
				(filter_ratio 0.9)
				(enabled yes)
				(allow_two_segments yes)
				(prefer_zone_connections yes)
			)
		)
		(pad "C95" smd rect
			(at 19.75 -3.125)
			(size 0.3 1.75)
			(layers "F.Cu" "F.Mask" "F.Paste")
			(net 459 "unconnected-(J12N-PCIE_RX29--PadC95)")
			(pinfunction "PCIE_RX29-")
			(pintype "input+no_connect")
			(teardrops
				(best_length_ratio 0.2)
				(max_length 1)
				(best_width_ratio 0.9)
				(max_width 2)
				(curved_edges yes)
				(filter_ratio 0.9)
				(enabled yes)
				(allow_two_segments yes)
				(prefer_zone_connections yes)
			)
		)
		(pad "C96" smd rect
			(at 20.25 -3.125)
			(size 0.3 1.75)
			(layers "F.Cu" "F.Mask" "F.Paste")
			(net 1 "GND")
			(pinfunction "GND")
			(pintype "passive")
			(teardrops
				(best_length_ratio 0.2)
				(max_length 1)
				(best_width_ratio 0.9)
				(max_width 2)
				(curved_edges yes)
				(filter_ratio 0.9)
				(enabled yes)
				(allow_two_segments yes)
				(prefer_zone_connections yes)
			)
		)
		(pad "C97" smd rect
			(at 20.75 -3.125)
			(size 0.3 1.75)
			(layers "F.Cu" "F.Mask" "F.Paste")
			(net 460 "unconnected-(J12M-RSVD-PadC97)")
			(pinfunction "RSVD")
			(pintype "no_connect")
			(teardrops
				(best_length_ratio 0.2)
				(max_length 1)
				(best_width_ratio 0.9)
				(max_width 2)
				(curved_edges yes)
				(filter_ratio 0.9)
				(enabled yes)
				(allow_two_segments yes)
				(prefer_zone_connections yes)
			)
		)
		(pad "C98" smd rect
			(at 21.25 -3.125)
			(size 0.3 1.75)
			(layers "F.Cu" "F.Mask" "F.Paste")
			(net 461 "unconnected-(J12N-PCIE_RX30+-PadC98)")
			(pinfunction "PCIE_RX30+")
			(pintype "input+no_connect")
			(teardrops
				(best_length_ratio 0.2)
				(max_length 1)
				(best_width_ratio 0.9)
				(max_width 2)
				(curved_edges yes)
				(filter_ratio 0.9)
				(enabled yes)
				(allow_two_segments yes)
				(prefer_zone_connections yes)
			)
		)
		(pad "C99" smd rect
			(at 21.75 -3.125)
			(size 0.3 1.75)
			(layers "F.Cu" "F.Mask" "F.Paste")
			(net 462 "unconnected-(J12N-PCIE_RX30--PadC99)")
			(pinfunction "PCIE_RX30-")
			(pintype "input+no_connect")
			(teardrops
				(best_length_ratio 0.2)
				(max_length 1)
				(best_width_ratio 0.9)
				(max_width 2)
				(curved_edges yes)
				(filter_ratio 0.9)
				(enabled yes)
				(allow_two_segments yes)
				(prefer_zone_connections yes)
			)
		)
		(pad "C100" smd rect
			(at 22.25 -3.125)
			(size 0.3 1.75)
			(layers "F.Cu" "F.Mask" "F.Paste")
			(net 1 "GND")
			(pinfunction "GND(FIXED)")
			(pintype "passive")
			(teardrops
				(best_length_ratio 0.2)
				(max_length 1)
				(best_width_ratio 0.9)
				(max_width 2)
				(curved_edges yes)
				(filter_ratio 0.9)
				(enabled yes)
				(allow_two_segments yes)
				(prefer_zone_connections yes)
			)
		)
		(pad "C101" smd rect
			(at 22.75 -3.125)
			(size 0.3 1.75)
			(layers "F.Cu" "F.Mask" "F.Paste")
			(net 463 "unconnected-(J12N-PCIE_RX31+-PadC101)")
			(pinfunction "PCIE_RX31+")
			(pintype "input+no_connect")
			(teardrops
				(best_length_ratio 0.2)
				(max_length 1)
				(best_width_ratio 0.9)
				(max_width 2)
				(curved_edges yes)
				(filter_ratio 0.9)
				(enabled yes)
				(allow_two_segments yes)
				(prefer_zone_connections yes)
			)
		)
		(pad "C102" smd rect
			(at 23.25 -3.125)
			(size 0.3 1.75)
			(layers "F.Cu" "F.Mask" "F.Paste")
			(net 464 "unconnected-(J12N-PCIE_RX31--PadC102)")
			(pinfunction "PCIE_RX31-")
			(pintype "input+no_connect")
			(teardrops
				(best_length_ratio 0.2)
				(max_length 1)
				(best_width_ratio 0.9)
				(max_width 2)
				(curved_edges yes)
				(filter_ratio 0.9)
				(enabled yes)
				(allow_two_segments yes)
				(prefer_zone_connections yes)
			)
		)
		(pad "C103" smd rect
			(at 23.75 -3.125)
			(size 0.3 1.75)
			(layers "F.Cu" "F.Mask" "F.Paste")
			(net 1 "GND")
			(pinfunction "GND")
			(pintype "power_in")
			(teardrops
				(best_length_ratio 0.2)
				(max_length 1)
				(best_width_ratio 0.9)
				(max_width 2)
				(curved_edges yes)
				(filter_ratio 0.9)
				(enabled yes)
				(allow_two_segments yes)
				(prefer_zone_connections yes)
			)
		)
		(pad "C104" smd rect
			(at 24.25 -3.125)
			(size 0.3 1.75)
			(layers "F.Cu" "F.Mask" "F.Paste")
			(net 65 "+12V")
			(pinfunction "VCC_12V")
			(pintype "power_in")
			(teardrops
				(best_length_ratio 0.2)
				(max_length 1)
				(best_width_ratio 0.9)
				(max_width 2)
				(curved_edges yes)
				(filter_ratio 0.9)
				(enabled yes)
				(allow_two_segments yes)
				(prefer_zone_connections yes)
			)
		)
		(pad "C105" smd rect
			(at 24.75 -3.125)
			(size 0.3 1.75)
			(layers "F.Cu" "F.Mask" "F.Paste")
			(net 65 "+12V")
			(pinfunction "VCC_12V")
			(pintype "passive")
			(teardrops
				(best_length_ratio 0.2)
				(max_length 1)
				(best_width_ratio 0.9)
				(max_width 2)
				(curved_edges yes)
				(filter_ratio 0.9)
				(enabled yes)
				(allow_two_segments yes)
				(prefer_zone_connections yes)
			)
		)
		(pad "C106" smd rect
			(at 25.25 -3.125)
			(size 0.3 1.75)
			(layers "F.Cu" "F.Mask" "F.Paste")
			(net 65 "+12V")
			(pinfunction "VCC_12V")
			(pintype "passive")
			(teardrops
				(best_length_ratio 0.2)
				(max_length 1)
				(best_width_ratio 0.9)
				(max_width 2)
				(curved_edges yes)
				(filter_ratio 0.9)
				(enabled yes)
				(allow_two_segments yes)
				(prefer_zone_connections yes)
			)
		)
		(pad "C107" smd rect
			(at 25.75 -3.125)
			(size 0.3 1.75)
			(layers "F.Cu" "F.Mask" "F.Paste")
			(net 65 "+12V")
			(pinfunction "VCC_12V")
			(pintype "passive")
			(teardrops
				(best_length_ratio 0.2)
				(max_length 1)
				(best_width_ratio 0.9)
				(max_width 2)
				(curved_edges yes)
				(filter_ratio 0.9)
				(enabled yes)
				(allow_two_segments yes)
				(prefer_zone_connections yes)
			)
		)
		(pad "C108" smd rect
			(at 26.25 -3.125)
			(size 0.3 1.75)
			(layers "F.Cu" "F.Mask" "F.Paste")
			(net 65 "+12V")
			(pinfunction "VCC_12V")
			(pintype "passive")
			(teardrops
				(best_length_ratio 0.2)
				(max_length 1)
				(best_width_ratio 0.9)
				(max_width 2)
				(curved_edges yes)
				(filter_ratio 0.9)
				(enabled yes)
				(allow_two_segments yes)
				(prefer_zone_connections yes)
			)
		)
		(pad "C109" smd rect
			(at 26.75 -3.125)
			(size 0.3 1.75)
			(layers "F.Cu" "F.Mask" "F.Paste")
			(net 65 "+12V")
			(pinfunction "VCC_12V")
			(pintype "passive")
			(teardrops
				(best_length_ratio 0.2)
				(max_length 1)
				(best_width_ratio 0.9)
				(max_width 2)
				(curved_edges yes)
				(filter_ratio 0.9)
				(enabled yes)
				(allow_two_segments yes)
				(prefer_zone_connections yes)
			)
		)
		(pad "C110" smd rect
			(at 27.25 -3.125)
			(size 0.3 1.75)
			(layers "F.Cu" "F.Mask" "F.Paste")
			(net 1 "GND")
			(pinfunction "GND(FIXED)")
			(pintype "passive")
			(teardrops
				(best_length_ratio 0.2)
				(max_length 1)
				(best_width_ratio 0.9)
				(max_width 2)
				(curved_edges yes)
				(filter_ratio 0.9)
				(enabled yes)
				(allow_two_segments yes)
				(prefer_zone_connections yes)
			)
		)
		(pad "D1" smd rect
			(at -27.25 -8.675)
			(size 0.3 1.75)
			(layers "F.Cu" "F.Mask" "F.Paste")
			(net 1 "GND")
			(pinfunction "GND(FIXED)")
			(pintype "passive")
			(teardrops
				(best_length_ratio 0.2)
				(max_length 1)
				(best_width_ratio 0.9)
				(max_width 2)
				(curved_edges yes)
				(filter_ratio 0.9)
				(enabled yes)
				(allow_two_segments yes)
				(prefer_zone_connections yes)
			)
		)
		(pad "D2" smd rect
			(at -26.75 -8.675)
			(size 0.3 1.75)
			(layers "F.Cu" "F.Mask" "F.Paste")
			(net 1 "GND")
			(pinfunction "GND")
			(pintype "passive")
			(teardrops
				(best_length_ratio 0.2)
				(max_length 1)
				(best_width_ratio 0.9)
				(max_width 2)
				(curved_edges yes)
				(filter_ratio 0.9)
				(enabled yes)
				(allow_two_segments yes)
				(prefer_zone_connections yes)
			)
		)
		(pad "D3" smd rect
			(at -26.25 -8.675)
			(size 0.3 1.75)
			(layers "F.Cu" "F.Mask" "F.Paste")
			(net 465 "unconnected-(J12J-USB_SSTX0--PadD3)")
			(pinfunction "USB_SSTX0-")
			(pintype "output+no_connect")
			(teardrops
				(best_length_ratio 0.2)
				(max_length 1)
				(best_width_ratio 0.9)
				(max_width 2)
				(curved_edges yes)
				(filter_ratio 0.9)
				(enabled yes)
				(allow_two_segments yes)
				(prefer_zone_connections yes)
			)
		)
		(pad "D4" smd rect
			(at -25.75 -8.675)
			(size 0.3 1.75)
			(layers "F.Cu" "F.Mask" "F.Paste")
			(net 466 "unconnected-(J12J-USB_SSTX0+-PadD4)")
			(pinfunction "USB_SSTX0+")
			(pintype "output+no_connect")
			(teardrops
				(best_length_ratio 0.2)
				(max_length 1)
				(best_width_ratio 0.9)
				(max_width 2)
				(curved_edges yes)
				(filter_ratio 0.9)
				(enabled yes)
				(allow_two_segments yes)
				(prefer_zone_connections yes)
			)
		)
		(pad "D5" smd rect
			(at -25.25 -8.675)
			(size 0.3 1.75)
			(layers "F.Cu" "F.Mask" "F.Paste")
			(net 1 "GND")
			(pinfunction "GND")
			(pintype "passive")
			(teardrops
				(best_length_ratio 0.2)
				(max_length 1)
				(best_width_ratio 0.9)
				(max_width 2)
				(curved_edges yes)
				(filter_ratio 0.9)
				(enabled yes)
				(allow_two_segments yes)
				(prefer_zone_connections yes)
			)
		)
		(pad "D6" smd rect
			(at -24.75 -8.675)
			(size 0.3 1.75)
			(layers "F.Cu" "F.Mask" "F.Paste")
			(net 467 "unconnected-(J12J-USB_SSTX1--PadD6)")
			(pinfunction "USB_SSTX1-")
			(pintype "output+no_connect")
			(teardrops
				(best_length_ratio 0.2)
				(max_length 1)
				(best_width_ratio 0.9)
				(max_width 2)
				(curved_edges yes)
				(filter_ratio 0.9)
				(enabled yes)
				(allow_two_segments yes)
				(prefer_zone_connections yes)
			)
		)
		(pad "D7" smd rect
			(at -24.25 -8.675)
			(size 0.3 1.75)
			(layers "F.Cu" "F.Mask" "F.Paste")
			(net 468 "unconnected-(J12J-USB_SSTX1+-PadD7)")
			(pinfunction "USB_SSTX1+")
			(pintype "output+no_connect")
			(teardrops
				(best_length_ratio 0.2)
				(max_length 1)
				(best_width_ratio 0.9)
				(max_width 2)
				(curved_edges yes)
				(filter_ratio 0.9)
				(enabled yes)
				(allow_two_segments yes)
				(prefer_zone_connections yes)
			)
		)
		(pad "D8" smd rect
			(at -23.75 -8.675)
			(size 0.3 1.75)
			(layers "F.Cu" "F.Mask" "F.Paste")
			(net 1 "GND")
			(pinfunction "GND")
			(pintype "passive")
			(teardrops
				(best_length_ratio 0.2)
				(max_length 1)
				(best_width_ratio 0.9)
				(max_width 2)
				(curved_edges yes)
				(filter_ratio 0.9)
				(enabled yes)
				(allow_two_segments yes)
				(prefer_zone_connections yes)
			)
		)
		(pad "D9" smd rect
			(at -23.25 -8.675)
			(size 0.3 1.75)
			(layers "F.Cu" "F.Mask" "F.Paste")
			(net 47 "/2xUSB3.0+RJ45/USBSS_1.TX-")
			(pinfunction "USB_SSTX2-")
			(pintype "output")
			(teardrops
				(best_length_ratio 0.2)
				(max_length 1)
				(best_width_ratio 0.9)
				(max_width 2)
				(curved_edges yes)
				(filter_ratio 0.9)
				(enabled yes)
				(allow_two_segments yes)
				(prefer_zone_connections yes)
			)
		)
		(pad "D10" smd rect
			(at -22.75 -8.675)
			(size 0.3 1.75)
			(layers "F.Cu" "F.Mask" "F.Paste")
			(net 44 "/2xUSB3.0+RJ45/USBSS_1.TX+")
			(pinfunction "USB_SSTX2+")
			(pintype "output")
			(teardrops
				(best_length_ratio 0.2)
				(max_length 1)
				(best_width_ratio 0.9)
				(max_width 2)
				(curved_edges yes)
				(filter_ratio 0.9)
				(enabled yes)
				(allow_two_segments yes)
				(prefer_zone_connections yes)
			)
		)
		(pad "D11" smd rect
			(at -22.25 -8.675)
			(size 0.3 1.75)
			(layers "F.Cu" "F.Mask" "F.Paste")
			(net 1 "GND")
			(pinfunction "GND(FIXED)")
			(pintype "passive")
			(teardrops
				(best_length_ratio 0.2)
				(max_length 1)
				(best_width_ratio 0.9)
				(max_width 2)
				(curved_edges yes)
				(filter_ratio 0.9)
				(enabled yes)
				(allow_two_segments yes)
				(prefer_zone_connections yes)
			)
		)
		(pad "D12" smd rect
			(at -21.75 -8.675)
			(size 0.3 1.75)
			(layers "F.Cu" "F.Mask" "F.Paste")
			(net 49 "/2xUSB3.0+RJ45/USBSS_2.TX-")
			(pinfunction "USB_SSTX3-")
			(pintype "output")
			(teardrops
				(best_length_ratio 0.2)
				(max_length 1)
				(best_width_ratio 0.9)
				(max_width 2)
				(curved_edges yes)
				(filter_ratio 0.9)
				(enabled yes)
				(allow_two_segments yes)
				(prefer_zone_connections yes)
			)
		)
		(pad "D13" smd rect
			(at -21.25 -8.675)
			(size 0.3 1.75)
			(layers "F.Cu" "F.Mask" "F.Paste")
			(net 45 "/2xUSB3.0+RJ45/USBSS_2.TX+")
			(pinfunction "USB_SSTX3+")
			(pintype "output")
			(teardrops
				(best_length_ratio 0.2)
				(max_length 1)
				(best_width_ratio 0.9)
				(max_width 2)
				(curved_edges yes)
				(filter_ratio 0.9)
				(enabled yes)
				(allow_two_segments yes)
				(prefer_zone_connections yes)
			)
		)
		(pad "D14" smd rect
			(at -20.75 -8.675)
			(size 0.3 1.75)
			(layers "F.Cu" "F.Mask" "F.Paste")
			(net 1 "GND")
			(pinfunction "GND")
			(pintype "passive")
			(teardrops
				(best_length_ratio 0.2)
				(max_length 1)
				(best_width_ratio 0.9)
				(max_width 2)
				(curved_edges yes)
				(filter_ratio 0.9)
				(enabled yes)
				(allow_two_segments yes)
				(prefer_zone_connections yes)
			)
		)
		(pad "D15" smd rect
			(at -20.25 -8.675)
			(size 0.3 1.75)
			(layers "F.Cu" "F.Mask" "F.Paste")
			(net 469 "unconnected-(J12K-10G_PHY_MDIO_SDA3-PadD15)")
			(pinfunction "10G_PHY_MDIO_SDA3")
			(pintype "open_collector+no_connect")
			(teardrops
				(best_length_ratio 0.2)
				(max_length 1)
				(best_width_ratio 0.9)
				(max_width 2)
				(curved_edges yes)
				(filter_ratio 0.9)
				(enabled yes)
				(allow_two_segments yes)
				(prefer_zone_connections yes)
			)
		)
		(pad "D16" smd rect
			(at -19.75 -8.675)
			(size 0.3 1.75)
			(layers "F.Cu" "F.Mask" "F.Paste")
			(net 470 "unconnected-(J12K-10G_PHY_MDIO_SDA2-PadD16)")
			(pinfunction "10G_PHY_MDIO_SDA2")
			(pintype "open_collector+no_connect")
			(teardrops
				(best_length_ratio 0.2)
				(max_length 1)
				(best_width_ratio 0.9)
				(max_width 2)
				(curved_edges yes)
				(filter_ratio 0.9)
				(enabled yes)
				(allow_two_segments yes)
				(prefer_zone_connections yes)
			)
		)
		(pad "D17" smd rect
			(at -19.25 -8.675)
			(size 0.3 1.75)
			(layers "F.Cu" "F.Mask" "F.Paste")
			(net 471 "Net-(J12K-10G_SDP3)")
			(pinfunction "10G_SDP3")
			(pintype "bidirectional")
			(teardrops
				(best_length_ratio 0.2)
				(max_length 1)
				(best_width_ratio 0.9)
				(max_width 2)
				(curved_edges yes)
				(filter_ratio 0.9)
				(enabled yes)
				(allow_two_segments yes)
				(prefer_zone_connections yes)
			)
		)
		(pad "D18" smd rect
			(at -18.75 -8.675)
			(size 0.3 1.75)
			(layers "F.Cu" "F.Mask" "F.Paste")
			(net 1 "GND")
			(pinfunction "GND")
			(pintype "passive")
			(teardrops
				(best_length_ratio 0.2)
				(max_length 1)
				(best_width_ratio 0.9)
				(max_width 2)
				(curved_edges yes)
				(filter_ratio 0.9)
				(enabled yes)
				(allow_two_segments yes)
				(prefer_zone_connections yes)
			)
		)
		(pad "D19" smd rect
			(at -18.25 -8.675)
			(size 0.3 1.75)
			(layers "F.Cu" "F.Mask" "F.Paste")
			(net 472 "unconnected-(J12O-PCIE_TX6+-PadD19)")
			(pinfunction "PCIE_TX6+")
			(pintype "output+no_connect")
			(teardrops
				(best_length_ratio 0.2)
				(max_length 1)
				(best_width_ratio 0.9)
				(max_width 2)
				(curved_edges yes)
				(filter_ratio 0.9)
				(enabled yes)
				(allow_two_segments yes)
				(prefer_zone_connections yes)
			)
		)
		(pad "D20" smd rect
			(at -17.75 -8.675)
			(size 0.3 1.75)
			(layers "F.Cu" "F.Mask" "F.Paste")
			(net 473 "unconnected-(J12O-PCIE_TX6--PadD20)")
			(pinfunction "PCIE_TX6-")
			(pintype "output+no_connect")
			(teardrops
				(best_length_ratio 0.2)
				(max_length 1)
				(best_width_ratio 0.9)
				(max_width 2)
				(curved_edges yes)
				(filter_ratio 0.9)
				(enabled yes)
				(allow_two_segments yes)
				(prefer_zone_connections yes)
			)
		)
		(pad "D21" smd rect
			(at -17.25 -8.675)
			(size 0.3 1.75)
			(layers "F.Cu" "F.Mask" "F.Paste")
			(net 1 "GND")
			(pinfunction "GND(FIXED)")
			(pintype "passive")
			(teardrops
				(best_length_ratio 0.2)
				(max_length 1)
				(best_width_ratio 0.9)
				(max_width 2)
				(curved_edges yes)
				(filter_ratio 0.9)
				(enabled yes)
				(allow_two_segments yes)
				(prefer_zone_connections yes)
			)
		)
		(pad "D22" smd rect
			(at -16.75 -8.675)
			(size 0.3 1.75)
			(layers "F.Cu" "F.Mask" "F.Paste")
			(net 474 "unconnected-(J12O-PCIE_TX7+-PadD22)")
			(pinfunction "PCIE_TX7+")
			(pintype "output+no_connect")
			(teardrops
				(best_length_ratio 0.2)
				(max_length 1)
				(best_width_ratio 0.9)
				(max_width 2)
				(curved_edges yes)
				(filter_ratio 0.9)
				(enabled yes)
				(allow_two_segments yes)
				(prefer_zone_connections yes)
			)
		)
		(pad "D23" smd rect
			(at -16.25 -8.675)
			(size 0.3 1.75)
			(layers "F.Cu" "F.Mask" "F.Paste")
			(net 475 "unconnected-(J12O-PCIE_TX7--PadD23)")
			(pinfunction "PCIE_TX7-")
			(pintype "output+no_connect")
			(teardrops
				(best_length_ratio 0.2)
				(max_length 1)
				(best_width_ratio 0.9)
				(max_width 2)
				(curved_edges yes)
				(filter_ratio 0.9)
				(enabled yes)
				(allow_two_segments yes)
				(prefer_zone_connections yes)
			)
		)
		(pad "D24" smd rect
			(at -15.75 -8.675)
			(size 0.3 1.75)
			(layers "F.Cu" "F.Mask" "F.Paste")
			(net 476 "unconnected-(J12K-10G_INT3-PadD24)")
			(pinfunction "10G_INT3")
			(pintype "input+no_connect")
			(teardrops
				(best_length_ratio 0.2)
				(max_length 1)
				(best_width_ratio 0.9)
				(max_width 2)
				(curved_edges yes)
				(filter_ratio 0.9)
				(enabled yes)
				(allow_two_segments yes)
				(prefer_zone_connections yes)
			)
		)
		(pad "D25" smd rect
			(at -15.25 -8.675)
			(size 0.3 1.75)
			(layers "F.Cu" "F.Mask" "F.Paste")
			(net 1 "GND")
			(pinfunction "GND")
			(pintype "passive")
			(teardrops
				(best_length_ratio 0.2)
				(max_length 1)
				(best_width_ratio 0.9)
				(max_width 2)
				(curved_edges yes)
				(filter_ratio 0.9)
				(enabled yes)
				(allow_two_segments yes)
				(prefer_zone_connections yes)
			)
		)
		(pad "D26" smd rect
			(at -14.75 -8.675)
			(size 0.3 1.75)
			(layers "F.Cu" "F.Mask" "F.Paste")
			(net 477 "unconnected-(J12K-10G_KR_TX3+-PadD26)")
			(pinfunction "10G_KR_TX3+")
			(pintype "output+no_connect")
			(teardrops
				(best_length_ratio 0.2)
				(max_length 1)
				(best_width_ratio 0.9)
				(max_width 2)
				(curved_edges yes)
				(filter_ratio 0.9)
				(enabled yes)
				(allow_two_segments yes)
				(prefer_zone_connections yes)
			)
		)
		(pad "D27" smd rect
			(at -14.25 -8.675)
			(size 0.3 1.75)
			(layers "F.Cu" "F.Mask" "F.Paste")
			(net 478 "unconnected-(J12K-10G_KR_TX3--PadD27)")
			(pinfunction "10G_KR_TX3-")
			(pintype "output+no_connect")
			(teardrops
				(best_length_ratio 0.2)
				(max_length 1)
				(best_width_ratio 0.9)
				(max_width 2)
				(curved_edges yes)
				(filter_ratio 0.9)
				(enabled yes)
				(allow_two_segments yes)
				(prefer_zone_connections yes)
			)
		)
		(pad "D28" smd rect
			(at -13.75 -8.675)
			(size 0.3 1.75)
			(layers "F.Cu" "F.Mask" "F.Paste")
			(net 1 "GND")
			(pinfunction "GND")
			(pintype "passive")
			(teardrops
				(best_length_ratio 0.2)
				(max_length 1)
				(best_width_ratio 0.9)
				(max_width 2)
				(curved_edges yes)
				(filter_ratio 0.9)
				(enabled yes)
				(allow_two_segments yes)
				(prefer_zone_connections yes)
			)
		)
		(pad "D29" smd rect
			(at -13.25 -8.675)
			(size 0.3 1.75)
			(layers "F.Cu" "F.Mask" "F.Paste")
			(net 479 "unconnected-(J12K-10G_KR_TX2+-PadD29)")
			(pinfunction "10G_KR_TX2+")
			(pintype "output+no_connect")
			(teardrops
				(best_length_ratio 0.2)
				(max_length 1)
				(best_width_ratio 0.9)
				(max_width 2)
				(curved_edges yes)
				(filter_ratio 0.9)
				(enabled yes)
				(allow_two_segments yes)
				(prefer_zone_connections yes)
			)
		)
		(pad "D30" smd rect
			(at -12.75 -8.675)
			(size 0.3 1.75)
			(layers "F.Cu" "F.Mask" "F.Paste")
			(net 480 "unconnected-(J12K-10G_KR_TX2--PadD30)")
			(pinfunction "10G_KR_TX2-")
			(pintype "output+no_connect")
			(teardrops
				(best_length_ratio 0.2)
				(max_length 1)
				(best_width_ratio 0.9)
				(max_width 2)
				(curved_edges yes)
				(filter_ratio 0.9)
				(enabled yes)
				(allow_two_segments yes)
				(prefer_zone_connections yes)
			)
		)
		(pad "D31" smd rect
			(at -12.25 -8.675)
			(size 0.3 1.75)
			(layers "F.Cu" "F.Mask" "F.Paste")
			(net 1 "GND")
			(pinfunction "GND(FIXED)")
			(pintype "passive")
			(teardrops
				(best_length_ratio 0.2)
				(max_length 1)
				(best_width_ratio 0.9)
				(max_width 2)
				(curved_edges yes)
				(filter_ratio 0.9)
				(enabled yes)
				(allow_two_segments yes)
				(prefer_zone_connections yes)
			)
		)
		(pad "D32" smd rect
			(at -11.75 -8.675)
			(size 0.3 1.75)
			(layers "F.Cu" "F.Mask" "F.Paste")
			(net 481 "unconnected-(J12K-10G_SFP_SCL3-PadD32)")
			(pinfunction "10G_SFP_SCL3")
			(pintype "open_collector+no_connect")
			(teardrops
				(best_length_ratio 0.2)
				(max_length 1)
				(best_width_ratio 0.9)
				(max_width 2)
				(curved_edges yes)
				(filter_ratio 0.9)
				(enabled yes)
				(allow_two_segments yes)
				(prefer_zone_connections yes)
			)
		)
		(pad "D33" smd rect
			(at -11.25 -8.675)
			(size 0.3 1.75)
			(layers "F.Cu" "F.Mask" "F.Paste")
			(net 482 "unconnected-(J12K-10G_SFP_SCL2-PadD33)")
			(pinfunction "10G_SFP_SCL2")
			(pintype "open_collector+no_connect")
			(teardrops
				(best_length_ratio 0.2)
				(max_length 1)
				(best_width_ratio 0.9)
				(max_width 2)
				(curved_edges yes)
				(filter_ratio 0.9)
				(enabled yes)
				(allow_two_segments yes)
				(prefer_zone_connections yes)
			)
		)
		(pad "D34" smd rect
			(at -10.75 -8.675)
			(size 0.3 1.75)
			(layers "F.Cu" "F.Mask" "F.Paste")
			(net 483 "unconnected-(J12K-10G_PHY_CAP_23-PadD34)")
			(pinfunction "10G_PHY_CAP_23")
			(pintype "input+no_connect")
			(teardrops
				(best_length_ratio 0.2)
				(max_length 1)
				(best_width_ratio 0.9)
				(max_width 2)
				(curved_edges yes)
				(filter_ratio 0.9)
				(enabled yes)
				(allow_two_segments yes)
				(prefer_zone_connections yes)
			)
		)
		(pad "D35" smd rect
			(at -10.25 -8.675)
			(size 0.3 1.75)
			(layers "F.Cu" "F.Mask" "F.Paste")
			(net 484 "Net-(J12K-10G_PHY_CAP_01)")
			(pinfunction "10G_PHY_CAP_01")
			(pintype "input")
			(teardrops
				(best_length_ratio 0.2)
				(max_length 1)
				(best_width_ratio 0.9)
				(max_width 2)
				(curved_edges yes)
				(filter_ratio 0.9)
				(enabled yes)
				(allow_two_segments yes)
				(prefer_zone_connections yes)
			)
		)
		(pad "D36" smd rect
			(at -9.75 -8.675)
			(size 0.3 1.75)
			(layers "F.Cu" "F.Mask" "F.Paste")
			(net 485 "unconnected-(J12M-RSVD-PadD36)")
			(pinfunction "RSVD")
			(pintype "no_connect")
			(teardrops
				(best_length_ratio 0.2)
				(max_length 1)
				(best_width_ratio 0.9)
				(max_width 2)
				(curved_edges yes)
				(filter_ratio 0.9)
				(enabled yes)
				(allow_two_segments yes)
				(prefer_zone_connections yes)
			)
		)
		(pad "D37" smd rect
			(at -9.25 -8.675)
			(size 0.3 1.75)
			(layers "F.Cu" "F.Mask" "F.Paste")
			(net 486 "unconnected-(J12M-RSVD-PadD37)")
			(pinfunction "RSVD")
			(pintype "no_connect")
			(teardrops
				(best_length_ratio 0.2)
				(max_length 1)
				(best_width_ratio 0.9)
				(max_width 2)
				(curved_edges yes)
				(filter_ratio 0.9)
				(enabled yes)
				(allow_two_segments yes)
				(prefer_zone_connections yes)
			)
		)
		(pad "D38" smd rect
			(at -8.75 -8.675)
			(size 0.3 1.75)
			(layers "F.Cu" "F.Mask" "F.Paste")
			(net 487 "/2xSFP+/I2C_{SFP1}.SCL")
			(pinfunction "10G_SFP_SCL1")
			(pintype "open_collector")
			(teardrops
				(best_length_ratio 0.2)
				(max_length 1)
				(best_width_ratio 0.9)
				(max_width 2)
				(curved_edges yes)
				(filter_ratio 0.9)
				(enabled yes)
				(allow_two_segments yes)
				(prefer_zone_connections yes)
			)
		)
		(pad "D39" smd rect
			(at -8.25 -8.675)
			(size 0.3 1.75)
			(layers "F.Cu" "F.Mask" "F.Paste")
			(net 488 "/2xSFP+/I2C_{SFP0}.SCL")
			(pinfunction "10G_SFP_SCL0")
			(pintype "open_collector")
			(teardrops
				(best_length_ratio 0.2)
				(max_length 1)
				(best_width_ratio 0.9)
				(max_width 2)
				(curved_edges yes)
				(filter_ratio 0.9)
				(enabled yes)
				(allow_two_segments yes)
				(prefer_zone_connections yes)
			)
		)
		(pad "D40" smd rect
			(at -7.75 -8.675)
			(size 0.3 1.75)
			(layers "F.Cu" "F.Mask" "F.Paste")
			(net 489 "Net-(J12K-10G_SDP1)")
			(pinfunction "10G_SDP1")
			(pintype "bidirectional")
			(teardrops
				(best_length_ratio 0.2)
				(max_length 1)
				(best_width_ratio 0.9)
				(max_width 2)
				(curved_edges yes)
				(filter_ratio 0.9)
				(enabled yes)
				(allow_two_segments yes)
				(prefer_zone_connections yes)
			)
		)
		(pad "D41" smd rect
			(at -7.25 -8.675)
			(size 0.3 1.75)
			(layers "F.Cu" "F.Mask" "F.Paste")
			(net 1 "GND")
			(pinfunction "GND(FIXED)")
			(pintype "passive")
			(teardrops
				(best_length_ratio 0.2)
				(max_length 1)
				(best_width_ratio 0.9)
				(max_width 2)
				(curved_edges yes)
				(filter_ratio 0.9)
				(enabled yes)
				(allow_two_segments yes)
				(prefer_zone_connections yes)
			)
		)
		(pad "D42" smd rect
			(at -6.75 -8.675)
			(size 0.3 1.75)
			(layers "F.Cu" "F.Mask" "F.Paste")
			(net 119 "/2xSFP+/10GKR_SFP1.TX+")
			(pinfunction "10G_KR_TX1+")
			(pintype "output")
			(teardrops
				(best_length_ratio 0.2)
				(max_length 1)
				(best_width_ratio 0.9)
				(max_width 2)
				(curved_edges yes)
				(filter_ratio 0.9)
				(enabled yes)
				(allow_two_segments yes)
				(prefer_zone_connections yes)
			)
		)
		(pad "D43" smd rect
			(at -6.25 -8.675)
			(size 0.3 1.75)
			(layers "F.Cu" "F.Mask" "F.Paste")
			(net 121 "/2xSFP+/10GKR_SFP1.TX-")
			(pinfunction "10G_KR_TX1-")
			(pintype "output")
			(teardrops
				(best_length_ratio 0.2)
				(max_length 1)
				(best_width_ratio 0.9)
				(max_width 2)
				(curved_edges yes)
				(filter_ratio 0.9)
				(enabled yes)
				(allow_two_segments yes)
				(prefer_zone_connections yes)
			)
		)
		(pad "D44" smd rect
			(at -5.75 -8.675)
			(size 0.3 1.75)
			(layers "F.Cu" "F.Mask" "F.Paste")
			(net 1 "GND")
			(pinfunction "GND")
			(pintype "passive")
			(teardrops
				(best_length_ratio 0.2)
				(max_length 1)
				(best_width_ratio 0.9)
				(max_width 2)
				(curved_edges yes)
				(filter_ratio 0.9)
				(enabled yes)
				(allow_two_segments yes)
				(prefer_zone_connections yes)
			)
		)
		(pad "D45" smd rect
			(at -5.25 -8.675)
			(size 0.3 1.75)
			(layers "F.Cu" "F.Mask" "F.Paste")
			(net 490 "/2xSFP+/MDIO1.MDIO")
			(pinfunction "10G_PHY_MDIO_SDA1")
			(pintype "open_collector")
			(teardrops
				(best_length_ratio 0.2)
				(max_length 1)
				(best_width_ratio 0.9)
				(max_width 2)
				(curved_edges yes)
				(filter_ratio 0.9)
				(enabled yes)
				(allow_two_segments yes)
				(prefer_zone_connections yes)
			)
		)
		(pad "D46" smd rect
			(at -4.75 -8.675)
			(size 0.3 1.75)
			(layers "F.Cu" "F.Mask" "F.Paste")
			(net 491 "/2xSFP+/MDIO0.MDIO")
			(pinfunction "10G_PHY_MDIO_SDA0")
			(pintype "open_collector")
			(teardrops
				(best_length_ratio 0.2)
				(max_length 1)
				(best_width_ratio 0.9)
				(max_width 2)
				(curved_edges yes)
				(filter_ratio 0.9)
				(enabled yes)
				(allow_two_segments yes)
				(prefer_zone_connections yes)
			)
		)
		(pad "D47" smd rect
			(at -4.25 -8.675)
			(size 0.3 1.75)
			(layers "F.Cu" "F.Mask" "F.Paste")
			(net 492 "/2xSFP+/MOD1_ABS")
			(pinfunction "10G_INT1")
			(pintype "input")
			(teardrops
				(best_length_ratio 0.2)
				(max_length 1)
				(best_width_ratio 0.9)
				(max_width 2)
				(curved_edges yes)
				(filter_ratio 0.9)
				(enabled yes)
				(allow_two_segments yes)
				(prefer_zone_connections yes)
			)
		)
		(pad "D48" smd rect
			(at -3.75 -8.675)
			(size 0.3 1.75)
			(layers "F.Cu" "F.Mask" "F.Paste")
			(net 1 "GND")
			(pinfunction "GND")
			(pintype "passive")
			(teardrops
				(best_length_ratio 0.2)
				(max_length 1)
				(best_width_ratio 0.9)
				(max_width 2)
				(curved_edges yes)
				(filter_ratio 0.9)
				(enabled yes)
				(allow_two_segments yes)
				(prefer_zone_connections yes)
			)
		)
		(pad "D49" smd rect
			(at -3.25 -8.675)
			(size 0.3 1.75)
			(layers "F.Cu" "F.Mask" "F.Paste")
			(net 111 "/2xSFP+/10GKR_SFP0.TX+")
			(pinfunction "10G_KR_TX0+")
			(pintype "output")
			(teardrops
				(best_length_ratio 0.2)
				(max_length 1)
				(best_width_ratio 0.9)
				(max_width 2)
				(curved_edges yes)
				(filter_ratio 0.9)
				(enabled yes)
				(allow_two_segments yes)
				(prefer_zone_connections yes)
			)
		)
		(pad "D50" smd rect
			(at -2.75 -8.675)
			(size 0.3 1.75)
			(layers "F.Cu" "F.Mask" "F.Paste")
			(net 113 "/2xSFP+/10GKR_SFP0.TX-")
			(pinfunction "10G_KR_TX0-")
			(pintype "output")
			(teardrops
				(best_length_ratio 0.2)
				(max_length 1)
				(best_width_ratio 0.9)
				(max_width 2)
				(curved_edges yes)
				(filter_ratio 0.9)
				(enabled yes)
				(allow_two_segments yes)
				(prefer_zone_connections yes)
			)
		)
		(pad "D51" smd rect
			(at -2.25 -8.675)
			(size 0.3 1.75)
			(layers "F.Cu" "F.Mask" "F.Paste")
			(net 1 "GND")
			(pinfunction "GND(FIXED)")
			(pintype "passive")
			(teardrops
				(best_length_ratio 0.2)
				(max_length 1)
				(best_width_ratio 0.9)
				(max_width 2)
				(curved_edges yes)
				(filter_ratio 0.9)
				(enabled yes)
				(allow_two_segments yes)
				(prefer_zone_connections yes)
			)
		)
		(pad "D52" smd rect
			(at -1.75 -8.675)
			(size 0.3 1.75)
			(layers "F.Cu" "F.Mask" "F.Paste")
			(net 866 "/Backplane/PCIe_{x2}.TX0+")
			(pinfunction "PCIE_TX16+")
			(pintype "output")
			(teardrops
				(best_length_ratio 0.2)
				(max_length 1)
				(best_width_ratio 0.9)
				(max_width 2)
				(curved_edges yes)
				(filter_ratio 0.9)
				(enabled yes)
				(allow_two_segments yes)
				(prefer_zone_connections yes)
			)
		)
		(pad "D53" smd rect
			(at -1.25 -8.675)
			(size 0.3 1.75)
			(layers "F.Cu" "F.Mask" "F.Paste")
			(net 867 "/Backplane/PCIe_{x2}.TX0-")
			(pinfunction "PCIE_TX16-")
			(pintype "output")
			(teardrops
				(best_length_ratio 0.2)
				(max_length 1)
				(best_width_ratio 0.9)
				(max_width 2)
				(curved_edges yes)
				(filter_ratio 0.9)
				(enabled yes)
				(allow_two_segments yes)
				(prefer_zone_connections yes)
			)
		)
		(pad "D54" smd rect
			(at -0.75 -8.675)
			(size 0.3 1.75)
			(layers "F.Cu" "F.Mask" "F.Paste")
			(net 493 "unconnected-(J12M-RSVD-PadD54)")
			(pinfunction "RSVD")
			(pintype "no_connect")
			(teardrops
				(best_length_ratio 0.2)
				(max_length 1)
				(best_width_ratio 0.9)
				(max_width 2)
				(curved_edges yes)
				(filter_ratio 0.9)
				(enabled yes)
				(allow_two_segments yes)
				(prefer_zone_connections yes)
			)
		)
		(pad "D55" smd rect
			(at -0.25 -8.675)
			(size 0.3 1.75)
			(layers "F.Cu" "F.Mask" "F.Paste")
			(net 868 "/Backplane/PCIe_{x2}.TX1+")
			(pinfunction "PCIE_TX17+")
			(pintype "output")
			(teardrops
				(best_length_ratio 0.2)
				(max_length 1)
				(best_width_ratio 0.9)
				(max_width 2)
				(curved_edges yes)
				(filter_ratio 0.9)
				(enabled yes)
				(allow_two_segments yes)
				(prefer_zone_connections yes)
			)
		)
		(pad "D56" smd rect
			(at 0.25 -8.675)
			(size 0.3 1.75)
			(layers "F.Cu" "F.Mask" "F.Paste")
			(net 869 "/Backplane/PCIe_{x2}.TX1-")
			(pinfunction "PCIE_TX17-")
			(pintype "output")
			(teardrops
				(best_length_ratio 0.2)
				(max_length 1)
				(best_width_ratio 0.9)
				(max_width 2)
				(curved_edges yes)
				(filter_ratio 0.9)
				(enabled yes)
				(allow_two_segments yes)
				(prefer_zone_connections yes)
			)
		)
		(pad "D57" smd rect
			(at 0.75 -8.675)
			(size 0.3 1.75)
			(layers "F.Cu" "F.Mask" "F.Paste")
			(net 137 "/Com Express 7 MGMT/~{TYPE2}")
			(pinfunction "~{TYPE2}")
			(pintype "passive")
			(teardrops
				(best_length_ratio 0.2)
				(max_length 1)
				(best_width_ratio 0.9)
				(max_width 2)
				(curved_edges yes)
				(filter_ratio 0.9)
				(enabled yes)
				(allow_two_segments yes)
				(prefer_zone_connections yes)
			)
		)
		(pad "D58" smd rect
			(at 1.25 -8.675)
			(size 0.3 1.75)
			(layers "F.Cu" "F.Mask" "F.Paste")
			(net 885 "unconnected-(J12N-PCIE_TX18+-PadD58)")
			(pinfunction "PCIE_TX18+")
			(pintype "output+no_connect")
			(teardrops
				(best_length_ratio 0.2)
				(max_length 1)
				(best_width_ratio 0.9)
				(max_width 2)
				(curved_edges yes)
				(filter_ratio 0.9)
				(enabled yes)
				(allow_two_segments yes)
				(prefer_zone_connections yes)
			)
		)
		(pad "D59" smd rect
			(at 1.75 -8.675)
			(size 0.3 1.75)
			(layers "F.Cu" "F.Mask" "F.Paste")
			(net 886 "unconnected-(J12N-PCIE_TX18--PadD59)")
			(pinfunction "PCIE_TX18-")
			(pintype "output+no_connect")
			(teardrops
				(best_length_ratio 0.2)
				(max_length 1)
				(best_width_ratio 0.9)
				(max_width 2)
				(curved_edges yes)
				(filter_ratio 0.9)
				(enabled yes)
				(allow_two_segments yes)
				(prefer_zone_connections yes)
			)
		)
		(pad "D60" smd rect
			(at 2.25 -8.675)
			(size 0.3 1.75)
			(layers "F.Cu" "F.Mask" "F.Paste")
			(net 1 "GND")
			(pinfunction "GND(FIXED)")
			(pintype "passive")
			(teardrops
				(best_length_ratio 0.2)
				(max_length 1)
				(best_width_ratio 0.9)
				(max_width 2)
				(curved_edges yes)
				(filter_ratio 0.9)
				(enabled yes)
				(allow_two_segments yes)
				(prefer_zone_connections yes)
			)
		)
		(pad "D61" smd rect
			(at 2.75 -8.675)
			(size 0.3 1.75)
			(layers "F.Cu" "F.Mask" "F.Paste")
			(net 887 "unconnected-(J12N-PCIE_TX19+-PadD61)")
			(pinfunction "PCIE_TX19+")
			(pintype "output+no_connect")
			(teardrops
				(best_length_ratio 0.2)
				(max_length 1)
				(best_width_ratio 0.9)
				(max_width 2)
				(curved_edges yes)
				(filter_ratio 0.9)
				(enabled yes)
				(allow_two_segments yes)
				(prefer_zone_connections yes)
			)
		)
		(pad "D62" smd rect
			(at 3.25 -8.675)
			(size 0.3 1.75)
			(layers "F.Cu" "F.Mask" "F.Paste")
			(net 888 "unconnected-(J12N-PCIE_TX19--PadD62)")
			(pinfunction "PCIE_TX19-")
			(pintype "output+no_connect")
			(teardrops
				(best_length_ratio 0.2)
				(max_length 1)
				(best_width_ratio 0.9)
				(max_width 2)
				(curved_edges yes)
				(filter_ratio 0.9)
				(enabled yes)
				(allow_two_segments yes)
				(prefer_zone_connections yes)
			)
		)
		(pad "D63" smd rect
			(at 3.75 -8.675)
			(size 0.3 1.75)
			(layers "F.Cu" "F.Mask" "F.Paste")
			(net 494 "unconnected-(J12M-RSVD-PadD63)")
			(pinfunction "RSVD")
			(pintype "no_connect")
			(teardrops
				(best_length_ratio 0.2)
				(max_length 1)
				(best_width_ratio 0.9)
				(max_width 2)
				(curved_edges yes)
				(filter_ratio 0.9)
				(enabled yes)
				(allow_two_segments yes)
				(prefer_zone_connections yes)
			)
		)
		(pad "D64" smd rect
			(at 4.25 -8.675)
			(size 0.3 1.75)
			(layers "F.Cu" "F.Mask" "F.Paste")
			(net 495 "unconnected-(J12M-RSVD-PadD64)")
			(pinfunction "RSVD")
			(pintype "no_connect")
			(teardrops
				(best_length_ratio 0.2)
				(max_length 1)
				(best_width_ratio 0.9)
				(max_width 2)
				(curved_edges yes)
				(filter_ratio 0.9)
				(enabled yes)
				(allow_two_segments yes)
				(prefer_zone_connections yes)
			)
		)
		(pad "D65" smd rect
			(at 4.75 -8.675)
			(size 0.3 1.75)
			(layers "F.Cu" "F.Mask" "F.Paste")
			(net 496 "unconnected-(J12N-PCIE_TX20+-PadD65)")
			(pinfunction "PCIE_TX20+")
			(pintype "output+no_connect")
			(teardrops
				(best_length_ratio 0.2)
				(max_length 1)
				(best_width_ratio 0.9)
				(max_width 2)
				(curved_edges yes)
				(filter_ratio 0.9)
				(enabled yes)
				(allow_two_segments yes)
				(prefer_zone_connections yes)
			)
		)
		(pad "D66" smd rect
			(at 5.25 -8.675)
			(size 0.3 1.75)
			(layers "F.Cu" "F.Mask" "F.Paste")
			(net 497 "unconnected-(J12N-PCIE_TX20--PadD66)")
			(pinfunction "PCIE_TX20-")
			(pintype "output+no_connect")
			(teardrops
				(best_length_ratio 0.2)
				(max_length 1)
				(best_width_ratio 0.9)
				(max_width 2)
				(curved_edges yes)
				(filter_ratio 0.9)
				(enabled yes)
				(allow_two_segments yes)
				(prefer_zone_connections yes)
			)
		)
		(pad "D67" smd rect
			(at 5.75 -8.675)
			(size 0.3 1.75)
			(layers "F.Cu" "F.Mask" "F.Paste")
			(net 1 "GND")
			(pinfunction "GND")
			(pintype "passive")
			(teardrops
				(best_length_ratio 0.2)
				(max_length 1)
				(best_width_ratio 0.9)
				(max_width 2)
				(curved_edges yes)
				(filter_ratio 0.9)
				(enabled yes)
				(allow_two_segments yes)
				(prefer_zone_connections yes)
			)
		)
		(pad "D68" smd rect
			(at 6.25 -8.675)
			(size 0.3 1.75)
			(layers "F.Cu" "F.Mask" "F.Paste")
			(net 498 "unconnected-(J12N-PCIE_TX21+-PadD68)")
			(pinfunction "PCIE_TX21+")
			(pintype "output+no_connect")
			(teardrops
				(best_length_ratio 0.2)
				(max_length 1)
				(best_width_ratio 0.9)
				(max_width 2)
				(curved_edges yes)
				(filter_ratio 0.9)
				(enabled yes)
				(allow_two_segments yes)
				(prefer_zone_connections yes)
			)
		)
		(pad "D69" smd rect
			(at 6.75 -8.675)
			(size 0.3 1.75)
			(layers "F.Cu" "F.Mask" "F.Paste")
			(net 499 "unconnected-(J12N-PCIE_TX21--PadD69)")
			(pinfunction "PCIE_TX21-")
			(pintype "output+no_connect")
			(teardrops
				(best_length_ratio 0.2)
				(max_length 1)
				(best_width_ratio 0.9)
				(max_width 2)
				(curved_edges yes)
				(filter_ratio 0.9)
				(enabled yes)
				(allow_two_segments yes)
				(prefer_zone_connections yes)
			)
		)
		(pad "D70" smd rect
			(at 7.25 -8.675)
			(size 0.3 1.75)
			(layers "F.Cu" "F.Mask" "F.Paste")
			(net 1 "GND")
			(pinfunction "GND(FIXED)")
			(pintype "passive")
			(teardrops
				(best_length_ratio 0.2)
				(max_length 1)
				(best_width_ratio 0.9)
				(max_width 2)
				(curved_edges yes)
				(filter_ratio 0.9)
				(enabled yes)
				(allow_two_segments yes)
				(prefer_zone_connections yes)
			)
		)
		(pad "D71" smd rect
			(at 7.75 -8.675)
			(size 0.3 1.75)
			(layers "F.Cu" "F.Mask" "F.Paste")
			(net 500 "unconnected-(J12N-PCIE_TX22+-PadD71)")
			(pinfunction "PCIE_TX22+")
			(pintype "output+no_connect")
			(teardrops
				(best_length_ratio 0.2)
				(max_length 1)
				(best_width_ratio 0.9)
				(max_width 2)
				(curved_edges yes)
				(filter_ratio 0.9)
				(enabled yes)
				(allow_two_segments yes)
				(prefer_zone_connections yes)
			)
		)
		(pad "D72" smd rect
			(at 8.25 -8.675)
			(size 0.3 1.75)
			(layers "F.Cu" "F.Mask" "F.Paste")
			(net 501 "unconnected-(J12N-PCIE_TX22--PadD72)")
			(pinfunction "PCIE_TX22-")
			(pintype "output+no_connect")
			(teardrops
				(best_length_ratio 0.2)
				(max_length 1)
				(best_width_ratio 0.9)
				(max_width 2)
				(curved_edges yes)
				(filter_ratio 0.9)
				(enabled yes)
				(allow_two_segments yes)
				(prefer_zone_connections yes)
			)
		)
		(pad "D73" smd rect
			(at 8.75 -8.675)
			(size 0.3 1.75)
			(layers "F.Cu" "F.Mask" "F.Paste")
			(net 1 "GND")
			(pinfunction "GND")
			(pintype "passive")
			(teardrops
				(best_length_ratio 0.2)
				(max_length 1)
				(best_width_ratio 0.9)
				(max_width 2)
				(curved_edges yes)
				(filter_ratio 0.9)
				(enabled yes)
				(allow_two_segments yes)
				(prefer_zone_connections yes)
			)
		)
		(pad "D74" smd rect
			(at 9.25 -8.675)
			(size 0.3 1.75)
			(layers "F.Cu" "F.Mask" "F.Paste")
			(net 502 "unconnected-(J12N-PCIE_TX23+-PadD74)")
			(pinfunction "PCIE_TX23+")
			(pintype "output+no_connect")
			(teardrops
				(best_length_ratio 0.2)
				(max_length 1)
				(best_width_ratio 0.9)
				(max_width 2)
				(curved_edges yes)
				(filter_ratio 0.9)
				(enabled yes)
				(allow_two_segments yes)
				(prefer_zone_connections yes)
			)
		)
		(pad "D75" smd rect
			(at 9.75 -8.675)
			(size 0.3 1.75)
			(layers "F.Cu" "F.Mask" "F.Paste")
			(net 503 "unconnected-(J12N-PCIE_TX23--PadD75)")
			(pinfunction "PCIE_TX23-")
			(pintype "output+no_connect")
			(teardrops
				(best_length_ratio 0.2)
				(max_length 1)
				(best_width_ratio 0.9)
				(max_width 2)
				(curved_edges yes)
				(filter_ratio 0.9)
				(enabled yes)
				(allow_two_segments yes)
				(prefer_zone_connections yes)
			)
		)
		(pad "D76" smd rect
			(at 10.25 -8.675)
			(size 0.3 1.75)
			(layers "F.Cu" "F.Mask" "F.Paste")
			(net 1 "GND")
			(pinfunction "GND")
			(pintype "passive")
			(teardrops
				(best_length_ratio 0.2)
				(max_length 1)
				(best_width_ratio 0.9)
				(max_width 2)
				(curved_edges yes)
				(filter_ratio 0.9)
				(enabled yes)
				(allow_two_segments yes)
				(prefer_zone_connections yes)
			)
		)
		(pad "D77" smd rect
			(at 10.75 -8.675)
			(size 0.3 1.75)
			(layers "F.Cu" "F.Mask" "F.Paste")
			(net 504 "unconnected-(J12M-RSVD-PadD77)")
			(pinfunction "RSVD")
			(pintype "no_connect")
			(teardrops
				(best_length_ratio 0.2)
				(max_length 1)
				(best_width_ratio 0.9)
				(max_width 2)
				(curved_edges yes)
				(filter_ratio 0.9)
				(enabled yes)
				(allow_two_segments yes)
				(prefer_zone_connections yes)
			)
		)
		(pad "D78" smd rect
			(at 11.25 -8.675)
			(size 0.3 1.75)
			(layers "F.Cu" "F.Mask" "F.Paste")
			(net 505 "unconnected-(J12N-PCIE_TX24+-PadD78)")
			(pinfunction "PCIE_TX24+")
			(pintype "output+no_connect")
			(teardrops
				(best_length_ratio 0.2)
				(max_length 1)
				(best_width_ratio 0.9)
				(max_width 2)
				(curved_edges yes)
				(filter_ratio 0.9)
				(enabled yes)
				(allow_two_segments yes)
				(prefer_zone_connections yes)
			)
		)
		(pad "D79" smd rect
			(at 11.75 -8.675)
			(size 0.3 1.75)
			(layers "F.Cu" "F.Mask" "F.Paste")
			(net 506 "unconnected-(J12N-PCIE_TX24--PadD79)")
			(pinfunction "PCIE_TX24-")
			(pintype "output+no_connect")
			(teardrops
				(best_length_ratio 0.2)
				(max_length 1)
				(best_width_ratio 0.9)
				(max_width 2)
				(curved_edges yes)
				(filter_ratio 0.9)
				(enabled yes)
				(allow_two_segments yes)
				(prefer_zone_connections yes)
			)
		)
		(pad "D80" smd rect
			(at 12.25 -8.675)
			(size 0.3 1.75)
			(layers "F.Cu" "F.Mask" "F.Paste")
			(net 1 "GND")
			(pinfunction "GND(FIXED)")
			(pintype "passive")
			(teardrops
				(best_length_ratio 0.2)
				(max_length 1)
				(best_width_ratio 0.9)
				(max_width 2)
				(curved_edges yes)
				(filter_ratio 0.9)
				(enabled yes)
				(allow_two_segments yes)
				(prefer_zone_connections yes)
			)
		)
		(pad "D81" smd rect
			(at 12.75 -8.675)
			(size 0.3 1.75)
			(layers "F.Cu" "F.Mask" "F.Paste")
			(net 507 "unconnected-(J12N-PCIE_TX25+-PadD81)")
			(pinfunction "PCIE_TX25+")
			(pintype "output+no_connect")
			(teardrops
				(best_length_ratio 0.2)
				(max_length 1)
				(best_width_ratio 0.9)
				(max_width 2)
				(curved_edges yes)
				(filter_ratio 0.9)
				(enabled yes)
				(allow_two_segments yes)
				(prefer_zone_connections yes)
			)
		)
		(pad "D82" smd rect
			(at 13.25 -8.675)
			(size 0.3 1.75)
			(layers "F.Cu" "F.Mask" "F.Paste")
			(net 508 "unconnected-(J12N-PCIE_TX25--PadD82)")
			(pinfunction "PCIE_TX25-")
			(pintype "output+no_connect")
			(teardrops
				(best_length_ratio 0.2)
				(max_length 1)
				(best_width_ratio 0.9)
				(max_width 2)
				(curved_edges yes)
				(filter_ratio 0.9)
				(enabled yes)
				(allow_two_segments yes)
				(prefer_zone_connections yes)
			)
		)
		(pad "D83" smd rect
			(at 13.75 -8.675)
			(size 0.3 1.75)
			(layers "F.Cu" "F.Mask" "F.Paste")
			(net 509 "unconnected-(J12M-RSVD-PadD83)")
			(pinfunction "RSVD")
			(pintype "no_connect")
			(teardrops
				(best_length_ratio 0.2)
				(max_length 1)
				(best_width_ratio 0.9)
				(max_width 2)
				(curved_edges yes)
				(filter_ratio 0.9)
				(enabled yes)
				(allow_two_segments yes)
				(prefer_zone_connections yes)
			)
		)
		(pad "D84" smd rect
			(at 14.25 -8.675)
			(size 0.3 1.75)
			(layers "F.Cu" "F.Mask" "F.Paste")
			(net 1 "GND")
			(pinfunction "GND")
			(pintype "passive")
			(teardrops
				(best_length_ratio 0.2)
				(max_length 1)
				(best_width_ratio 0.9)
				(max_width 2)
				(curved_edges yes)
				(filter_ratio 0.9)
				(enabled yes)
				(allow_two_segments yes)
				(prefer_zone_connections yes)
			)
		)
		(pad "D85" smd rect
			(at 14.75 -8.675)
			(size 0.3 1.75)
			(layers "F.Cu" "F.Mask" "F.Paste")
			(net 510 "unconnected-(J12N-PCIE_TX26+-PadD85)")
			(pinfunction "PCIE_TX26+")
			(pintype "output+no_connect")
			(teardrops
				(best_length_ratio 0.2)
				(max_length 1)
				(best_width_ratio 0.9)
				(max_width 2)
				(curved_edges yes)
				(filter_ratio 0.9)
				(enabled yes)
				(allow_two_segments yes)
				(prefer_zone_connections yes)
			)
		)
		(pad "D86" smd rect
			(at 15.25 -8.675)
			(size 0.3 1.75)
			(layers "F.Cu" "F.Mask" "F.Paste")
			(net 511 "unconnected-(J12N-PCIE_TX26--PadD86)")
			(pinfunction "PCIE_TX26-")
			(pintype "output+no_connect")
			(teardrops
				(best_length_ratio 0.2)
				(max_length 1)
				(best_width_ratio 0.9)
				(max_width 2)
				(curved_edges yes)
				(filter_ratio 0.9)
				(enabled yes)
				(allow_two_segments yes)
				(prefer_zone_connections yes)
			)
		)
		(pad "D87" smd rect
			(at 15.75 -8.675)
			(size 0.3 1.75)
			(layers "F.Cu" "F.Mask" "F.Paste")
			(net 1 "GND")
			(pinfunction "GND")
			(pintype "passive")
			(teardrops
				(best_length_ratio 0.2)
				(max_length 1)
				(best_width_ratio 0.9)
				(max_width 2)
				(curved_edges yes)
				(filter_ratio 0.9)
				(enabled yes)
				(allow_two_segments yes)
				(prefer_zone_connections yes)
			)
		)
		(pad "D88" smd rect
			(at 16.25 -8.675)
			(size 0.3 1.75)
			(layers "F.Cu" "F.Mask" "F.Paste")
			(net 512 "unconnected-(J12N-PCIE_TX27+-PadD88)")
			(pinfunction "PCIE_TX27+")
			(pintype "output+no_connect")
			(teardrops
				(best_length_ratio 0.2)
				(max_length 1)
				(best_width_ratio 0.9)
				(max_width 2)
				(curved_edges yes)
				(filter_ratio 0.9)
				(enabled yes)
				(allow_two_segments yes)
				(prefer_zone_connections yes)
			)
		)
		(pad "D89" smd rect
			(at 16.75 -8.675)
			(size 0.3 1.75)
			(layers "F.Cu" "F.Mask" "F.Paste")
			(net 513 "unconnected-(J12N-PCIE_TX27--PadD89)")
			(pinfunction "PCIE_TX27-")
			(pintype "output+no_connect")
			(teardrops
				(best_length_ratio 0.2)
				(max_length 1)
				(best_width_ratio 0.9)
				(max_width 2)
				(curved_edges yes)
				(filter_ratio 0.9)
				(enabled yes)
				(allow_two_segments yes)
				(prefer_zone_connections yes)
			)
		)
		(pad "D90" smd rect
			(at 17.25 -8.675)
			(size 0.3 1.75)
			(layers "F.Cu" "F.Mask" "F.Paste")
			(net 1 "GND")
			(pinfunction "GND(FIXED)")
			(pintype "passive")
			(teardrops
				(best_length_ratio 0.2)
				(max_length 1)
				(best_width_ratio 0.9)
				(max_width 2)
				(curved_edges yes)
				(filter_ratio 0.9)
				(enabled yes)
				(allow_two_segments yes)
				(prefer_zone_connections yes)
			)
		)
		(pad "D91" smd rect
			(at 17.75 -8.675)
			(size 0.3 1.75)
			(layers "F.Cu" "F.Mask" "F.Paste")
			(net 514 "unconnected-(J12N-PCIE_TX28+-PadD91)")
			(pinfunction "PCIE_TX28+")
			(pintype "output+no_connect")
			(teardrops
				(best_length_ratio 0.2)
				(max_length 1)
				(best_width_ratio 0.9)
				(max_width 2)
				(curved_edges yes)
				(filter_ratio 0.9)
				(enabled yes)
				(allow_two_segments yes)
				(prefer_zone_connections yes)
			)
		)
		(pad "D92" smd rect
			(at 18.25 -8.675)
			(size 0.3 1.75)
			(layers "F.Cu" "F.Mask" "F.Paste")
			(net 515 "unconnected-(J12N-PCIE_TX28--PadD92)")
			(pinfunction "PCIE_TX28-")
			(pintype "output+no_connect")
			(teardrops
				(best_length_ratio 0.2)
				(max_length 1)
				(best_width_ratio 0.9)
				(max_width 2)
				(curved_edges yes)
				(filter_ratio 0.9)
				(enabled yes)
				(allow_two_segments yes)
				(prefer_zone_connections yes)
			)
		)
		(pad "D93" smd rect
			(at 18.75 -8.675)
			(size 0.3 1.75)
			(layers "F.Cu" "F.Mask" "F.Paste")
			(net 1 "GND")
			(pinfunction "GND")
			(pintype "passive")
			(teardrops
				(best_length_ratio 0.2)
				(max_length 1)
				(best_width_ratio 0.9)
				(max_width 2)
				(curved_edges yes)
				(filter_ratio 0.9)
				(enabled yes)
				(allow_two_segments yes)
				(prefer_zone_connections yes)
			)
		)
		(pad "D94" smd rect
			(at 19.25 -8.675)
			(size 0.3 1.75)
			(layers "F.Cu" "F.Mask" "F.Paste")
			(net 516 "unconnected-(J12N-PCIE_TX29+-PadD94)")
			(pinfunction "PCIE_TX29+")
			(pintype "output+no_connect")
			(teardrops
				(best_length_ratio 0.2)
				(max_length 1)
				(best_width_ratio 0.9)
				(max_width 2)
				(curved_edges yes)
				(filter_ratio 0.9)
				(enabled yes)
				(allow_two_segments yes)
				(prefer_zone_connections yes)
			)
		)
		(pad "D95" smd rect
			(at 19.75 -8.675)
			(size 0.3 1.75)
			(layers "F.Cu" "F.Mask" "F.Paste")
			(net 517 "unconnected-(J12N-PCIE_TX29--PadD95)")
			(pinfunction "PCIE_TX29-")
			(pintype "output+no_connect")
			(teardrops
				(best_length_ratio 0.2)
				(max_length 1)
				(best_width_ratio 0.9)
				(max_width 2)
				(curved_edges yes)
				(filter_ratio 0.9)
				(enabled yes)
				(allow_two_segments yes)
				(prefer_zone_connections yes)
			)
		)
		(pad "D96" smd rect
			(at 20.25 -8.675)
			(size 0.3 1.75)
			(layers "F.Cu" "F.Mask" "F.Paste")
			(net 1 "GND")
			(pinfunction "GND")
			(pintype "passive")
			(teardrops
				(best_length_ratio 0.2)
				(max_length 1)
				(best_width_ratio 0.9)
				(max_width 2)
				(curved_edges yes)
				(filter_ratio 0.9)
				(enabled yes)
				(allow_two_segments yes)
				(prefer_zone_connections yes)
			)
		)
		(pad "D97" smd rect
			(at 20.75 -8.675)
			(size 0.3 1.75)
			(layers "F.Cu" "F.Mask" "F.Paste")
			(net 518 "unconnected-(J12M-RSVD-PadD97)")
			(pinfunction "RSVD")
			(pintype "no_connect")
			(teardrops
				(best_length_ratio 0.2)
				(max_length 1)
				(best_width_ratio 0.9)
				(max_width 2)
				(curved_edges yes)
				(filter_ratio 0.9)
				(enabled yes)
				(allow_two_segments yes)
				(prefer_zone_connections yes)
			)
		)
		(pad "D98" smd rect
			(at 21.25 -8.675)
			(size 0.3 1.75)
			(layers "F.Cu" "F.Mask" "F.Paste")
			(net 519 "unconnected-(J12N-PCIE_TX30+-PadD98)")
			(pinfunction "PCIE_TX30+")
			(pintype "output+no_connect")
			(teardrops
				(best_length_ratio 0.2)
				(max_length 1)
				(best_width_ratio 0.9)
				(max_width 2)
				(curved_edges yes)
				(filter_ratio 0.9)
				(enabled yes)
				(allow_two_segments yes)
				(prefer_zone_connections yes)
			)
		)
		(pad "D99" smd rect
			(at 21.75 -8.675)
			(size 0.3 1.75)
			(layers "F.Cu" "F.Mask" "F.Paste")
			(net 520 "unconnected-(J12N-PCIE_TX30--PadD99)")
			(pinfunction "PCIE_TX30-")
			(pintype "output+no_connect")
			(teardrops
				(best_length_ratio 0.2)
				(max_length 1)
				(best_width_ratio 0.9)
				(max_width 2)
				(curved_edges yes)
				(filter_ratio 0.9)
				(enabled yes)
				(allow_two_segments yes)
				(prefer_zone_connections yes)
			)
		)
		(pad "D100" smd rect
			(at 22.25 -8.675)
			(size 0.3 1.75)
			(layers "F.Cu" "F.Mask" "F.Paste")
			(net 1 "GND")
			(pinfunction "GND(FIXED)")
			(pintype "passive")
			(teardrops
				(best_length_ratio 0.2)
				(max_length 1)
				(best_width_ratio 0.9)
				(max_width 2)
				(curved_edges yes)
				(filter_ratio 0.9)
				(enabled yes)
				(allow_two_segments yes)
				(prefer_zone_connections yes)
			)
		)
		(pad "D101" smd rect
			(at 22.75 -8.675)
			(size 0.3 1.75)
			(layers "F.Cu" "F.Mask" "F.Paste")
			(net 521 "unconnected-(J12N-PCIE_TX31+-PadD101)")
			(pinfunction "PCIE_TX31+")
			(pintype "output+no_connect")
			(teardrops
				(best_length_ratio 0.2)
				(max_length 1)
				(best_width_ratio 0.9)
				(max_width 2)
				(curved_edges yes)
				(filter_ratio 0.9)
				(enabled yes)
				(allow_two_segments yes)
				(prefer_zone_connections yes)
			)
		)
		(pad "D102" smd rect
			(at 23.25 -8.675)
			(size 0.3 1.75)
			(layers "F.Cu" "F.Mask" "F.Paste")
			(net 522 "unconnected-(J12N-PCIE_TX31--PadD102)")
			(pinfunction "PCIE_TX31-")
			(pintype "output+no_connect")
			(teardrops
				(best_length_ratio 0.2)
				(max_length 1)
				(best_width_ratio 0.9)
				(max_width 2)
				(curved_edges yes)
				(filter_ratio 0.9)
				(enabled yes)
				(allow_two_segments yes)
				(prefer_zone_connections yes)
			)
		)
		(pad "D103" smd rect
			(at 23.75 -8.675)
			(size 0.3 1.75)
			(layers "F.Cu" "F.Mask" "F.Paste")
			(net 1 "GND")
			(pinfunction "GND")
			(pintype "passive")
			(teardrops
				(best_length_ratio 0.2)
				(max_length 1)
				(best_width_ratio 0.9)
				(max_width 2)
				(curved_edges yes)
				(filter_ratio 0.9)
				(enabled yes)
				(allow_two_segments yes)
				(prefer_zone_connections yes)
			)
		)
		(pad "D104" smd rect
			(at 24.25 -8.675)
			(size 0.3 1.75)
			(layers "F.Cu" "F.Mask" "F.Paste")
			(net 65 "+12V")
			(pinfunction "VCC_12V")
			(pintype "passive")
			(teardrops
				(best_length_ratio 0.2)
				(max_length 1)
				(best_width_ratio 0.9)
				(max_width 2)
				(curved_edges yes)
				(filter_ratio 0.9)
				(enabled yes)
				(allow_two_segments yes)
				(prefer_zone_connections yes)
			)
		)
		(pad "D105" smd rect
			(at 24.75 -8.675)
			(size 0.3 1.75)
			(layers "F.Cu" "F.Mask" "F.Paste")
			(net 65 "+12V")
			(pinfunction "VCC_12V")
			(pintype "passive")
			(teardrops
				(best_length_ratio 0.2)
				(max_length 1)
				(best_width_ratio 0.9)
				(max_width 2)
				(curved_edges yes)
				(filter_ratio 0.9)
				(enabled yes)
				(allow_two_segments yes)
				(prefer_zone_connections yes)
			)
		)
		(pad "D106" smd rect
			(at 25.25 -8.675)
			(size 0.3 1.75)
			(layers "F.Cu" "F.Mask" "F.Paste")
			(net 65 "+12V")
			(pinfunction "VCC_12V")
			(pintype "passive")
			(teardrops
				(best_length_ratio 0.2)
				(max_length 1)
				(best_width_ratio 0.9)
				(max_width 2)
				(curved_edges yes)
				(filter_ratio 0.9)
				(enabled yes)
				(allow_two_segments yes)
				(prefer_zone_connections yes)
			)
		)
		(pad "D107" smd rect
			(at 25.75 -8.675)
			(size 0.3 1.75)
			(layers "F.Cu" "F.Mask" "F.Paste")
			(net 65 "+12V")
			(pinfunction "VCC_12V")
			(pintype "passive")
			(teardrops
				(best_length_ratio 0.2)
				(max_length 1)
				(best_width_ratio 0.9)
				(max_width 2)
				(curved_edges yes)
				(filter_ratio 0.9)
				(enabled yes)
				(allow_two_segments yes)
				(prefer_zone_connections yes)
			)
		)
		(pad "D108" smd rect
			(at 26.25 -8.675)
			(size 0.3 1.75)
			(layers "F.Cu" "F.Mask" "F.Paste")
			(net 65 "+12V")
			(pinfunction "VCC_12V")
			(pintype "passive")
			(teardrops
				(best_length_ratio 0.2)
				(max_length 1)
				(best_width_ratio 0.9)
				(max_width 2)
				(curved_edges yes)
				(filter_ratio 0.9)
				(enabled yes)
				(allow_two_segments yes)
				(prefer_zone_connections yes)
			)
		)
		(pad "D109" smd rect
			(at 26.75 -8.675)
			(size 0.3 1.75)
			(layers "F.Cu" "F.Mask" "F.Paste")
			(net 65 "+12V")
			(pinfunction "VCC_12V")
			(pintype "passive")
			(teardrops
				(best_length_ratio 0.2)
				(max_length 1)
				(best_width_ratio 0.9)
				(max_width 2)
				(curved_edges yes)
				(filter_ratio 0.9)
				(enabled yes)
				(allow_two_segments yes)
				(prefer_zone_connections yes)
			)
		)
		(pad "D110" smd rect
			(at 27.25 -8.675)
			(size 0.3 1.75)
			(layers "F.Cu" "F.Mask" "F.Paste")
			(net 1 "GND")
			(pinfunction "GND(FIXED)")
			(pintype "passive")
			(teardrops
				(best_length_ratio 0.2)
				(max_length 1)
				(best_width_ratio 0.9)
				(max_width 2)
				(curved_edges yes)
				(filter_ratio 0.9)
				(enabled yes)
				(allow_two_segments yes)
				(prefer_zone_connections yes)
			)
		)
		(pad "MP" smd rect
			(at -30.575 -6 90)
			(size 3.3 1.65)
			(layers "F.Cu" "F.Mask" "F.Paste")
			(net 1 "GND")
			(pinfunction "MP")
			(pintype "passive")
			(teardrops
				(best_length_ratio 0.2)
				(max_length 1)
				(best_width_ratio 0.9)
				(max_width 2)
				(curved_edges yes)
				(filter_ratio 0.9)
				(enabled yes)
				(allow_two_segments yes)
				(prefer_zone_connections yes)
			)
		)
		(pad "MP" smd rect
			(at -30.575 6 90)
			(size 3.3 1.65)
			(layers "F.Cu" "F.Mask" "F.Paste")
			(net 1 "GND")
			(pinfunction "MP")
			(pintype "passive")
			(teardrops
				(best_length_ratio 0.2)
				(max_length 1)
				(best_width_ratio 0.9)
				(max_width 2)
				(curved_edges yes)
				(filter_ratio 0.9)
				(enabled yes)
				(allow_two_segments yes)
				(prefer_zone_connections yes)
			)
		)
		(pad "MP" smd rect
			(at 30.575 6 90)
			(size 0.001 0.001)
			(layers "F.Cu" "F.Mask" "F.Paste")
			(net 1 "GND")
			(pinfunction "MP")
			(pintype "passive")
			(teardrops
				(best_length_ratio 0.2)
				(max_length 1)
				(best_width_ratio 0.9)
				(max_width 2)
				(curved_edges yes)
				(filter_ratio 0.9)
				(enabled yes)
				(allow_two_segments yes)
				(prefer_zone_connections yes)
			)
		)
		(pad "MP" smd rect
			(at 30.65 -6 90)
			(size 3.3 1.6)
			(layers "F.Cu" "F.Mask" "F.Paste")
			(net 1 "GND")
			(pinfunction "MP")
			(pintype "passive")
			(teardrops
				(best_length_ratio 0.2)
				(max_length 1)
				(best_width_ratio 0.9)
				(max_width 2)
				(curved_edges yes)
				(filter_ratio 0.9)
				(enabled yes)
				(allow_two_segments yes)
				(prefer_zone_connections yes)
			)
		)
		(pad "MP" smd rect
			(at 30.65 5.9995 90)
			(size 3.3 1.6)
			(layers "F.Cu" "F.Mask" "F.Paste")
			(net 1 "GND")
			(pinfunction "MP")
			(pintype "passive")
			(teardrops
				(best_length_ratio 0.2)
				(max_length 1)
				(best_width_ratio 0.9)
				(max_width 2)
				(curved_edges yes)
				(filter_ratio 0.9)
				(enabled yes)
				(allow_two_segments yes)
				(prefer_zone_connections yes)
			)
		)
	)
	(footprint "antmicro-footprints:USON-10_2.5x1mm_P0.5mm"
		(layer "F.Cu")
		(at 112.15 137.91)
		(descr "USON-10 2.5x1mm_ Pitch 0.5mm")
		(tags "USON-10 2.5x1mm Pitch 0.5mm")
		(property "Reference" "U46"
			(at 1.75 1.15 90)
			(layer "F.SilkS")
			(effects
				(font
					(size 0.7 0.7)
					(thickness 0.15)
				)
				(justify left bottom)
			)
		)
		(property "Value" "ESD204DQAR"
			(at 0.018 2.499 0)
			(layer "F.Fab")
			(effects
				(font
					(size 0.7 0.7)
					(thickness 0.15)
				)
				(justify left bottom)
			)
		)
		(property "Datasheet" "https://www.ti.com/lit/ds/symlink/esd204.pdf?ts=1706004844383&ref_url=https%253A%252F%252Fwww.ti.com%252Finterface%252Fdiodes%252Fesd-protection-diodes%252Fproducts.html"
			(at 0 0 0)
			(layer "F.Fab")
			(hide yes)
			(effects
				(font
					(size 1.27 1.27)
					(thickness 0.15)
				)
			)
		)
		(property "Author" "Antmicro"
			(at 0 0 0)
			(layer "F.Fab")
			(hide yes)
			(effects
				(font
					(size 1 1)
					(thickness 0.15)
				)
			)
		)
		(property "License" "Apache-2.0"
			(at 0 0 0)
			(layer "F.Fab")
			(hide yes)
			(effects
				(font
					(size 1 1)
					(thickness 0.15)
				)
			)
		)
		(property "MPN" "ESD204DQAR"
			(at 0 0 0)
			(layer "F.Fab")
			(hide yes)
			(effects
				(font
					(size 1 1)
					(thickness 0.15)
				)
			)
		)
		(property "Manufacturer" "Texas Instruments"
			(at 0 0 0)
			(layer "F.Fab")
			(hide yes)
			(effects
				(font
					(size 1 1)
					(thickness 0.15)
				)
			)
		)
		(sheetname "SD card")
		(sheetfile "sd_card.kicad_sch")
		(attr smd)
		(fp_line
			(start 0.498 -1.401)
			(end -0.5 -1.401)
			(stroke
				(width 0.15)
				(type solid)
			)
			(layer "F.SilkS")
		)
		(fp_line
			(start 0.498 1.398)
			(end -0.5 1.398)
			(stroke
				(width 0.15)
				(type solid)
			)
			(layer "F.SilkS")
		)
		(fp_circle
			(center -0.68 -1.27)
			(end -0.63 -1.27)
			(stroke
				(width 0.15)
				(type solid)
			)
			(fill yes)
			(layer "F.SilkS")
		)
		(fp_rect
			(start -0.8 -1.5)
			(end 0.8 1.499)
			(stroke
				(width 0.05)
				(type solid)
			)
			(fill no)
			(layer "F.CrtYd")
		)
		(fp_line
			(start -0.5 -1)
			(end -0.5 1.249)
			(stroke
				(width 0.15)
				(type solid)
			)
			(layer "F.Fab")
		)
		(fp_line
			(start -0.5 1.249)
			(end 0.498 1.249)
			(stroke
				(width 0.15)
				(type solid)
			)
			(layer "F.Fab")
		)
		(fp_line
			(start -0.25 -1.25)
			(end -0.5 -1)
			(stroke
				(width 0.15)
				(type solid)
			)
			(layer "F.Fab")
		)
		(fp_line
			(start 0.498 -1.25)
			(end -0.25 -1.25)
			(stroke
				(width 0.15)
				(type solid)
			)
			(layer "F.Fab")
		)
		(fp_line
			(start 0.498 -1.25)
			(end 0.498 1.249)
			(stroke
				(width 0.15)
				(type solid)
			)
			(layer "F.Fab")
		)
		(pad "1" smd roundrect
			(at -0.387 -1 270)
			(size 0.25 0.55)
			(layers "F.Cu" "F.Mask" "F.Paste")
			(roundrect_rratio 0.25)
			(net 385 "/Com Express 7 Interfaces/SDIO.CMD")
			(pintype "passive")
			(teardrops
				(best_length_ratio 0.2)
				(max_length 1)
				(best_width_ratio 0.9)
				(max_width 2)
				(curved_edges yes)
				(filter_ratio 0.9)
				(enabled yes)
				(allow_two_segments yes)
				(prefer_zone_connections yes)
			)
		)
		(pad "2" smd roundrect
			(at -0.387 -0.5 270)
			(size 0.25 0.55)
			(layers "F.Cu" "F.Mask" "F.Paste")
			(roundrect_rratio 0.25)
			(net 333 "/Com Express 7 Interfaces/SDIO.DAT3")
			(pintype "passive")
			(teardrops
				(best_length_ratio 0.2)
				(max_length 1)
				(best_width_ratio 0.9)
				(max_width 2)
				(curved_edges yes)
				(filter_ratio 0.9)
				(enabled yes)
				(allow_two_segments yes)
				(prefer_zone_connections yes)
			)
		)
		(pad "3" smd roundrect
			(at -0.387 0 270)
			(size 0.4 0.55)
			(layers "F.Cu" "F.Mask" "F.Paste")
			(roundrect_rratio 0.25)
			(net 1 "GND")
			(pintype "power_in")
			(teardrops
				(best_length_ratio 0.2)
				(max_length 1)
				(best_width_ratio 0.9)
				(max_width 2)
				(curved_edges yes)
				(filter_ratio 0.9)
				(enabled yes)
				(allow_two_segments yes)
				(prefer_zone_connections yes)
			)
		)
		(pad "4" smd roundrect
			(at -0.387 0.498 270)
			(size 0.25 0.55)
			(layers "F.Cu" "F.Mask" "F.Paste")
			(roundrect_rratio 0.25)
			(net 323 "/Com Express 7 Interfaces/SDIO.DAT2")
			(pintype "passive")
			(teardrops
				(best_length_ratio 0.2)
				(max_length 1)
				(best_width_ratio 0.9)
				(max_width 2)
				(curved_edges yes)
				(filter_ratio 0.9)
				(enabled yes)
				(allow_two_segments yes)
				(prefer_zone_connections yes)
			)
		)
		(pad "5" smd roundrect
			(at -0.387 0.998 270)
			(size 0.25 0.55)
			(layers "F.Cu" "F.Mask" "F.Paste")
			(roundrect_rratio 0.25)
			(net 890 "unconnected-(U46-Pad5)")
			(pintype "passive+no_connect")
			(teardrops
				(best_length_ratio 0.2)
				(max_length 1)
				(best_width_ratio 0.9)
				(max_width 2)
				(curved_edges yes)
				(filter_ratio 0.9)
				(enabled yes)
				(allow_two_segments yes)
				(prefer_zone_connections yes)
			)
		)
		(pad "6" smd roundrect
			(at 0.385 0.998 270)
			(size 0.25 0.55)
			(layers "F.Cu" "F.Mask" "F.Paste")
			(roundrect_rratio 0.25)
			(net 998 "unconnected-(U46-Pad5)_1")
			(pintype "passive+no_connect")
			(teardrops
				(best_length_ratio 0.2)
				(max_length 1)
				(best_width_ratio 0.9)
				(max_width 2)
				(curved_edges yes)
				(filter_ratio 0.9)
				(enabled yes)
				(allow_two_segments yes)
				(prefer_zone_connections yes)
			)
		)
		(pad "7" smd roundrect
			(at 0.385 0.498 270)
			(size 0.25 0.55)
			(layers "F.Cu" "F.Mask" "F.Paste")
			(roundrect_rratio 0.25)
			(net 323 "/Com Express 7 Interfaces/SDIO.DAT2")
			(pintype "passive")
			(teardrops
				(best_length_ratio 0.2)
				(max_length 1)
				(best_width_ratio 0.9)
				(max_width 2)
				(curved_edges yes)
				(filter_ratio 0.9)
				(enabled yes)
				(allow_two_segments yes)
				(prefer_zone_connections yes)
			)
		)
		(pad "8" smd roundrect
			(at 0.385 0 270)
			(size 0.4 0.55)
			(layers "F.Cu" "F.Mask" "F.Paste")
			(roundrect_rratio 0.25)
			(net 1 "GND")
			(pintype "passive")
			(teardrops
				(best_length_ratio 0.2)
				(max_length 1)
				(best_width_ratio 0.9)
				(max_width 2)
				(curved_edges yes)
				(filter_ratio 0.9)
				(enabled yes)
				(allow_two_segments yes)
				(prefer_zone_connections yes)
			)
		)
		(pad "9" smd roundrect
			(at 0.385 -0.5 270)
			(size 0.25 0.55)
			(layers "F.Cu" "F.Mask" "F.Paste")
			(roundrect_rratio 0.25)
			(net 333 "/Com Express 7 Interfaces/SDIO.DAT3")
			(pintype "passive")
			(teardrops
				(best_length_ratio 0.2)
				(max_length 1)
				(best_width_ratio 0.9)
				(max_width 2)
				(curved_edges yes)
				(filter_ratio 0.9)
				(enabled yes)
				(allow_two_segments yes)
				(prefer_zone_connections yes)
			)
		)
		(pad "10" smd roundrect
			(at 0.385 -1 270)
			(size 0.25 0.55)
			(layers "F.Cu" "F.Mask" "F.Paste")
			(roundrect_rratio 0.25)
			(net 385 "/Com Express 7 Interfaces/SDIO.CMD")
			(pintype "passive")
			(teardrops
				(best_length_ratio 0.2)
				(max_length 1)
				(best_width_ratio 0.9)
				(max_width 2)
				(curved_edges yes)
				(filter_ratio 0.9)
				(enabled yes)
				(allow_two_segments yes)
				(prefer_zone_connections yes)
			)
		)
	)
	(footprint "antmicro-footprints:R_0402_1005Metric"
		(layer "F.Cu")
		(at 312.075499 136.46 90)
		(descr "Resistor SMD 0402")
		(tags "resistor SMD 0402")
		(property "Reference" "R106"
			(at 0.2 5.674501 90)
			(layer "F.SilkS")
			(effects
				(font
					(size 0.7 0.7)
					(thickness 0.15)
				)
				(justify left bottom)
			)
		)
		(property "Value" "R_0R_0402"
			(at -1.011843 1.772047 90)
			(layer "F.Fab")
			(effects
				(font
					(size 0.7 0.7)
					(thickness 0.15)
				)
				(justify left bottom)
			)
		)
		(property "Datasheet" "https://industrial.panasonic.com/cdbs/www-data/pdf/RDA0000/AOA0000C301.pdf"
			(at 0 0 90)
			(layer "F.Fab")
			(hide yes)
			(effects
				(font
					(size 1.27 1.27)
					(thickness 0.15)
				)
			)
		)
		(property "Author" "Antmicro"
			(at 448.535499 -175.615499 0)
			(layer "F.Fab")
			(hide yes)
			(effects
				(font
					(size 1 1)
					(thickness 0.15)
				)
			)
		)
		(property "Current" "1A"
			(at 448.535499 -175.615499 0)
			(layer "F.Fab")
			(hide yes)
			(effects
				(font
					(size 1 1)
					(thickness 0.15)
				)
			)
		)
		(property "License" "Apache-2.0"
			(at 448.535499 -175.615499 0)
			(layer "F.Fab")
			(hide yes)
			(effects
				(font
					(size 1 1)
					(thickness 0.15)
				)
			)
		)
		(property "MPN" "ERJ2GE0R00X"
			(at 448.535499 -175.615499 0)
			(layer "F.Fab")
			(hide yes)
			(effects
				(font
					(size 1 1)
					(thickness 0.15)
				)
			)
		)
		(property "Manufacturer" "Panasonic"
			(at 448.535499 -175.615499 0)
			(layer "F.Fab")
			(hide yes)
			(effects
				(font
					(size 1 1)
					(thickness 0.15)
				)
			)
		)
		(property "Public" "False"
			(at 448.535499 -175.615499 0)
			(layer "F.Fab")
			(hide yes)
			(effects
				(font
					(size 1 1)
					(thickness 0.15)
				)
			)
		)
		(property "Tolerance" ""
			(at 448.535499 -175.615499 0)
			(layer "F.Fab")
			(hide yes)
			(effects
				(font
					(size 1 1)
					(thickness 0.15)
				)
			)
		)
		(property "Val" "0R"
			(at 448.535499 -175.615499 0)
			(layer "F.Fab")
			(hide yes)
			(effects
				(font
					(size 1 1)
					(thickness 0.15)
				)
			)
		)
		(sheetname "Power")
		(sheetfile "power.kicad_sch")
		(attr smd)
		(fp_rect
			(start -0.925 -0.47)
			(end 0.925 0.47)
			(stroke
				(width 0.05)
				(type default)
			)
			(fill no)
			(layer "F.CrtYd")
		)
		(fp_rect
			(start -0.5 -0.25)
			(end 0.5 0.25)
			(stroke
				(width 0.15)
				(type solid)
			)
			(fill no)
			(layer "F.Fab")
		)
		(pad "1" smd roundrect
			(at -0.48 0 90)
			(size 0.59 0.64)
			(layers "F.Cu" "F.Mask" "F.Paste")
			(roundrect_rratio 0.25)
			(net 889 "/Power/PG_{3V3}")
			(pintype "passive")
			(teardrops
				(best_length_ratio 0.2)
				(max_length 1)
				(best_width_ratio 0.9)
				(max_width 2)
				(curved_edges yes)
				(filter_ratio 0.9)
				(enabled yes)
				(allow_two_segments yes)
				(prefer_zone_connections yes)
			)
		)
		(pad "2" smd roundrect
			(at 0.48 0 90)
			(size 0.59 0.64)
			(layers "F.Cu" "F.Mask" "F.Paste")
			(roundrect_rratio 0.25)
			(net 583 "Net-(U22-EN)")
			(pintype "passive")
			(teardrops
				(best_length_ratio 0.2)
				(max_length 1)
				(best_width_ratio 0.9)
				(max_width 2)
				(curved_edges yes)
				(filter_ratio 0.9)
				(enabled yes)
				(allow_two_segments yes)
				(prefer_zone_connections yes)
			)
		)
	)
	(footprint "antmicro-footprints:C_0402_1005Metric"
		(layer "F.Cu")
		(at 262.430708 75.76)
		(descr "Capacitor SMD 0402")
		(tags "capacitor SMD 0402")
		(property "Reference" "C90"
			(at -3.01 0.45 0)
			(layer "F.SilkS")
			(effects
				(font
					(size 0.7 0.7)
					(thickness 0.15)
				)
				(justify left bottom)
			)
		)
		(property "Value" "C_100n_0402"
			(at -1.022927 2.155213 0)
			(layer "F.Fab")
			(effects
				(font
					(size 0.7 0.7)
					(thickness 0.15)
				)
				(justify left bottom)
			)
		)
		(property "Datasheet" "https://www.murata.com/products/productdetail?partno=GRM155R61H104KE14%23"
			(at 0 0 0)
			(layer "F.Fab")
			(hide yes)
			(effects
				(font
					(size 1.27 1.27)
					(thickness 0.15)
				)
			)
		)
		(property "Author" "Antmicro"
			(at 0 0 0)
			(layer "F.Fab")
			(hide yes)
			(effects
				(font
					(size 1 1)
					(thickness 0.15)
				)
			)
		)
		(property "Dielectric" "X5R"
			(at 0 0 0)
			(layer "F.Fab")
			(hide yes)
			(effects
				(font
					(size 1 1)
					(thickness 0.15)
				)
			)
		)
		(property "License" "Apache-2.0"
			(at 0 0 0)
			(layer "F.Fab")
			(hide yes)
			(effects
				(font
					(size 1 1)
					(thickness 0.15)
				)
			)
		)
		(property "MPN" "GRM155R61H104KE14D"
			(at 0 0 0)
			(layer "F.Fab")
			(hide yes)
			(effects
				(font
					(size 1 1)
					(thickness 0.15)
				)
			)
		)
		(property "Manufacturer" "Murata"
			(at 0 0 0)
			(layer "F.Fab")
			(hide yes)
			(effects
				(font
					(size 1 1)
					(thickness 0.15)
				)
			)
		)
		(property "Public" "False"
			(at 0 0 0)
			(layer "F.Fab")
			(hide yes)
			(effects
				(font
					(size 1 1)
					(thickness 0.15)
				)
			)
		)
		(property "Val" "100n"
			(at 0 0 0)
			(layer "F.Fab")
			(hide yes)
			(effects
				(font
					(size 1 1)
					(thickness 0.15)
				)
			)
		)
		(property "Voltage" "50V"
			(at 0 0 0)
			(layer "F.Fab")
			(hide yes)
			(effects
				(font
					(size 1 1)
					(thickness 0.15)
				)
			)
		)
		(sheetname "Misc")
		(sheetfile "misc.kicad_sch")
		(attr smd)
		(fp_rect
			(start -0.925 -0.47)
			(end 0.925 0.47)
			(stroke
				(width 0.05)
				(type default)
			)
			(fill no)
			(layer "F.CrtYd")
		)
		(fp_line
			(start -0.494 -0.25)
			(end 0.504 -0.25)
			(stroke
				(width 0.15)
				(type solid)
			)
			(layer "F.Fab")
		)
		(fp_line
			(start -0.494 0.248)
			(end -0.494 -0.25)
			(stroke
				(width 0.15)
				(type solid)
			)
			(layer "F.Fab")
		)
		(fp_line
			(start 0.504 -0.25)
			(end 0.504 0.248)
			(stroke
				(width 0.15)
				(type solid)
			)
			(layer "F.Fab")
		)
		(fp_line
			(start 0.504 0.248)
			(end -0.494 0.248)
			(stroke
				(width 0.15)
				(type solid)
			)
			(layer "F.Fab")
		)
		(pad "1" smd roundrect
			(at -0.48 0)
			(size 0.59 0.64)
			(layers "F.Cu" "F.Mask" "F.Paste")
			(roundrect_rratio 0.25)
			(net 1 "GND")
			(pintype "passive")
			(teardrops
				(best_length_ratio 0.2)
				(max_length 1)
				(best_width_ratio 0.9)
				(max_width 2)
				(curved_edges yes)
				(filter_ratio 0.9)
				(enabled yes)
				(allow_two_segments yes)
				(prefer_zone_connections yes)
			)
		)
		(pad "2" smd roundrect
			(at 0.48 0)
			(size 0.59 0.64)
			(layers "F.Cu" "F.Mask" "F.Paste")
			(roundrect_rratio 0.25)
			(net 52 "+5V")
			(pintype "passive")
			(teardrops
				(best_length_ratio 0.2)
				(max_length 1)
				(best_width_ratio 0.9)
				(max_width 2)
				(curved_edges yes)
				(filter_ratio 0.9)
				(enabled yes)
				(allow_two_segments yes)
				(prefer_zone_connections yes)
			)
		)
	)
	(footprint "antmicro-footprints:C_0402_1005Metric"
		(layer "F.Cu")
		(at 191.780956 136.25552 135)
		(descr "Capacitor SMD 0402")
		(tags "capacitor SMD 0402")
		(property "Reference" "C122"
			(at 3.844168 0.29978 135)
			(layer "F.SilkS")
			(effects
				(font
					(size 0.7 0.7)
					(thickness 0.15)
				)
				(justify left top)
			)
		)
		(property "Value" "C_100n_0402"
			(at -1.022927 2.155213 135)
			(layer "F.Fab")
			(effects
				(font
					(size 0.7 0.7)
					(thickness 0.15)
				)
				(justify left top)
			)
		)
		(property "Datasheet" "https://www.murata.com/products/productdetail?partno=GRM155R61H104KE14%23"
			(at 0 0 135)
			(layer "B.Fab")
			(hide yes)
			(effects
				(font
					(size 1.27 1.27)
					(thickness 0.15)
				)
				(justify mirror)
			)
		)
		(property "Author" "Antmicro"
			(at 325.014 56.288 45)
			(layer "F.Fab")
			(hide yes)
			(effects
				(font
					(size 1 1)
					(thickness 0.15)
				)
			)
		)
		(property "Dielectric" "X5R"
			(at 325.014 56.288 45)
			(layer "F.Fab")
			(hide yes)
			(effects
				(font
					(size 1 1)
					(thickness 0.15)
				)
			)
		)
		(property "License" "Apache-2.0"
			(at 325.014 56.288 45)
			(layer "F.Fab")
			(hide yes)
			(effects
				(font
					(size 1 1)
					(thickness 0.15)
				)
			)
		)
		(property "MPN" "GRM155R61H104KE14D"
			(at 325.014 56.288 45)
			(layer "F.Fab")
			(hide yes)
			(effects
				(font
					(size 1 1)
					(thickness 0.15)
				)
			)
		)
		(property "Manufacturer" "Murata"
			(at 325.014 56.288 45)
			(layer "F.Fab")
			(hide yes)
			(effects
				(font
					(size 1 1)
					(thickness 0.15)
				)
			)
		)
		(property "Public" "False"
			(at 325.014 56.288 45)
			(layer "F.Fab")
			(hide yes)
			(effects
				(font
					(size 1 1)
					(thickness 0.15)
				)
			)
		)
		(property "Val" "100n"
			(at 325.014 56.288 45)
			(layer "F.Fab")
			(hide yes)
			(effects
				(font
					(size 1 1)
					(thickness 0.15)
				)
			)
		)
		(property "Voltage" "50V"
			(at 325.014 56.288 45)
			(layer "F.Fab")
			(hide yes)
			(effects
				(font
					(size 1 1)
					(thickness 0.15)
				)
			)
		)
		(sheetname "PCIe redriver")
		(sheetfile "pcie_redriver.kicad_sch")
		(attr smd)
		(fp_poly
			(pts
				(xy -0.925 -0.47) (xy 0.925 -0.47) (xy 0.925 0.47) (xy -0.925 0.47)
			)
			(stroke
				(width 0.05)
				(type default)
			)
			(fill no)
			(layer "F.CrtYd")
		)
		(fp_line
			(start 0.504 -0.25)
			(end 0.504 0.248)
			(stroke
				(width 0.15)
				(type solid)
			)
			(layer "F.Fab")
		)
		(fp_line
			(start 0.504 0.248)
			(end -0.494 0.248)
			(stroke
				(width 0.15)
				(type solid)
			)
			(layer "F.Fab")
		)
		(fp_line
			(start -0.494 -0.25)
			(end 0.504 -0.25)
			(stroke
				(width 0.15)
				(type solid)
			)
			(layer "F.Fab")
		)
		(fp_line
			(start -0.494 0.248)
			(end -0.494 -0.25)
			(stroke
				(width 0.15)
				(type solid)
			)
			(layer "F.Fab")
		)
		(pad "1" smd roundrect
			(at -0.48 0 135)
			(size 0.59 0.64)
			(layers "F.Cu" "F.Mask" "F.Paste")
			(roundrect_rratio 0.25)
			(net 1 "GND")
			(pintype "passive")
			(teardrops
				(best_length_ratio 0.2)
				(max_length 1)
				(best_width_ratio 0.9)
				(max_width 2)
				(curved_edges yes)
				(filter_ratio 0.9)
				(enabled yes)
				(allow_two_segments yes)
				(prefer_zone_connections yes)
			)
		)
		(pad "2" smd roundrect
			(at 0.48 0 135)
			(size 0.59 0.64)
			(layers "F.Cu" "F.Mask" "F.Paste")
			(roundrect_rratio 0.25)
			(net 2 "+3V3")
			(pintype "passive")
			(teardrops
				(best_length_ratio 0.2)
				(max_length 1)
				(best_width_ratio 0.9)
				(max_width 2)
				(curved_edges yes)
				(filter_ratio 0.9)
				(enabled yes)
				(allow_two_segments yes)
				(prefer_zone_connections yes)
			)
		)
	)
	(footprint "antmicro-footprints:SOD-523"
		(layer "F.Cu")
		(at 113.2 91.31 -90)
		(property "Reference" "D2"
			(at -2.4 -0.5 90)
			(layer "F.SilkS")
			(effects
				(font
					(size 0.7 0.7)
					(thickness 0.15)
				)
				(justify right bottom)
			)
		)
		(property "Value" "PESD5Z5_0F"
			(at 0 1.499 90)
			(layer "F.Fab")
			(effects
				(font
					(size 0.7 0.7)
					(thickness 0.15)
				)
				(justify right bottom)
			)
		)
		(property "Datasheet" "https://assets.nexperia.com/documents/data-sheet/PESD5Z5_0.pdf"
			(at 0 0 270)
			(layer "F.Fab")
			(hide yes)
			(effects
				(font
					(size 1.27 1.27)
					(thickness 0.15)
				)
			)
		)
		(property "Author" "Antmicro"
			(at 21.89 204.51 0)
			(layer "F.Fab")
			(hide yes)
			(effects
				(font
					(size 1 1)
					(thickness 0.15)
				)
			)
		)
		(property "License" "Apache-2.0"
			(at 21.89 204.51 0)
			(layer "F.Fab")
			(hide yes)
			(effects
				(font
					(size 1 1)
					(thickness 0.15)
				)
			)
		)
		(property "MPN" "PESD5Z5.0F"
			(at 21.89 204.51 0)
			(layer "F.Fab")
			(hide yes)
			(effects
				(font
					(size 1 1)
					(thickness 0.15)
				)
			)
		)
		(property "Manufacturer" "Nexperia"
			(at 21.89 204.51 0)
			(layer "F.Fab")
			(hide yes)
			(effects
				(font
					(size 1 1)
					(thickness 0.15)
				)
			)
		)
		(property "Public" "False"
			(at 21.89 204.51 0)
			(layer "F.Fab")
			(hide yes)
			(effects
				(font
					(size 1 1)
					(thickness 0.15)
				)
			)
		)
		(sheetname "2xUSB3.0+RJ45")
		(sheetfile "usb3+rj45.kicad_sch")
		(attr smd)
		(fp_line
			(start -0.35 -0.5)
			(end -0.35 0.5)
			(stroke
				(width 0.15)
				(type solid)
			)
			(layer "F.SilkS")
		)
		(fp_rect
			(start -1 -0.6)
			(end 1 0.6)
			(stroke
				(width 0.05)
				(type solid)
			)
			(fill no)
			(layer "F.CrtYd")
		)
		(fp_line
			(start -0.652 0.423)
			(end 0.65 0.423)
			(stroke
				(width 0.15)
				(type solid)
			)
			(layer "F.Fab")
		)
		(fp_line
			(start -0.652 0.423)
			(end -0.652 -0.425)
			(stroke
				(width 0.15)
				(type solid)
			)
			(layer "F.Fab")
		)
		(fp_line
			(start -0.35 -0.4)
			(end -0.35 0.4)
			(stroke
				(width 0.15)
				(type solid)
			)
			(layer "F.Fab")
		)
		(fp_line
			(start -0.652 -0.425)
			(end 0.65 -0.425)
			(stroke
				(width 0.15)
				(type solid)
			)
			(layer "F.Fab")
		)
		(fp_line
			(start 0.65 -0.425)
			(end 0.65 0.423)
			(stroke
				(width 0.15)
				(type solid)
			)
			(layer "F.Fab")
		)
		(pad "1" smd roundrect
			(at -0.701 0 270)
			(size 0.5 0.6)
			(layers "F.Cu" "F.Mask" "F.Paste")
			(roundrect_rratio 0.25)
			(net 43 "/2xUSB3.0+RJ45/P2_VBUS")
			(pinfunction "C")
			(pintype "passive")
			(teardrops
				(best_length_ratio 0.2)
				(max_length 1)
				(best_width_ratio 0.9)
				(max_width 2)
				(curved_edges yes)
				(filter_ratio 0.9)
				(enabled yes)
				(allow_two_segments yes)
				(prefer_zone_connections yes)
			)
		)
		(pad "2" smd roundrect
			(at 0.699 0 270)
			(size 0.5 0.6)
			(layers "F.Cu" "F.Mask" "F.Paste")
			(roundrect_rratio 0.25)
			(net 1 "GND")
			(pinfunction "A")
			(pintype "passive")
			(teardrops
				(best_length_ratio 0.2)
				(max_length 1)
				(best_width_ratio 0.9)
				(max_width 2)
				(curved_edges yes)
				(filter_ratio 0.9)
				(enabled yes)
				(allow_two_segments yes)
				(prefer_zone_connections yes)
			)
		)
	)
	(footprint "antmicro-footprints:R_0402_1005Metric"
		(layer "F.Cu")
		(at 190.70861 77.152163 90)
		(descr "Resistor SMD 0402")
		(tags "resistor SMD 0402")
		(property "Reference" "R322"
			(at -1.9 -0.5 90)
			(layer "F.SilkS")
			(effects
				(font
					(size 0.7 0.7)
					(thickness 0.15)
				)
				(justify left bottom)
			)
		)
		(property "Value" "R_220R_0402"
			(at -1.011843 1.772047 90)
			(layer "F.Fab")
			(effects
				(font
					(size 0.7 0.7)
					(thickness 0.15)
				)
				(justify left bottom)
			)
		)
		(property "Datasheet" "https://www.bourns.com/docs/product-datasheets/cr.pdf"
			(at 0 0 90)
			(layer "F.Fab")
			(hide yes)
			(effects
				(font
					(size 1.27 1.27)
					(thickness 0.15)
				)
			)
		)
		(property "Author" "Antmicro"
			(at 267.860773 -113.556447 0)
			(layer "F.Fab")
			(hide yes)
			(effects
				(font
					(size 1 1)
					(thickness 0.15)
				)
			)
		)
		(property "License" "Apache-2.0"
			(at 267.860773 -113.556447 0)
			(layer "F.Fab")
			(hide yes)
			(effects
				(font
					(size 1 1)
					(thickness 0.15)
				)
			)
		)
		(property "MPN" "CR0402-FX-2200GLF"
			(at 267.860773 -113.556447 0)
			(layer "F.Fab")
			(hide yes)
			(effects
				(font
					(size 1 1)
					(thickness 0.15)
				)
			)
		)
		(property "Manufacturer" "Bourns"
			(at 267.860773 -113.556447 0)
			(layer "F.Fab")
			(hide yes)
			(effects
				(font
					(size 1 1)
					(thickness 0.15)
				)
			)
		)
		(property "Public" "False"
			(at 267.860773 -113.556447 0)
			(layer "F.Fab")
			(hide yes)
			(effects
				(font
					(size 1 1)
					(thickness 0.15)
				)
			)
		)
		(property "Tolerance" "1%"
			(at 267.860773 -113.556447 0)
			(layer "F.Fab")
			(hide yes)
			(effects
				(font
					(size 1 1)
					(thickness 0.15)
				)
			)
		)
		(property "Val" "220R"
			(at 267.860773 -113.556447 0)
			(layer "F.Fab")
			(hide yes)
			(effects
				(font
					(size 1 1)
					(thickness 0.15)
				)
			)
		)
		(sheetname "Power")
		(sheetfile "power.kicad_sch")
		(attr smd)
		(fp_rect
			(start -0.925 -0.47)
			(end 0.925 0.47)
			(stroke
				(width 0.05)
				(type default)
			)
			(fill no)
			(layer "F.CrtYd")
		)
		(fp_rect
			(start -0.5 -0.25)
			(end 0.5 0.25)
			(stroke
				(width 0.15)
				(type solid)
			)
			(fill no)
			(layer "F.Fab")
		)
		(pad "1" smd roundrect
			(at -0.48 0 90)
			(size 0.59 0.64)
			(layers "F.Cu" "F.Mask" "F.Paste")
			(roundrect_rratio 0.25)
			(net 1 "GND")
			(pintype "passive")
			(teardrops
				(best_length_ratio 0.2)
				(max_length 1)
				(best_width_ratio 0.9)
				(max_width 2)
				(curved_edges yes)
				(filter_ratio 0.9)
				(enabled yes)
				(allow_two_segments yes)
				(prefer_zone_connections yes)
			)
		)
		(pad "2" smd roundrect
			(at 0.48 0 90)
			(size 0.59 0.64)
			(layers "F.Cu" "F.Mask" "F.Paste")
			(roundrect_rratio 0.25)
			(net 982 "Net-(D30-C)")
			(pintype "passive")
			(teardrops
				(best_length_ratio 0.2)
				(max_length 1)
				(best_width_ratio 0.9)
				(max_width 2)
				(curved_edges yes)
				(filter_ratio 0.9)
				(enabled yes)
				(allow_two_segments yes)
				(prefer_zone_connections yes)
			)
		)
	)
	(footprint "antmicro-footprints:C_0402_1005Metric"
		(layer "F.Cu")
		(at 314.114999 121.939999 -90)
		(descr "Capacitor SMD 0402")
		(tags "capacitor SMD 0402")
		(property "Reference" "C47"
			(at 0.870001 -0.485001 90)
			(layer "F.SilkS")
			(effects
				(font
					(size 0.7 0.7)
					(thickness 0.15)
				)
				(justify right bottom)
			)
		)
		(property "Value" "C_100n_0402"
			(at -1.022927 2.155213 90)
			(layer "F.Fab")
			(effects
				(font
					(size 0.7 0.7)
					(thickness 0.15)
				)
				(justify right bottom)
			)
		)
		(property "Datasheet" "https://www.murata.com/products/productdetail?partno=GRM155R61H104KE14%23"
			(at 0 0 270)
			(layer "F.Fab")
			(hide yes)
			(effects
				(font
					(size 1.27 1.27)
					(thickness 0.15)
				)
			)
		)
		(property "Author" "Antmicro"
			(at 192.175 436.054998 0)
			(layer "F.Fab")
			(hide yes)
			(effects
				(font
					(size 1 1)
					(thickness 0.15)
				)
			)
		)
		(property "Dielectric" "X5R"
			(at 192.175 436.054998 0)
			(layer "F.Fab")
			(hide yes)
			(effects
				(font
					(size 1 1)
					(thickness 0.15)
				)
			)
		)
		(property "License" "Apache-2.0"
			(at 192.175 436.054998 0)
			(layer "F.Fab")
			(hide yes)
			(effects
				(font
					(size 1 1)
					(thickness 0.15)
				)
			)
		)
		(property "MPN" "GRM155R61H104KE14D"
			(at 192.175 436.054998 0)
			(layer "F.Fab")
			(hide yes)
			(effects
				(font
					(size 1 1)
					(thickness 0.15)
				)
			)
		)
		(property "Manufacturer" "Murata"
			(at 192.175 436.054998 0)
			(layer "F.Fab")
			(hide yes)
			(effects
				(font
					(size 1 1)
					(thickness 0.15)
				)
			)
		)
		(property "Public" "False"
			(at 192.175 436.054998 0)
			(layer "F.Fab")
			(hide yes)
			(effects
				(font
					(size 1 1)
					(thickness 0.15)
				)
			)
		)
		(property "Val" "100n"
			(at 192.175 436.054998 0)
			(layer "F.Fab")
			(hide yes)
			(effects
				(font
					(size 1 1)
					(thickness 0.15)
				)
			)
		)
		(property "Voltage" "50V"
			(at 192.175 436.054998 0)
			(layer "F.Fab")
			(hide yes)
			(effects
				(font
					(size 1 1)
					(thickness 0.15)
				)
			)
		)
		(sheetname "Power")
		(sheetfile "power.kicad_sch")
		(attr smd)
		(fp_rect
			(start -0.925 -0.47)
			(end 0.925 0.47)
			(stroke
				(width 0.05)
				(type default)
			)
			(fill no)
			(layer "F.CrtYd")
		)
		(fp_line
			(start -0.494 0.248)
			(end -0.494 -0.25)
			(stroke
				(width 0.15)
				(type solid)
			)
			(layer "F.Fab")
		)
		(fp_line
			(start 0.504 0.248)
			(end -0.494 0.248)
			(stroke
				(width 0.15)
				(type solid)
			)
			(layer "F.Fab")
		)
		(fp_line
			(start -0.494 -0.25)
			(end 0.504 -0.25)
			(stroke
				(width 0.15)
				(type solid)
			)
			(layer "F.Fab")
		)
		(fp_line
			(start 0.504 -0.25)
			(end 0.504 0.248)
			(stroke
				(width 0.15)
				(type solid)
			)
			(layer "F.Fab")
		)
		(pad "1" smd roundrect
			(at -0.48 0 270)
			(size 0.59 0.64)
			(layers "F.Cu" "F.Mask" "F.Paste")
			(roundrect_rratio 0.25)
			(net 66 "Net-(U18-BST)")
			(pintype "passive")
			(teardrops
				(best_length_ratio 0.2)
				(max_length 1)
				(best_width_ratio 0.9)
				(max_width 2)
				(curved_edges yes)
				(filter_ratio 0.9)
				(enabled yes)
				(allow_two_segments yes)
				(prefer_zone_connections yes)
			)
		)
		(pad "2" smd roundrect
			(at 0.48 0 270)
			(size 0.59 0.64)
			(layers "F.Cu" "F.Mask" "F.Paste")
			(roundrect_rratio 0.25)
			(net 67 "Net-(C47-Pad2)")
			(pintype "passive")
			(teardrops
				(best_length_ratio 0.2)
				(max_length 1)
				(best_width_ratio 0.9)
				(max_width 2)
				(curved_edges yes)
				(filter_ratio 0.9)
				(enabled yes)
				(allow_two_segments yes)
				(prefer_zone_connections yes)
			)
		)
	)
	(footprint "antmicro-footprints:SOT-23-3"
		(layer "F.Cu")
		(at 265.5 92.41 90)
		(property "Reference" "Q5"
			(at 1.45 0.45 180)
			(layer "F.SilkS")
			(effects
				(font
					(size 0.7 0.7)
					(thickness 0.15)
				)
				(justify left bottom)
			)
		)
		(property "Value" "BSS138-7-F"
			(at -1.9 2.7 90)
			(layer "F.Fab")
			(effects
				(font
					(size 0.7 0.7)
					(thickness 0.15)
				)
				(justify left bottom)
			)
		)
		(property "Datasheet" "https://www.diodes.com/assets/Datasheets/ds30144.pdf"
			(at 0 0 90)
			(layer "F.Fab")
			(hide yes)
			(effects
				(font
					(size 1.27 1.27)
					(thickness 0.15)
				)
			)
		)
		(property "Author" "Antmicro"
			(at 357.91 -173.09 0)
			(layer "F.Fab")
			(hide yes)
			(effects
				(font
					(size 1 1)
					(thickness 0.15)
				)
			)
		)
		(property "License" "Apache-2.0"
			(at 357.91 -173.09 0)
			(layer "F.Fab")
			(hide yes)
			(effects
				(font
					(size 1 1)
					(thickness 0.15)
				)
			)
		)
		(property "MPN" "BSS138-7-F"
			(at 357.91 -173.09 0)
			(layer "F.Fab")
			(hide yes)
			(effects
				(font
					(size 1 1)
					(thickness 0.15)
				)
			)
		)
		(property "Manufacturer" "Diodes Incorporated"
			(at 357.91 -173.09 0)
			(layer "F.Fab")
			(hide yes)
			(effects
				(font
					(size 1 1)
					(thickness 0.15)
				)
			)
		)
		(sheetname "Misc")
		(sheetfile "misc.kicad_sch")
		(attr smd)
		(fp_line
			(start 0.7 -1.5)
			(end -0.7 -1.5)
			(stroke
				(width 0.15)
				(type solid)
			)
			(layer "F.SilkS")
		)
		(fp_line
			(start -0.85 -1.35)
			(end -0.7 -1.5)
			(stroke
				(width 0.15)
				(type solid)
			)
			(layer "F.SilkS")
		)
		(fp_line
			(start -1.45 -1.35)
			(end -0.85 -1.35)
			(stroke
				(width 0.15)
				(type solid)
			)
			(layer "F.SilkS")
		)
		(fp_line
			(start 0.7 -0.4)
			(end 0.7 -1.5)
			(stroke
				(width 0.15)
				(type solid)
			)
			(layer "F.SilkS")
		)
		(fp_line
			(start 0.7 0.4)
			(end 0.7 1.5)
			(stroke
				(width 0.15)
				(type solid)
			)
			(layer "F.SilkS")
		)
		(fp_line
			(start 0.7 1.5)
			(end -0.7 1.5)
			(stroke
				(width 0.15)
				(type solid)
			)
			(layer "F.SilkS")
		)
		(fp_line
			(start -0.7 1.5)
			(end -0.7 1.35)
			(stroke
				(width 0.15)
				(type solid)
			)
			(layer "F.SilkS")
		)
		(fp_line
			(start 0.825 -1.6)
			(end 0.825 -0.45)
			(stroke
				(width 0.05)
				(type solid)
			)
			(layer "F.CrtYd")
		)
		(fp_line
			(start -0.9 -1.6)
			(end 0.825 -1.6)
			(stroke
				(width 0.05)
				(type solid)
			)
			(layer "F.CrtYd")
		)
		(fp_line
			(start -0.9 -1.6)
			(end -0.9 -1.4)
			(stroke
				(width 0.05)
				(type solid)
			)
			(layer "F.CrtYd")
		)
		(fp_line
			(start -0.9 -1.4)
			(end -1.75 -1.4)
			(stroke
				(width 0.05)
				(type solid)
			)
			(layer "F.CrtYd")
		)
		(fp_line
			(start -0.85 -0.5)
			(end -1.75 -0.5)
			(stroke
				(width 0.05)
				(type solid)
			)
			(layer "F.CrtYd")
		)
		(fp_line
			(start -1.75 -0.5)
			(end -1.75 -1.4)
			(stroke
				(width 0.05)
				(type solid)
			)
			(layer "F.CrtYd")
		)
		(fp_line
			(start 1.75 -0.45)
			(end 1.75 0.45)
			(stroke
				(width 0.05)
				(type solid)
			)
			(layer "F.CrtYd")
		)
		(fp_line
			(start 0.825 -0.45)
			(end 1.75 -0.45)
			(stroke
				(width 0.05)
				(type solid)
			)
			(layer "F.CrtYd")
		)
		(fp_line
			(start 1.75 0.45)
			(end 0.85 0.45)
			(stroke
				(width 0.05)
				(type solid)
			)
			(layer "F.CrtYd")
		)
		(fp_line
			(start 0.85 0.45)
			(end 0.85 1.65)
			(stroke
				(width 0.05)
				(type solid)
			)
			(layer "F.CrtYd")
		)
		(fp_line
			(start -0.85 0.5)
			(end -0.85 -0.5)
			(stroke
				(width 0.05)
				(type solid)
			)
			(layer "F.CrtYd")
		)
		(fp_line
			(start -1.75 0.5)
			(end -0.85 0.5)
			(stroke
				(width 0.05)
				(type solid)
			)
			(layer "F.CrtYd")
		)
		(fp_line
			(start -0.85 1.4)
			(end -1.75 1.4)
			(stroke
				(width 0.05)
				(type solid)
			)
			(layer "F.CrtYd")
		)
		(fp_line
			(start -1.75 1.4)
			(end -1.75 0.5)
			(stroke
				(width 0.05)
				(type solid)
			)
			(layer "F.CrtYd")
		)
		(fp_line
			(start 0.85 1.65)
			(end -0.85 1.65)
			(stroke
				(width 0.05)
				(type solid)
			)
			(layer "F.CrtYd")
		)
		(fp_line
			(start -0.85 1.65)
			(end -0.85 1.4)
			(stroke
				(width 0.05)
				(type solid)
			)
			(layer "F.CrtYd")
		)
		(fp_line
			(start -0.437 -1.526)
			(end 0.688 -1.526)
			(stroke
				(width 0.15)
				(type solid)
			)
			(layer "F.Fab")
		)
		(fp_line
			(start -0.437 -1.526)
			(end -0.712 -1.325)
			(stroke
				(width 0.15)
				(type solid)
			)
			(layer "F.Fab")
		)
		(fp_line
			(start -0.712 -1.325)
			(end -0.712 1.523)
			(stroke
				(width 0.15)
				(type solid)
			)
			(layer "F.Fab")
		)
		(fp_line
			(start 0.688 1.519)
			(end 0.688 -1.52)
			(stroke
				(width 0.15)
				(type solid)
			)
			(layer "F.Fab")
		)
		(fp_line
			(start -0.712 1.519)
			(end 0.688 1.519)
			(stroke
				(width 0.15)
				(type solid)
			)
			(layer "F.Fab")
		)
		(pad "1" smd roundrect
			(at -1.1 -0.951 90)
			(size 1 0.6)
			(layers "F.Cu" "F.Mask" "F.Paste")
			(roundrect_rratio 0.15)
			(net 528 "/Backplane/~{PERST}")
			(pinfunction "G")
			(pintype "bidirectional")
			(teardrops
				(best_length_ratio 0.2)
				(max_length 1)
				(best_width_ratio 0.9)
				(max_width 2)
				(curved_edges yes)
				(filter_ratio 0.9)
				(enabled yes)
				(allow_two_segments yes)
				(prefer_zone_connections yes)
			)
		)
		(pad "2" smd roundrect
			(at -1.1 0.949 90)
			(size 1 0.6)
			(layers "F.Cu" "F.Mask" "F.Paste")
			(roundrect_rratio 0.15)
			(net 1 "GND")
			(pinfunction "S")
			(pintype "bidirectional")
			(teardrops
				(best_length_ratio 0.2)
				(max_length 1)
				(best_width_ratio 0.9)
				(max_width 2)
				(curved_edges yes)
				(filter_ratio 0.9)
				(enabled yes)
				(allow_two_segments yes)
				(prefer_zone_connections yes)
			)
		)
		(pad "3" smd roundrect
			(at 1.1 -0.0005 90)
			(size 1 0.6)
			(layers "F.Cu" "F.Mask" "F.Paste")
			(roundrect_rratio 0.15)
			(net 538 "Net-(Q5-D)")
			(pinfunction "D")
			(pintype "bidirectional")
			(teardrops
				(best_length_ratio 0.2)
				(max_length 1)
				(best_width_ratio 0.9)
				(max_width 2)
				(curved_edges yes)
				(filter_ratio 0.9)
				(enabled yes)
				(allow_two_segments yes)
				(prefer_zone_connections yes)
			)
		)
	)
	(footprint "antmicro-footprints:L_Coilcraft-XAL6030"
		(layer "F.Cu")
		(at 311.064999 110.96 180)
		(property "Reference" "L2"
			(at 4.864999 -0.35 0)
			(unlocked yes)
			(layer "F.SilkS")
			(effects
				(font
					(size 0.7 0.7)
					(thickness 0.15)
				)
				(justify left bottom)
			)
		)
		(property "Value" "L_1u8_14A_Coilcraft-XAL6030"
			(at 0 4.7 180)
			(unlocked yes)
			(layer "F.Fab")
			(effects
				(font
					(size 0.7 0.7)
					(thickness 0.15)
				)
				(justify left bottom)
			)
		)
		(property "Datasheet" "https://www.mouser.com/datasheet/2/597/xal60xx-270658.pdf"
			(at 0 0 180)
			(layer "F.Fab")
			(hide yes)
			(effects
				(font
					(size 1.27 1.27)
					(thickness 0.15)
				)
			)
		)
		(property "Author" "Antmicro"
			(at 622.129998 221.92 0)
			(layer "F.Fab")
			(hide yes)
			(effects
				(font
					(size 1 1)
					(thickness 0.15)
				)
			)
		)
		(property "IMax" "14 A"
			(at 622.129998 221.92 0)
			(layer "F.Fab")
			(hide yes)
			(effects
				(font
					(size 1 1)
					(thickness 0.15)
				)
			)
		)
		(property "ISat" "18.2 A"
			(at 622.129998 221.92 0)
			(layer "F.Fab")
			(hide yes)
			(effects
				(font
					(size 1 1)
					(thickness 0.15)
				)
			)
		)
		(property "License" "Apache-2.0"
			(at 622.129998 221.92 0)
			(layer "F.Fab")
			(hide yes)
			(effects
				(font
					(size 1 1)
					(thickness 0.15)
				)
			)
		)
		(property "MPN" "XAL6030-182MEC"
			(at 622.129998 221.92 0)
			(layer "F.Fab")
			(hide yes)
			(effects
				(font
					(size 1 1)
					(thickness 0.15)
				)
			)
		)
		(property "Manufacturer" "Coilcraft"
			(at 622.129998 221.92 0)
			(layer "F.Fab")
			(hide yes)
			(effects
				(font
					(size 1 1)
					(thickness 0.15)
				)
			)
		)
		(property "Public" "False"
			(at 622.129998 221.92 0)
			(layer "F.Fab")
			(hide yes)
			(effects
				(font
					(size 1 1)
					(thickness 0.15)
				)
			)
		)
		(property "Size" "6.36x6.56"
			(at 622.129998 221.92 0)
			(layer "F.Fab")
			(hide yes)
			(effects
				(font
					(size 1 1)
					(thickness 0.15)
				)
			)
		)
		(property "Val" "1.8u/14A"
			(at 622.129998 221.92 0)
			(layer "F.Fab")
			(hide yes)
			(effects
				(font
					(size 1 1)
					(thickness 0.15)
				)
			)
		)
		(sheetname "Power")
		(sheetfile "power.kicad_sch")
		(attr smd)
		(fp_rect
			(start -3.299 -3.4)
			(end 3.299 3.4)
			(stroke
				(width 0.15)
				(type solid)
			)
			(fill no)
			(layer "F.SilkS")
		)
		(fp_rect
			(start -3.52 -3.63)
			(end 3.52 3.63)
			(stroke
				(width 0.05)
				(type solid)
			)
			(fill no)
			(layer "F.CrtYd")
		)
		(fp_rect
			(start -3.279 -3.38)
			(end 3.279 3.38)
			(stroke
				(width 0.15)
				(type solid)
			)
			(fill no)
			(layer "F.Fab")
		)
		(pad "1" smd roundrect
			(at -2.02 0 180)
			(size 1.43 5.5)
			(layers "F.Cu" "F.Mask" "F.Paste")
			(roundrect_rratio 0.1)
			(net 69 "Net-(C48-Pad2)")
			(pintype "passive")
			(teardrops
				(best_length_ratio 0.2)
				(max_length 1)
				(best_width_ratio 0.9)
				(max_width 2)
				(curved_edges yes)
				(filter_ratio 0.9)
				(enabled yes)
				(allow_two_segments yes)
				(prefer_zone_connections yes)
			)
		)
		(pad "2" smd roundrect
			(at 2.019 0 180)
			(size 1.43 5.5)
			(layers "F.Cu" "F.Mask" "F.Paste")
			(roundrect_rratio 0.1)
			(net 71 "Net-(U49-IN+)")
			(pintype "passive")
			(teardrops
				(best_length_ratio 0.2)
				(max_length 1)
				(best_width_ratio 0.9)
				(max_width 2)
				(curved_edges yes)
				(filter_ratio 0.9)
				(enabled yes)
				(allow_two_segments yes)
				(prefer_zone_connections yes)
			)
		)
	)
	(footprint "antmicro-footprints:TP_SMD_0.75mm"
		(layer "F.Cu")
		(at 196.057538 132.257538 45)
		(property "Reference" "TP53"
			(at 0.4 0.45 45)
			(layer "F.SilkS")
			(effects
				(font
					(size 0.7 0.7)
					(thickness 0.15)
				)
				(justify left bottom)
			)
		)
		(property "Value" "TP_0.75mm_SMD"
			(at 0 1.2 45)
			(layer "F.Fab")
			(effects
				(font
					(size 0.7 0.7)
					(thickness 0.15)
				)
				(justify left bottom)
			)
		)
		(property "Author" "Antmicro"
			(at 369.6 -269.12 45)
			(layer "F.Fab")
			(hide yes)
			(effects
				(font
					(size 1 1)
					(thickness 0.15)
				)
			)
		)
		(property "License" "Apache-2.0"
			(at 369.6 -269.12 45)
			(layer "F.Fab")
			(hide yes)
			(effects
				(font
					(size 1 1)
					(thickness 0.15)
				)
			)
		)
		(property "MPN" ""
			(at 369.6 -269.12 45)
			(layer "F.Fab")
			(hide yes)
			(effects
				(font
					(size 1 1)
					(thickness 0.15)
				)
			)
		)
		(property "Manufacturer" ""
			(at 369.6 -269.12 45)
			(layer "F.Fab")
			(hide yes)
			(effects
				(font
					(size 1 1)
					(thickness 0.15)
				)
			)
		)
		(property "Public" "False"
			(at 369.6 -269.12 45)
			(layer "F.Fab")
			(hide yes)
			(effects
				(font
					(size 1 1)
					(thickness 0.15)
				)
			)
		)
		(sheetname "PCIe redriver")
		(sheetfile "pcie_redriver.kicad_sch")
		(attr exclude_from_pos_files exclude_from_bom)
		(fp_circle
			(center 0 0)
			(end 0.475 0)
			(stroke
				(width 0.05)
				(type default)
			)
			(fill no)
			(layer "F.CrtYd")
		)
		(pad "1" smd circle
			(at 0 0 45)
			(size 0.75 0.75)
			(layers "F.Cu" "F.Mask")
			(net 716 "Net-(U40-SDA)")
			(pinfunction "1")
			(pintype "passive")
			(teardrops
				(best_length_ratio 0.4)
				(max_length 1)
				(best_width_ratio 0.9)
				(max_width 2)
				(curved_edges yes)
				(filter_ratio 0.9)
				(enabled yes)
				(allow_two_segments yes)
				(prefer_zone_connections yes)
			)
		)
	)
	(footprint "antmicro-footprints:SOT-23-3"
		(layer "F.Cu")
		(at 261.42 161.58 180)
		(property "Reference" "D21"
			(at 0.32 -1.72 90)
			(layer "F.SilkS")
			(effects
				(font
					(size 0.7 0.7)
					(thickness 0.15)
				)
				(justify right top)
			)
		)
		(property "Value" "BAT54C"
			(at -1.9 2.7 0)
			(layer "F.Fab")
			(effects
				(font
					(size 0.7 0.7)
					(thickness 0.15)
				)
				(justify right top)
			)
		)
		(property "Datasheet" "https://diotec.com/request/datasheet/bat54.pdf"
			(at 0 0 0)
			(layer "F.Fab")
			(hide yes)
			(effects
				(font
					(size 1.27 1.27)
					(thickness 0.15)
				)
			)
		)
		(property "Author" "Antmicro"
			(at 317.61 -19.19 90)
			(layer "F.Fab")
			(hide yes)
			(effects
				(font
					(size 1 1)
					(thickness 0.15)
				)
			)
		)
		(property "License" "Apache-2.0"
			(at 317.61 -19.19 90)
			(layer "F.Fab")
			(hide yes)
			(effects
				(font
					(size 1 1)
					(thickness 0.15)
				)
			)
		)
		(property "MPN" "BAT54C"
			(at 317.61 -19.19 90)
			(layer "F.Fab")
			(hide yes)
			(effects
				(font
					(size 1 1)
					(thickness 0.15)
				)
			)
		)
		(property "Manufacturer" "Diotec Semiconductor"
			(at 317.61 -19.19 90)
			(layer "F.Fab")
			(hide yes)
			(effects
				(font
					(size 1 1)
					(thickness 0.15)
				)
			)
		)
		(sheetname "Com Express 7 MGMT")
		(sheetfile "com_express_7_mgmt.kicad_sch")
		(attr smd)
		(fp_line
			(start 0.7 1.5)
			(end -0.7 1.5)
			(stroke
				(width 0.15)
				(type solid)
			)
			(layer "F.SilkS")
		)
		(fp_line
			(start 0.7 0.4)
			(end 0.7 1.5)
			(stroke
				(width 0.15)
				(type solid)
			)
			(layer "F.SilkS")
		)
		(fp_line
			(start 0.7 -0.4)
			(end 0.7 -1.5)
			(stroke
				(width 0.15)
				(type solid)
			)
			(layer "F.SilkS")
		)
		(fp_line
			(start 0.7 -1.5)
			(end -0.7 -1.5)
			(stroke
				(width 0.15)
				(type solid)
			)
			(layer "F.SilkS")
		)
		(fp_line
			(start -0.7 1.5)
			(end -0.7 1.35)
			(stroke
				(width 0.15)
				(type solid)
			)
			(layer "F.SilkS")
		)
		(fp_line
			(start -0.85 -1.35)
			(end -0.7 -1.5)
			(stroke
				(width 0.15)
				(type solid)
			)
			(layer "F.SilkS")
		)
		(fp_line
			(start -1.45 -1.35)
			(end -0.85 -1.35)
			(stroke
				(width 0.15)
				(type solid)
			)
			(layer "F.SilkS")
		)
		(fp_line
			(start 1.75 0.45)
			(end 0.85 0.45)
			(stroke
				(width 0.05)
				(type solid)
			)
			(layer "F.CrtYd")
		)
		(fp_line
			(start 1.75 -0.45)
			(end 1.75 0.45)
			(stroke
				(width 0.05)
				(type solid)
			)
			(layer "F.CrtYd")
		)
		(fp_line
			(start 0.85 1.65)
			(end -0.85 1.65)
			(stroke
				(width 0.05)
				(type solid)
			)
			(layer "F.CrtYd")
		)
		(fp_line
			(start 0.85 0.45)
			(end 0.85 1.65)
			(stroke
				(width 0.05)
				(type solid)
			)
			(layer "F.CrtYd")
		)
		(fp_line
			(start 0.825 -0.45)
			(end 1.75 -0.45)
			(stroke
				(width 0.05)
				(type solid)
			)
			(layer "F.CrtYd")
		)
		(fp_line
			(start 0.825 -1.6)
			(end 0.825 -0.45)
			(stroke
				(width 0.05)
				(type solid)
			)
			(layer "F.CrtYd")
		)
		(fp_line
			(start -0.85 1.65)
			(end -0.85 1.4)
			(stroke
				(width 0.05)
				(type solid)
			)
			(layer "F.CrtYd")
		)
		(fp_line
			(start -0.85 1.4)
			(end -1.75 1.4)
			(stroke
				(width 0.05)
				(type solid)
			)
			(layer "F.CrtYd")
		)
		(fp_line
			(start -0.85 0.5)
			(end -0.85 -0.5)
			(stroke
				(width 0.05)
				(type solid)
			)
			(layer "F.CrtYd")
		)
		(fp_line
			(start -0.85 -0.5)
			(end -1.75 -0.5)
			(stroke
				(width 0.05)
				(type solid)
			)
			(layer "F.CrtYd")
		)
		(fp_line
			(start -0.9 -1.4)
			(end -1.75 -1.4)
			(stroke
				(width 0.05)
				(type solid)
			)
			(layer "F.CrtYd")
		)
		(fp_line
			(start -0.9 -1.6)
			(end 0.825 -1.6)
			(stroke
				(width 0.05)
				(type solid)
			)
			(layer "F.CrtYd")
		)
		(fp_line
			(start -0.9 -1.6)
			(end -0.9 -1.4)
			(stroke
				(width 0.05)
				(type solid)
			)
			(layer "F.CrtYd")
		)
		(fp_line
			(start -1.75 1.4)
			(end -1.75 0.5)
			(stroke
				(width 0.05)
				(type solid)
			)
			(layer "F.CrtYd")
		)
		(fp_line
			(start -1.75 0.5)
			(end -0.85 0.5)
			(stroke
				(width 0.05)
				(type solid)
			)
			(layer "F.CrtYd")
		)
		(fp_line
			(start -1.75 -0.5)
			(end -1.75 -1.4)
			(stroke
				(width 0.05)
				(type solid)
			)
			(layer "F.CrtYd")
		)
		(fp_line
			(start 0.688 1.519)
			(end 0.688 -1.52)
			(stroke
				(width 0.15)
				(type solid)
			)
			(layer "F.Fab")
		)
		(fp_line
			(start -0.437 -1.526)
			(end 0.688 -1.526)
			(stroke
				(width 0.15)
				(type solid)
			)
			(layer "F.Fab")
		)
		(fp_line
			(start -0.437 -1.526)
			(end -0.712 -1.325)
			(stroke
				(width 0.15)
				(type solid)
			)
			(layer "F.Fab")
		)
		(fp_line
			(start -0.712 1.519)
			(end 0.688 1.519)
			(stroke
				(width 0.15)
				(type solid)
			)
			(layer "F.Fab")
		)
		(fp_line
			(start -0.712 -1.325)
			(end -0.712 1.523)
			(stroke
				(width 0.15)
				(type solid)
			)
			(layer "F.Fab")
		)
		(pad "1" smd roundrect
			(at -1.1 -0.951 180)
			(size 1 0.6)
			(layers "F.Cu" "F.Mask" "F.Paste")
			(roundrect_rratio 0.15)
			(net 139 "/Com Express 7 MGMT/SPI_POWER")
			(pinfunction "1")
			(pintype "passive")
			(teardrops
				(best_length_ratio 0.2)
				(max_length 1)
				(best_width_ratio 0.9)
				(max_width 2)
				(curved_edges yes)
				(filter_ratio 0.9)
				(enabled yes)
				(allow_two_segments yes)
				(prefer_zone_connections yes)
			)
		)
		(pad "2" smd roundrect
			(at -1.1 0.949 180)
			(size 1 0.6)
			(layers "F.Cu" "F.Mask" "F.Paste")
			(roundrect_rratio 0.15)
			(net 140 "unconnected-(D21-Pad2)")
			(pinfunction "2")
			(pintype "passive+no_connect")
			(teardrops
				(best_length_ratio 0.2)
				(max_length 1)
				(best_width_ratio 0.9)
				(max_width 2)
				(curved_edges yes)
				(filter_ratio 0.9)
				(enabled yes)
				(allow_two_segments yes)
				(prefer_zone_connections yes)
			)
		)
		(pad "3" smd roundrect
			(at 1.1 -0.0005 180)
			(size 1 0.6)
			(layers "F.Cu" "F.Mask" "F.Paste")
			(roundrect_rratio 0.15)
			(net 85 "/Com Express 7 MGMT/MAFS_POWER")
			(pinfunction "3")
			(pintype "passive")
			(teardrops
				(best_length_ratio 0.2)
				(max_length 1)
				(best_width_ratio 0.9)
				(max_width 2)
				(curved_edges yes)
				(filter_ratio 0.9)
				(enabled yes)
				(allow_two_segments yes)
				(prefer_zone_connections yes)
			)
		)
	)
	(footprint "antmicro-footprints:R_0402_1005Metric"
		(layer "F.Cu")
		(at 178.4 148 180)
		(descr "Resistor SMD 0402")
		(tags "resistor SMD 0402")
		(property "Reference" "R41"
			(at -2.95 -0.45 0)
			(layer "F.SilkS")
			(effects
				(font
					(size 0.7 0.7)
					(thickness 0.15)
				)
				(justify right bottom)
			)
		)
		(property "Value" "R_0R_0402"
			(at -1.011843 1.772046 0)
			(layer "F.Fab")
			(effects
				(font
					(size 0.7 0.7)
					(thickness 0.15)
				)
				(justify right bottom)
			)
		)
		(property "Datasheet" "https://industrial.panasonic.com/cdbs/www-data/pdf/RDA0000/AOA0000C301.pdf"
			(at 0 0 0)
			(layer "F.Fab")
			(hide yes)
			(effects
				(font
					(size 1.27 1.27)
					(thickness 0.15)
				)
			)
		)
		(property "Author" "Antmicro"
			(at 337.899999 336.52 0)
			(layer "F.Fab")
			(hide yes)
			(effects
				(font
					(size 1 1)
					(thickness 0.15)
				)
			)
		)
		(property "Current" "1A"
			(at 337.899999 336.52 0)
			(layer "F.Fab")
			(hide yes)
			(effects
				(font
					(size 1 1)
					(thickness 0.15)
				)
			)
		)
		(property "License" "Apache-2.0"
			(at 337.899999 336.52 0)
			(layer "F.Fab")
			(hide yes)
			(effects
				(font
					(size 1 1)
					(thickness 0.15)
				)
			)
		)
		(property "MPN" "ERJ2GE0R00X"
			(at 337.899999 336.52 0)
			(layer "F.Fab")
			(hide yes)
			(effects
				(font
					(size 1 1)
					(thickness 0.15)
				)
			)
		)
		(property "Manufacturer" "Panasonic"
			(at 337.899999 336.52 0)
			(layer "F.Fab")
			(hide yes)
			(effects
				(font
					(size 1 1)
					(thickness 0.15)
				)
			)
		)
		(property "Public" "False"
			(at 337.899999 336.52 0)
			(layer "F.Fab")
			(hide yes)
			(effects
				(font
					(size 1 1)
					(thickness 0.15)
				)
			)
		)
		(property "Tolerance" ""
			(at 337.899999 336.52 0)
			(layer "F.Fab")
			(hide yes)
			(effects
				(font
					(size 1 1)
					(thickness 0.15)
				)
			)
		)
		(property "Val" "0R"
			(at 337.899999 336.52 0)
			(layer "F.Fab")
			(hide yes)
			(effects
				(font
					(size 1 1)
					(thickness 0.15)
				)
			)
		)
		(sheetname "2xSFP+")
		(sheetfile "2xSFP+.kicad_sch")
		(attr smd)
		(fp_rect
			(start -0.925 -0.47)
			(end 0.925 0.47)
			(stroke
				(width 0.05)
				(type default)
			)
			(fill no)
			(layer "F.CrtYd")
		)
		(fp_rect
			(start -0.5 -0.25)
			(end 0.5 0.25)
			(stroke
				(width 0.15)
				(type solid)
			)
			(fill no)
			(layer "F.Fab")
		)
		(pad "1" smd roundrect
			(at -0.48 0 180)
			(size 0.59 0.64)
			(layers "F.Cu" "F.Mask" "F.Paste")
			(roundrect_rratio 0.25)
			(net 487 "/2xSFP+/I2C_{SFP1}.SCL")
			(pintype "passive")
			(teardrops
				(best_length_ratio 0.2)
				(max_length 1)
				(best_width_ratio 0.9)
				(max_width 2)
				(curved_edges yes)
				(filter_ratio 0.9)
				(enabled yes)
				(allow_two_segments yes)
				(prefer_zone_connections yes)
			)
		)
		(pad "2" smd roundrect
			(at 0.48 0 180)
			(size 0.59 0.64)
			(layers "F.Cu" "F.Mask" "F.Paste")
			(roundrect_rratio 0.25)
			(net 875 "/2xSFP+/SCL1")
			(pintype "passive")
			(teardrops
				(best_length_ratio 0.2)
				(max_length 1)
				(best_width_ratio 0.9)
				(max_width 2)
				(curved_edges yes)
				(filter_ratio 0.9)
				(enabled yes)
				(allow_two_segments yes)
				(prefer_zone_connections yes)
			)
		)
	)
	(footprint "antmicro-footprints:R_0402_1005Metric"
		(layer "F.Cu")
		(at 309.174999 120.16 -90)
		(descr "Resistor SMD 0402")
		(tags "resistor SMD 0402")
		(property "Reference" "R98"
			(at -1.1 0.524999 270)
			(layer "F.SilkS")
			(effects
				(font
					(size 0.7 0.7)
					(thickness 0.15)
				)
				(justify right bottom)
			)
		)
		(property "Value" "R_15k_0402"
			(at -1.011843 1.772047 90)
			(layer "F.Fab")
			(effects
				(font
					(size 0.7 0.7)
					(thickness 0.15)
				)
				(justify right bottom)
			)
		)
		(property "Datasheet" "https://www.bourns.com/docs/product-datasheets/cr.pdf"
			(at 0 0 270)
			(layer "F.Fab")
			(hide yes)
			(effects
				(font
					(size 1.27 1.27)
					(thickness 0.15)
				)
			)
		)
		(property "Author" "Antmicro"
			(at 189.014999 429.334999 0)
			(layer "F.Fab")
			(hide yes)
			(effects
				(font
					(size 1 1)
					(thickness 0.15)
				)
			)
		)
		(property "License" "Apache-2.0"
			(at 189.014999 429.334999 0)
			(layer "F.Fab")
			(hide yes)
			(effects
				(font
					(size 1 1)
					(thickness 0.15)
				)
			)
		)
		(property "MPN" "CR0402-FX-1502GLF"
			(at 189.014999 429.334999 0)
			(layer "F.Fab")
			(hide yes)
			(effects
				(font
					(size 1 1)
					(thickness 0.15)
				)
			)
		)
		(property "Manufacturer" "Bourns"
			(at 189.014999 429.334999 0)
			(layer "F.Fab")
			(hide yes)
			(effects
				(font
					(size 1 1)
					(thickness 0.15)
				)
			)
		)
		(property "Public" "False"
			(at 189.014999 429.334999 0)
			(layer "F.Fab")
			(hide yes)
			(effects
				(font
					(size 1 1)
					(thickness 0.15)
				)
			)
		)
		(property "Tolerance" "1%"
			(at 189.014999 429.334999 0)
			(layer "F.Fab")
			(hide yes)
			(effects
				(font
					(size 1 1)
					(thickness 0.15)
				)
			)
		)
		(property "Val" "15k"
			(at 189.014999 429.334999 0)
			(layer "F.Fab")
			(hide yes)
			(effects
				(font
					(size 1 1)
					(thickness 0.15)
				)
			)
		)
		(sheetname "Power")
		(sheetfile "power.kicad_sch")
		(attr smd)
		(fp_rect
			(start -0.925 -0.47)
			(end 0.925 0.47)
			(stroke
				(width 0.05)
				(type default)
			)
			(fill no)
			(layer "F.CrtYd")
		)
		(fp_rect
			(start -0.5 -0.25)
			(end 0.5 0.25)
			(stroke
				(width 0.15)
				(type solid)
			)
			(fill no)
			(layer "F.Fab")
		)
		(pad "1" smd roundrect
			(at -0.48 0 270)
			(size 0.59 0.64)
			(layers "F.Cu" "F.Mask" "F.Paste")
			(roundrect_rratio 0.25)
			(net 1 "GND")
			(pintype "passive")
			(teardrops
				(best_length_ratio 0.2)
				(max_length 1)
				(best_width_ratio 0.9)
				(max_width 2)
				(curved_edges yes)
				(filter_ratio 0.9)
				(enabled yes)
				(allow_two_segments yes)
				(prefer_zone_connections yes)
			)
		)
		(pad "2" smd roundrect
			(at 0.48 0 270)
			(size 0.59 0.64)
			(layers "F.Cu" "F.Mask" "F.Paste")
			(roundrect_rratio 0.25)
			(net 580 "Net-(U18-FB)")
			(pintype "passive")
			(teardrops
				(best_length_ratio 0.2)
				(max_length 1)
				(best_width_ratio 0.9)
				(max_width 2)
				(curved_edges yes)
				(filter_ratio 0.9)
				(enabled yes)
				(allow_two_segments yes)
				(prefer_zone_connections yes)
			)
		)
	)
	(footprint "antmicro-footprints:R_0402_1005Metric"
		(layer "F.Cu")
		(at 252.665 89.449999)
		(descr "Resistor SMD 0402")
		(tags "resistor SMD 0402")
		(property "Reference" "R151"
			(at -0.865 0.440001 0)
			(layer "F.SilkS")
			(effects
				(font
					(size 0.7 0.7)
					(thickness 0.15)
				)
				(justify right bottom)
			)
		)
		(property "Value" "R_0R_0402"
			(at -1.011843 1.772047 0)
			(layer "F.Fab")
			(effects
				(font
					(size 0.7 0.7)
					(thickness 0.15)
				)
				(justify left bottom)
			)
		)
		(property "Datasheet" "https://industrial.panasonic.com/cdbs/www-data/pdf/RDA0000/AOA0000C301.pdf"
			(at 0 0 0)
			(layer "F.Fab")
			(hide yes)
			(effects
				(font
					(size 1.27 1.27)
					(thickness 0.15)
				)
			)
		)
		(property "Author" "Antmicro"
			(at 0 0 0)
			(layer "F.Fab")
			(hide yes)
			(effects
				(font
					(size 1 1)
					(thickness 0.15)
				)
			)
		)
		(property "Current" "1A"
			(at 0 0 0)
			(layer "F.Fab")
			(hide yes)
			(effects
				(font
					(size 1 1)
					(thickness 0.15)
				)
			)
		)
		(property "License" "Apache-2.0"
			(at 0 0 0)
			(layer "F.Fab")
			(hide yes)
			(effects
				(font
					(size 1 1)
					(thickness 0.15)
				)
			)
		)
		(property "MPN" "ERJ2GE0R00X"
			(at 0 0 0)
			(layer "F.Fab")
			(hide yes)
			(effects
				(font
					(size 1 1)
					(thickness 0.15)
				)
			)
		)
		(property "Manufacturer" "Panasonic"
			(at 0 0 0)
			(layer "F.Fab")
			(hide yes)
			(effects
				(font
					(size 1 1)
					(thickness 0.15)
				)
			)
		)
		(property "Public" "False"
			(at 0 0 0)
			(layer "F.Fab")
			(hide yes)
			(effects
				(font
					(size 1 1)
					(thickness 0.15)
				)
			)
		)
		(property "Tolerance" ""
			(at 0 0 0)
			(layer "F.Fab")
			(hide yes)
			(effects
				(font
					(size 1 1)
					(thickness 0.15)
				)
			)
		)
		(property "Val" "0R"
			(at 0 0 0)
			(layer "F.Fab")
			(hide yes)
			(effects
				(font
					(size 1 1)
					(thickness 0.15)
				)
			)
		)
		(sheetname "Misc")
		(sheetfile "misc.kicad_sch")
		(attr smd)
		(fp_rect
			(start -0.925 -0.47)
			(end 0.925 0.47)
			(stroke
				(width 0.05)
				(type default)
			)
			(fill no)
			(layer "F.CrtYd")
		)
		(fp_rect
			(start -0.5 -0.25)
			(end 0.5 0.25)
			(stroke
				(width 0.15)
				(type solid)
			)
			(fill no)
			(layer "F.Fab")
		)
		(pad "1" smd roundrect
			(at -0.48 0)
			(size 0.59 0.64)
			(layers "F.Cu" "F.Mask" "F.Paste")
			(roundrect_rratio 0.25)
			(net 78 "+1V8")
			(pintype "passive")
			(teardrops
				(best_length_ratio 0.2)
				(max_length 1)
				(best_width_ratio 0.9)
				(max_width 2)
				(curved_edges yes)
				(filter_ratio 0.9)
				(enabled yes)
				(allow_two_segments yes)
				(prefer_zone_connections yes)
			)
		)
		(pad "2" smd roundrect
			(at 0.48 0)
			(size 0.59 0.64)
			(layers "F.Cu" "F.Mask" "F.Paste")
			(roundrect_rratio 0.25)
			(net 593 "Net-(U24-V_{CCP})")
			(pintype "passive")
			(teardrops
				(best_length_ratio 0.2)
				(max_length 1)
				(best_width_ratio 0.9)
				(max_width 2)
				(curved_edges yes)
				(filter_ratio 0.9)
				(enabled yes)
				(allow_two_segments yes)
				(prefer_zone_connections yes)
			)
		)
	)
	(footprint "antmicro-footprints:TP_SMD_0.75mm"
		(layer "F.Cu")
		(at 193.70861 72.802163 -90)
		(property "Reference" "TP102"
			(at 0 -0.6 90)
			(layer "F.SilkS")
			(hide yes)
			(effects
				(font
					(size 0.7 0.7)
					(thickness 0.15)
				)
				(justify right bottom)
			)
		)
		(property "Value" "TP_0.75mm_SMD"
			(at 0 1.2 90)
			(layer "F.Fab")
			(effects
				(font
					(size 0.7 0.7)
					(thickness 0.15)
				)
				(justify right bottom)
			)
		)
		(property "Author" "Antmicro"
			(at 120.906447 266.510773 0)
			(layer "F.Fab")
			(hide yes)
			(effects
				(font
					(size 1 1)
					(thickness 0.15)
				)
			)
		)
		(property "License" "Apache-2.0"
			(at 120.906447 266.510773 0)
			(layer "F.Fab")
			(hide yes)
			(effects
				(font
					(size 1 1)
					(thickness 0.15)
				)
			)
		)
		(property "MPN" ""
			(at 120.906447 266.510773 0)
			(layer "F.Fab")
			(hide yes)
			(effects
				(font
					(size 1 1)
					(thickness 0.15)
				)
			)
		)
		(property "Manufacturer" ""
			(at 120.906447 266.510773 0)
			(layer "F.Fab")
			(hide yes)
			(effects
				(font
					(size 1 1)
					(thickness 0.15)
				)
			)
		)
		(property "Public" "False"
			(at 120.906447 266.510773 0)
			(layer "F.Fab")
			(hide yes)
			(effects
				(font
					(size 1 1)
					(thickness 0.15)
				)
			)
		)
		(sheetname "Power")
		(sheetfile "power.kicad_sch")
		(attr exclude_from_pos_files exclude_from_bom)
		(fp_circle
			(center 0 0)
			(end 0.475 0)
			(stroke
				(width 0.05)
				(type default)
			)
			(fill no)
			(layer "F.CrtYd")
		)
		(pad "1" smd circle
			(at 0 0 270)
			(size 0.75 0.75)
			(layers "F.Cu" "F.Mask")
			(net 65 "+12V")
			(pinfunction "1")
			(pintype "passive")
			(teardrops
				(best_length_ratio 0.4)
				(max_length 1)
				(best_width_ratio 0.9)
				(max_width 2)
				(curved_edges yes)
				(filter_ratio 0.9)
				(enabled yes)
				(allow_two_segments yes)
				(prefer_zone_connections yes)
			)
		)
	)
	(footprint "antmicro-footprints:C_0402_1005Metric"
		(layer "F.Cu")
		(at 124.84 140.86)
		(descr "Capacitor SMD 0402")
		(tags "capacitor SMD 0402")
		(property "Reference" "C178"
			(at -3.69 0.45 180)
			(layer "F.SilkS")
			(effects
				(font
					(size 0.7 0.7)
					(thickness 0.15)
				)
				(justify left bottom)
			)
		)
		(property "Value" "C_100n_0402"
			(at -1.022927 2.155213 0)
			(layer "F.Fab")
			(effects
				(font
					(size 0.7 0.7)
					(thickness 0.15)
				)
				(justify left bottom)
			)
		)
		(property "Datasheet" "https://www.murata.com/products/productdetail?partno=GRM155R61H104KE14%23"
			(at 0 0 0)
			(layer "F.Fab")
			(hide yes)
			(effects
				(font
					(size 1.27 1.27)
					(thickness 0.15)
				)
			)
		)
		(property "Author" "Antmicro"
			(at 0 0 0)
			(layer "F.Fab")
			(hide yes)
			(effects
				(font
					(size 1 1)
					(thickness 0.15)
				)
			)
		)
		(property "Dielectric" "X5R"
			(at 0 0 0)
			(layer "F.Fab")
			(hide yes)
			(effects
				(font
					(size 1 1)
					(thickness 0.15)
				)
			)
		)
		(property "License" "Apache-2.0"
			(at 0 0 0)
			(layer "F.Fab")
			(hide yes)
			(effects
				(font
					(size 1 1)
					(thickness 0.15)
				)
			)
		)
		(property "MPN" "GRM155R61H104KE14D"
			(at 0 0 0)
			(layer "F.Fab")
			(hide yes)
			(effects
				(font
					(size 1 1)
					(thickness 0.15)
				)
			)
		)
		(property "Manufacturer" "Murata"
			(at 0 0 0)
			(layer "F.Fab")
			(hide yes)
			(effects
				(font
					(size 1 1)
					(thickness 0.15)
				)
			)
		)
		(property "Public" "False"
			(at 0 0 0)
			(layer "F.Fab")
			(hide yes)
			(effects
				(font
					(size 1 1)
					(thickness 0.15)
				)
			)
		)
		(property "Val" "100n"
			(at 0 0 0)
			(layer "F.Fab")
			(hide yes)
			(effects
				(font
					(size 1 1)
					(thickness 0.15)
				)
			)
		)
		(property "Voltage" "50V"
			(at 0 0 0)
			(layer "F.Fab")
			(hide yes)
			(effects
				(font
					(size 1 1)
					(thickness 0.15)
				)
			)
		)
		(sheetname "KR to SFI #2")
		(sheetfile "kr_sfi.kicad_sch")
		(attr smd)
		(fp_rect
			(start -0.925 -0.47)
			(end 0.925 0.47)
			(stroke
				(width 0.05)
				(type default)
			)
			(fill no)
			(layer "F.CrtYd")
		)
		(fp_line
			(start -0.494 -0.25)
			(end 0.504 -0.25)
			(stroke
				(width 0.15)
				(type solid)
			)
			(layer "F.Fab")
		)
		(fp_line
			(start -0.494 0.248)
			(end -0.494 -0.25)
			(stroke
				(width 0.15)
				(type solid)
			)
			(layer "F.Fab")
		)
		(fp_line
			(start 0.504 -0.25)
			(end 0.504 0.248)
			(stroke
				(width 0.15)
				(type solid)
			)
			(layer "F.Fab")
		)
		(fp_line
			(start 0.504 0.248)
			(end -0.494 0.248)
			(stroke
				(width 0.15)
				(type solid)
			)
			(layer "F.Fab")
		)
		(pad "1" smd roundrect
			(at -0.48 0)
			(size 0.59 0.64)
			(layers "F.Cu" "F.Mask" "F.Paste")
			(roundrect_rratio 0.25)
			(net 117 "/2xSFP+/KR to SFI #2/CLK-")
			(pintype "passive")
			(teardrops
				(best_length_ratio 0.2)
				(max_length 1)
				(best_width_ratio 0.9)
				(max_width 2)
				(curved_edges yes)
				(filter_ratio 0.9)
				(enabled yes)
				(allow_two_segments yes)
				(prefer_zone_connections yes)
			)
		)
		(pad "2" smd roundrect
			(at 0.48 0)
			(size 0.59 0.64)
			(layers "F.Cu" "F.Mask" "F.Paste")
			(roundrect_rratio 0.25)
			(net 116 "/2xSFP+/KR to SFI #2/REFCLK+")
			(pintype "passive")
			(teardrops
				(best_length_ratio 0.2)
				(max_length 1)
				(best_width_ratio 0.9)
				(max_width 2)
				(curved_edges yes)
				(filter_ratio 0.9)
				(enabled yes)
				(allow_two_segments yes)
				(prefer_zone_connections yes)
			)
		)
	)
	(footprint "antmicro-footprints:C_0603_1608Metric"
		(layer "F.Cu")
		(at 315.625499 134.21 90)
		(descr "Capacitor SMD 0603")
		(tags "capacitor 0603")
		(property "Reference" "C60"
			(at 1.15 0.474501 90)
			(layer "F.SilkS")
			(effects
				(font
					(size 0.7 0.7)
					(thickness 0.15)
				)
				(justify left bottom)
			)
		)
		(property "Value" "C_22u_16V_0603"
			(at -1.42757 1.770288 90)
			(layer "F.Fab")
			(effects
				(font
					(size 0.7 0.7)
					(thickness 0.15)
				)
				(justify left bottom)
			)
		)
		(property "Datasheet" "https://product.samsungsem.com/mlcc/CL10A226MO7JZN.do"
			(at 0 0 90)
			(layer "F.Fab")
			(hide yes)
			(effects
				(font
					(size 1.27 1.27)
					(thickness 0.15)
				)
			)
		)
		(property "Author" "Antmicro"
			(at 449.835499 -181.415499 0)
			(layer "F.Fab")
			(hide yes)
			(effects
				(font
					(size 1 1)
					(thickness 0.15)
				)
			)
		)
		(property "Dielectric" ""
			(at 449.835499 -181.415499 0)
			(layer "F.Fab")
			(hide yes)
			(effects
				(font
					(size 1 1)
					(thickness 0.15)
				)
			)
		)
		(property "License" "Apache-2.0"
			(at 449.835499 -181.415499 0)
			(layer "F.Fab")
			(hide yes)
			(effects
				(font
					(size 1 1)
					(thickness 0.15)
				)
			)
		)
		(property "MPN" "CL10A226MO7JZNC"
			(at 449.835499 -181.415499 0)
			(layer "F.Fab")
			(hide yes)
			(effects
				(font
					(size 1 1)
					(thickness 0.15)
				)
			)
		)
		(property "Manufacturer" "Samsung Electro-Mechanics"
			(at 449.835499 -181.415499 0)
			(layer "F.Fab")
			(hide yes)
			(effects
				(font
					(size 1 1)
					(thickness 0.15)
				)
			)
		)
		(property "Public" "False"
			(at 449.835499 -181.415499 0)
			(layer "F.Fab")
			(hide yes)
			(effects
				(font
					(size 1 1)
					(thickness 0.15)
				)
			)
		)
		(property "Val" "22u"
			(at 449.835499 -181.415499 0)
			(layer "F.Fab")
			(hide yes)
			(effects
				(font
					(size 1 1)
					(thickness 0.15)
				)
			)
		)
		(property "Voltage" "16V"
			(at 449.835499 -181.415499 0)
			(layer "F.Fab")
			(hide yes)
			(effects
				(font
					(size 1 1)
					(thickness 0.15)
				)
			)
		)
		(sheetname "Power")
		(sheetfile "power.kicad_sch")
		(attr smd)
		(fp_line
			(start -0.15 -0.4)
			(end 0.15 -0.4)
			(stroke
				(width 0.15)
				(type solid)
			)
			(layer "F.SilkS")
		)
		(fp_line
			(start -0.15 0.4)
			(end 0.15 0.4)
			(stroke
				(width 0.15)
				(type solid)
			)
			(layer "F.SilkS")
		)
		(fp_rect
			(start -1.25 -0.65)
			(end 1.25 0.65)
			(stroke
				(width 0.05)
				(type solid)
			)
			(fill no)
			(layer "F.CrtYd")
		)
		(fp_rect
			(start -0.8 -0.4)
			(end 0.8 0.4)
			(stroke
				(width 0.15)
				(type solid)
			)
			(fill no)
			(layer "F.Fab")
		)
		(pad "1" smd roundrect
			(at -0.7 0 90)
			(size 0.8 1)
			(layers "F.Cu" "F.Mask" "F.Paste")
			(roundrect_rratio 0.2)
			(net 1 "GND")
			(pintype "passive")
			(teardrops
				(best_length_ratio 0.2)
				(max_length 1)
				(best_width_ratio 0.9)
				(max_width 2)
				(curved_edges yes)
				(filter_ratio 0.9)
				(enabled yes)
				(allow_two_segments yes)
				(prefer_zone_connections yes)
			)
		)
		(pad "2" smd roundrect
			(at 0.7 0 90)
			(size 0.8 1)
			(layers "F.Cu" "F.Mask" "F.Paste")
			(roundrect_rratio 0.2)
			(net 62 "+12V_AON")
			(pintype "passive")
			(teardrops
				(best_length_ratio 0.2)
				(max_length 1)
				(best_width_ratio 0.9)
				(max_width 2)
				(curved_edges yes)
				(filter_ratio 0.9)
				(enabled yes)
				(allow_two_segments yes)
				(prefer_zone_connections yes)
			)
		)
	)
	(footprint "antmicro-footprints:R_0402_1005Metric"
		(layer "F.Cu")
		(at 126.425 83.06 180)
		(descr "Resistor SMD 0402")
		(tags "resistor SMD 0402")
		(property "Reference" "R238"
			(at -1.575 -6.4 0)
			(layer "F.SilkS")
			(effects
				(font
					(size 0.7 0.7)
					(thickness 0.15)
				)
				(justify right bottom)
			)
		)
		(property "Value" "R_0R_0402"
			(at -1.011843 1.772047 0)
			(layer "F.Fab")
			(effects
				(font
					(size 0.7 0.7)
					(thickness 0.15)
				)
				(justify right bottom)
			)
		)
		(property "Datasheet" "https://industrial.panasonic.com/cdbs/www-data/pdf/RDA0000/AOA0000C301.pdf"
			(at 0 0 180)
			(layer "F.Fab")
			(hide yes)
			(effects
				(font
					(size 1.27 1.27)
					(thickness 0.15)
				)
			)
		)
		(property "Author" "Antmicro"
			(at 252.85 166.12 0)
			(layer "F.Fab")
			(hide yes)
			(effects
				(font
					(size 1 1)
					(thickness 0.15)
				)
			)
		)
		(property "Current" "1A"
			(at 252.85 166.12 0)
			(layer "F.Fab")
			(hide yes)
			(effects
				(font
					(size 1 1)
					(thickness 0.15)
				)
			)
		)
		(property "License" "Apache-2.0"
			(at 252.85 166.12 0)
			(layer "F.Fab")
			(hide yes)
			(effects
				(font
					(size 1 1)
					(thickness 0.15)
				)
			)
		)
		(property "MPN" "ERJ2GE0R00X"
			(at 252.85 166.12 0)
			(layer "F.Fab")
			(hide yes)
			(effects
				(font
					(size 1 1)
					(thickness 0.15)
				)
			)
		)
		(property "Manufacturer" "Panasonic"
			(at 252.85 166.12 0)
			(layer "F.Fab")
			(hide yes)
			(effects
				(font
					(size 1 1)
					(thickness 0.15)
				)
			)
		)
		(property "Public" "False"
			(at 252.85 166.12 0)
			(layer "F.Fab")
			(hide yes)
			(effects
				(font
					(size 1 1)
					(thickness 0.15)
				)
			)
		)
		(property "Tolerance" ""
			(at 252.85 166.12 0)
			(layer "F.Fab")
			(hide yes)
			(effects
				(font
					(size 1 1)
					(thickness 0.15)
				)
			)
		)
		(property "Val" "0R"
			(at 252.85 166.12 0)
			(layer "F.Fab")
			(hide yes)
			(effects
				(font
					(size 1 1)
					(thickness 0.15)
				)
			)
		)
		(sheetname "GPIO expander")
		(sheetfile "gpio_exp.kicad_sch")
		(attr smd)
		(fp_rect
			(start -0.925 -0.47)
			(end 0.925 0.47)
			(stroke
				(width 0.05)
				(type default)
			)
			(fill no)
			(layer "F.CrtYd")
		)
		(fp_rect
			(start -0.5 -0.25)
			(end 0.5 0.25)
			(stroke
				(width 0.15)
				(type solid)
			)
			(fill no)
			(layer "F.Fab")
		)
		(pad "1" smd roundrect
			(at -0.48 0 180)
			(size 0.59 0.64)
			(layers "F.Cu" "F.Mask" "F.Paste")
			(roundrect_rratio 0.25)
			(net 639 "Net-(U41-IO0_0)")
			(pintype "passive")
			(teardrops
				(best_length_ratio 0.2)
				(max_length 1)
				(best_width_ratio 0.9)
				(max_width 2)
				(curved_edges yes)
				(filter_ratio 0.9)
				(enabled yes)
				(allow_two_segments yes)
				(prefer_zone_connections yes)
			)
		)
		(pad "2" smd roundrect
			(at 0.48 0 180)
			(size 0.59 0.64)
			(layers "F.Cu" "F.Mask" "F.Paste")
			(roundrect_rratio 0.25)
			(net 573 "/GPIO expander/GPIOEX0")
			(pintype "passive")
			(teardrops
				(best_length_ratio 0.2)
				(max_length 1)
				(best_width_ratio 0.9)
				(max_width 2)
				(curved_edges yes)
				(filter_ratio 0.9)
				(enabled yes)
				(allow_two_segments yes)
				(prefer_zone_connections yes)
			)
		)
	)
	(footprint "antmicro-footprints:C_0402_1005Metric"
		(layer "F.Cu")
		(at 258.325 126.701748 90)
		(descr "Capacitor SMD 0402")
		(tags "capacitor SMD 0402")
		(property "Reference" "C98"
			(at -1.108252 1.325 90)
			(layer "F.SilkS")
			(effects
				(font
					(size 0.7 0.7)
					(thickness 0.15)
				)
				(justify left bottom)
			)
		)
		(property "Value" "C_1u_25V_0402"
			(at -1.022927 2.155213 90)
			(layer "F.Fab")
			(effects
				(font
					(size 0.7 0.7)
					(thickness 0.15)
				)
				(justify left bottom)
			)
		)
		(property "Datasheet" "https://www.murata.com/products/productdetail?partno=GRM155R61E105KE11%23"
			(at 0 0 90)
			(layer "F.Fab")
			(hide yes)
			(effects
				(font
					(size 1.27 1.27)
					(thickness 0.15)
				)
			)
		)
		(property "Description" "SMD Multilayer Ceramic Capacitor, 1 µF, 25 V, 0402 [1005 Metric], ± 10%, X5R, GRM Series"
			(at 0 0 90)
			(layer "F.Fab")
			(hide yes)
			(effects
				(font
					(size 1.27 1.27)
					(thickness 0.15)
				)
			)
		)
		(property "Author" "Antmicro"
			(at 385.026748 -131.623252 0)
			(layer "F.Fab")
			(hide yes)
			(effects
				(font
					(size 1 1)
					(thickness 0.15)
				)
			)
		)
		(property "Dielectric" "X5R"
			(at 385.026748 -131.623252 0)
			(layer "F.Fab")
			(hide yes)
			(effects
				(font
					(size 1 1)
					(thickness 0.15)
				)
			)
		)
		(property "License" "Apache-2.0"
			(at 385.026748 -131.623252 0)
			(layer "F.Fab")
			(hide yes)
			(effects
				(font
					(size 1 1)
					(thickness 0.15)
				)
			)
		)
		(property "MPN" "GRM155R61E105KE11J"
			(at 385.026748 -131.623252 0)
			(layer "F.Fab")
			(hide yes)
			(effects
				(font
					(size 1 1)
					(thickness 0.15)
				)
			)
		)
		(property "Manufacturer" "Murata"
			(at 385.026748 -131.623252 0)
			(layer "F.Fab")
			(hide yes)
			(effects
				(font
					(size 1 1)
					(thickness 0.15)
				)
			)
		)
		(property "Val" "1u"
			(at 385.026748 -131.623252 0)
			(layer "F.Fab")
			(hide yes)
			(effects
				(font
					(size 1 1)
					(thickness 0.15)
				)
			)
		)
		(property "Voltage" "25V"
			(at 385.026748 -131.623252 0)
			(layer "F.Fab")
			(hide yes)
			(effects
				(font
					(size 1 1)
					(thickness 0.15)
				)
			)
		)
		(sheetname "Com Express 7 MGMT")
		(sheetfile "com_express_7_mgmt.kicad_sch")
		(attr smd)
		(fp_rect
			(start -0.925 -0.47)
			(end 0.925 0.47)
			(stroke
				(width 0.05)
				(type default)
			)
			(fill no)
			(layer "F.CrtYd")
		)
		(fp_line
			(start 0.504 -0.25)
			(end 0.504 0.248)
			(stroke
				(width 0.15)
				(type solid)
			)
			(layer "F.Fab")
		)
		(fp_line
			(start -0.494 -0.25)
			(end 0.504 -0.25)
			(stroke
				(width 0.15)
				(type solid)
			)
			(layer "F.Fab")
		)
		(fp_line
			(start 0.504 0.248)
			(end -0.494 0.248)
			(stroke
				(width 0.15)
				(type solid)
			)
			(layer "F.Fab")
		)
		(fp_line
			(start -0.494 0.248)
			(end -0.494 -0.25)
			(stroke
				(width 0.15)
				(type solid)
			)
			(layer "F.Fab")
		)
		(pad "1" smd roundrect
			(at -0.48 0 90)
			(size 0.59 0.64)
			(layers "F.Cu" "F.Mask" "F.Paste")
			(roundrect_rratio 0.25)
			(net 1 "GND")
			(pintype "passive")
			(teardrops
				(best_length_ratio 0.2)
				(max_length 1)
				(best_width_ratio 0.9)
				(max_width 2)
				(curved_edges yes)
				(filter_ratio 0.9)
				(enabled yes)
				(allow_two_segments yes)
				(prefer_zone_connections yes)
			)
		)
		(pad "2" smd roundrect
			(at 0.48 0 90)
			(size 0.59 0.64)
			(layers "F.Cu" "F.Mask" "F.Paste")
			(roundrect_rratio 0.25)
			(net 82 "Net-(U32-CT)")
			(pintype "passive")
			(teardrops
				(best_length_ratio 0.2)
				(max_length 1)
				(best_width_ratio 0.9)
				(max_width 2)
				(curved_edges yes)
				(filter_ratio 0.9)
				(enabled yes)
				(allow_two_segments yes)
				(prefer_zone_connections yes)
			)
		)
	)
	(footprint "antmicro-footprints:SOT-23-8"
		(layer "F.Cu")
		(at 303.15 92.56 -90)
		(descr "http://www.ti.com/lit/ds/symlink/ina219.pdf")
		(property "Reference" "U50"
			(at -1.1 -2.65 90)
			(layer "F.SilkS")
			(effects
				(font
					(size 0.7 0.7)
					(thickness 0.15)
				)
				(justify right bottom)
			)
		)
		(property "Value" "INA219AIDCNR"
			(at 0 2.8 90)
			(layer "F.Fab")
			(effects
				(font
					(size 0.7 0.7)
					(thickness 0.15)
				)
				(justify right bottom)
			)
		)
		(property "Datasheet" "https://www.ti.com/lit/ds/symlink/ina219.pdf?ts=1713856455637&ref_url=https%253A%252F%252Fwww.mouser.es%252F"
			(at 0 0 270)
			(layer "F.Fab")
			(hide yes)
			(effects
				(font
					(size 1.27 1.27)
					(thickness 0.15)
				)
			)
		)
		(property "Author" "Antmicro"
			(at 210.59 395.71 0)
			(layer "F.Fab")
			(hide yes)
			(effects
				(font
					(size 1 1)
					(thickness 0.15)
				)
			)
		)
		(property "License" "Apache-2.0"
			(at 210.59 395.71 0)
			(layer "F.Fab")
			(hide yes)
			(effects
				(font
					(size 1 1)
					(thickness 0.15)
				)
			)
		)
		(property "MPN" "INA219AIDCNR"
			(at 210.59 395.71 0)
			(layer "F.Fab")
			(hide yes)
			(effects
				(font
					(size 1 1)
					(thickness 0.15)
				)
			)
		)
		(property "Manufacturer" "Texas Instruments"
			(at 210.59 395.71 0)
			(layer "F.Fab")
			(hide yes)
			(effects
				(font
					(size 1 1)
					(thickness 0.15)
				)
			)
		)
		(sheetname "Power")
		(sheetfile "power.kicad_sch")
		(attr smd)
		(fp_line
			(start -0.987 1.6)
			(end -0.987 1.324)
			(stroke
				(width 0.15)
				(type solid)
			)
			(layer "F.SilkS")
		)
		(fp_line
			(start -0.613 1.6)
			(end -0.987 1.6)
			(stroke
				(width 0.15)
				(type solid)
			)
			(layer "F.SilkS")
		)
		(fp_line
			(start 1 1.6)
			(end 0.6 1.6)
			(stroke
				(width 0.15)
				(type solid)
			)
			(layer "F.SilkS")
		)
		(fp_line
			(start 1 1.3)
			(end 1 1.6)
			(stroke
				(width 0.15)
				(type solid)
			)
			(layer "F.SilkS")
		)
		(fp_line
			(start -1 -1.3)
			(end -1 -1.6)
			(stroke
				(width 0.15)
				(type solid)
			)
			(layer "F.SilkS")
		)
		(fp_line
			(start 1 -1.3)
			(end 1 -1.6)
			(stroke
				(width 0.15)
				(type solid)
			)
			(layer "F.SilkS")
		)
		(fp_line
			(start -1 -1.6)
			(end -0.6 -1.6)
			(stroke
				(width 0.15)
				(type solid)
			)
			(layer "F.SilkS")
		)
		(fp_line
			(start 1 -1.6)
			(end 0.625 -1.6)
			(stroke
				(width 0.15)
				(type solid)
			)
			(layer "F.SilkS")
		)
		(fp_circle
			(center -1.3 -1.4)
			(end -1.25 -1.4)
			(stroke
				(width 0.15)
				(type solid)
			)
			(fill yes)
			(layer "F.SilkS")
		)
		(fp_rect
			(start -1.9 -1.75)
			(end 1.898 1.75)
			(stroke
				(width 0.05)
				(type solid)
			)
			(fill no)
			(layer "F.CrtYd")
		)
		(fp_line
			(start -1.4 -1.25)
			(end -1.2 -1.45)
			(stroke
				(width 0.15)
				(type solid)
			)
			(layer "F.Fab")
		)
		(fp_rect
			(start -1.401 -1.45)
			(end 1.398 1.449)
			(stroke
				(width 0.15)
				(type solid)
			)
			(fill no)
			(layer "F.Fab")
		)
		(pad "1" smd roundrect
			(at -1.3 -0.975 180)
			(size 0.45 1.1)
			(layers "F.Cu" "F.Mask" "F.Paste")
			(roundrect_rratio 0.25)
			(net 75 "Net-(U50-IN+)")
			(pinfunction "IN+")
			(pintype "passive")
			(teardrops
				(best_length_ratio 0.2)
				(max_length 1)
				(best_width_ratio 0.9)
				(max_width 2)
				(curved_edges yes)
				(filter_ratio 0.9)
				(enabled yes)
				(allow_two_segments yes)
				(prefer_zone_connections yes)
			)
		)
		(pad "2" smd roundrect
			(at -1.3 -0.325 180)
			(size 0.45 1.1)
			(layers "F.Cu" "F.Mask" "F.Paste")
			(roundrect_rratio 0.25)
			(net 77 "+5V_AON")
			(pinfunction "IN-")
			(pintype "passive")
			(teardrops
				(best_length_ratio 0.2)
				(max_length 1)
				(best_width_ratio 0.9)
				(max_width 2)
				(curved_edges yes)
				(filter_ratio 0.9)
				(enabled yes)
				(allow_two_segments yes)
				(prefer_zone_connections yes)
			)
		)
		(pad "3" smd roundrect
			(at -1.3 0.325 180)
			(size 0.45 1.1)
			(layers "F.Cu" "F.Mask" "F.Paste")
			(roundrect_rratio 0.25)
			(net 1 "GND")
			(pinfunction "GND")
			(pintype "power_in")
			(teardrops
				(best_length_ratio 0.2)
				(max_length 1)
				(best_width_ratio 0.9)
				(max_width 2)
				(curved_edges yes)
				(filter_ratio 0.9)
				(enabled yes)
				(allow_two_segments yes)
				(prefer_zone_connections yes)
			)
		)
		(pad "4" smd roundrect
			(at -1.3 0.975 180)
			(size 0.45 1.1)
			(layers "F.Cu" "F.Mask" "F.Paste")
			(roundrect_rratio 0.25)
			(net 73 "+3V3_AON")
			(pinfunction "V_{S}")
			(pintype "power_in")
			(teardrops
				(best_length_ratio 0.2)
				(max_length 1)
				(best_width_ratio 0.9)
				(max_width 2)
				(curved_edges yes)
				(filter_ratio 0.9)
				(enabled yes)
				(allow_two_segments yes)
				(prefer_zone_connections yes)
			)
		)
		(pad "5" smd roundrect
			(at 1.3 0.975 180)
			(size 0.45 1.1)
			(layers "F.Cu" "F.Mask" "F.Paste")
			(roundrect_rratio 0.25)
			(net 371 "/Com Express 7 MGMT/I2C.SCL")
			(pinfunction "SCL")
			(pintype "open_collector")
			(teardrops
				(best_length_ratio 0.2)
				(max_length 1)
				(best_width_ratio 0.9)
				(max_width 2)
				(curved_edges yes)
				(filter_ratio 0.9)
				(enabled yes)
				(allow_two_segments yes)
				(prefer_zone_connections yes)
			)
		)
		(pad "6" smd roundrect
			(at 1.3 0.325 180)
			(size 0.45 1.1)
			(layers "F.Cu" "F.Mask" "F.Paste")
			(roundrect_rratio 0.25)
			(net 372 "/Com Express 7 MGMT/I2C.SDA")
			(pinfunction "SDA")
			(pintype "open_collector")
			(teardrops
				(best_length_ratio 0.2)
				(max_length 1)
				(best_width_ratio 0.9)
				(max_width 2)
				(curved_edges yes)
				(filter_ratio 0.9)
				(enabled yes)
				(allow_two_segments yes)
				(prefer_zone_connections yes)
			)
		)
		(pad "7" smd roundrect
			(at 1.3 -0.325 180)
			(size 0.45 1.1)
			(layers "F.Cu" "F.Mask" "F.Paste")
			(roundrect_rratio 0.25)
			(net 372 "/Com Express 7 MGMT/I2C.SDA")
			(pinfunction "A0")
			(pintype "passive")
			(teardrops
				(best_length_ratio 0.2)
				(max_length 1)
				(best_width_ratio 0.9)
				(max_width 2)
				(curved_edges yes)
				(filter_ratio 0.9)
				(enabled yes)
				(allow_two_segments yes)
				(prefer_zone_connections yes)
			)
		)
		(pad "8" smd roundrect
			(at 1.3 -0.975 180)
			(size 0.45 1.1)
			(layers "F.Cu" "F.Mask" "F.Paste")
			(roundrect_rratio 0.25)
			(net 1 "GND")
			(pinfunction "A1")
			(pintype "passive")
			(teardrops
				(best_length_ratio 0.2)
				(max_length 1)
				(best_width_ratio 0.9)
				(max_width 2)
				(curved_edges yes)
				(filter_ratio 0.9)
				(enabled yes)
				(allow_two_segments yes)
				(prefer_zone_connections yes)
			)
		)
	)
	(footprint "antmicro-footprints:C_0402_1005Metric"
		(layer "F.Cu")
		(at 252.92 165.53 180)
		(descr "Capacitor SMD 0402")
		(tags "capacitor SMD 0402")
		(property "Reference" "C105"
			(at -1.5 -0.5 0)
			(layer "F.SilkS")
			(effects
				(font
					(size 0.7 0.7)
					(thickness 0.15)
				)
				(justify right top)
			)
		)
		(property "Value" "C_100n_0402"
			(at -1.022927 2.155213 0)
			(layer "F.Fab")
			(effects
				(font
					(size 0.7 0.7)
					(thickness 0.15)
				)
				(justify right top)
			)
		)
		(property "Datasheet" "https://www.murata.com/products/productdetail?partno=GRM155R61H104KE14%23"
			(at 0 0 0)
			(layer "F.Fab")
			(hide yes)
			(effects
				(font
					(size 1.27 1.27)
					(thickness 0.15)
				)
			)
		)
		(property "Author" "Antmicro"
			(at 305.16 -23.74 90)
			(layer "F.Fab")
			(hide yes)
			(effects
				(font
					(size 1 1)
					(thickness 0.15)
				)
			)
		)
		(property "Dielectric" "X5R"
			(at 305.16 -23.74 90)
			(layer "F.Fab")
			(hide yes)
			(effects
				(font
					(size 1 1)
					(thickness 0.15)
				)
			)
		)
		(property "License" "Apache-2.0"
			(at 305.16 -23.74 90)
			(layer "F.Fab")
			(hide yes)
			(effects
				(font
					(size 1 1)
					(thickness 0.15)
				)
			)
		)
		(property "MPN" "GRM155R61H104KE14D"
			(at 305.16 -23.74 90)
			(layer "F.Fab")
			(hide yes)
			(effects
				(font
					(size 1 1)
					(thickness 0.15)
				)
			)
		)
		(property "Manufacturer" "Murata"
			(at 305.16 -23.74 90)
			(layer "F.Fab")
			(hide yes)
			(effects
				(font
					(size 1 1)
					(thickness 0.15)
				)
			)
		)
		(property "Public" "False"
			(at 305.16 -23.74 90)
			(layer "F.Fab")
			(hide yes)
			(effects
				(font
					(size 1 1)
					(thickness 0.15)
				)
			)
		)
		(property "Val" "100n"
			(at 305.16 -23.74 90)
			(layer "F.Fab")
			(hide yes)
			(effects
				(font
					(size 1 1)
					(thickness 0.15)
				)
			)
		)
		(property "Voltage" "50V"
			(at 305.16 -23.74 90)
			(layer "F.Fab")
			(hide yes)
			(effects
				(font
					(size 1 1)
					(thickness 0.15)
				)
			)
		)
		(sheetname "Com Express 7 MGMT")
		(sheetfile "com_express_7_mgmt.kicad_sch")
		(attr smd)
		(fp_rect
			(start -0.925 -0.47)
			(end 0.925 0.47)
			(stroke
				(width 0.05)
				(type default)
			)
			(fill no)
			(layer "F.CrtYd")
		)
		(fp_line
			(start 0.504 0.248)
			(end -0.494 0.248)
			(stroke
				(width 0.15)
				(type solid)
			)
			(layer "F.Fab")
		)
		(fp_line
			(start 0.504 -0.25)
			(end 0.504 0.248)
			(stroke
				(width 0.15)
				(type solid)
			)
			(layer "F.Fab")
		)
		(fp_line
			(start -0.494 0.248)
			(end -0.494 -0.25)
			(stroke
				(width 0.15)
				(type solid)
			)
			(layer "F.Fab")
		)
		(fp_line
			(start -0.494 -0.25)
			(end 0.504 -0.25)
			(stroke
				(width 0.15)
				(type solid)
			)
			(layer "F.Fab")
		)
		(pad "1" smd roundrect
			(at -0.48 0 180)
			(size 0.59 0.64)
			(layers "F.Cu" "F.Mask" "F.Paste")
			(roundrect_rratio 0.25)
			(net 1 "GND")
			(pintype "passive")
			(teardrops
				(best_length_ratio 0.2)
				(max_length 1)
				(best_width_ratio 0.9)
				(max_width 2)
				(curved_edges yes)
				(filter_ratio 0.9)
				(enabled yes)
				(allow_two_segments yes)
				(prefer_zone_connections yes)
			)
		)
		(pad "2" smd roundrect
			(at 0.48 0 180)
			(size 0.59 0.64)
			(layers "F.Cu" "F.Mask" "F.Paste")
			(roundrect_rratio 0.25)
			(net 85 "/Com Express 7 MGMT/MAFS_POWER")
			(pintype "passive")
			(teardrops
				(best_length_ratio 0.2)
				(max_length 1)
				(best_width_ratio 0.9)
				(max_width 2)
				(curved_edges yes)
				(filter_ratio 0.9)
				(enabled yes)
				(allow_two_segments yes)
				(prefer_zone_connections yes)
			)
		)
	)
	(footprint "antmicro-footprints:R_0201"
		(layer "F.Cu")
		(at 135.17 147.935 -90)
		(descr "Resistor SMD 0201")
		(tags "resistor SMD 0201")
		(property "Reference" "R283"
			(at 6.475 -0.58 270)
			(layer "F.SilkS")
			(effects
				(font
					(size 0.7 0.7)
					(thickness 0.15)
				)
				(justify left bottom)
			)
		)
		(property "Value" "R_0R_0201"
			(at 0 1.25 270)
			(layer "F.Fab")
			(effects
				(font
					(size 0.7 0.7)
					(thickness 0.15)
				)
				(justify left bottom)
			)
		)
		(property "Datasheet" "https://www.bourns.com/docs/product-datasheets/cr.pdf"
			(at 0 0 270)
			(layer "F.Fab")
			(hide yes)
			(effects
				(font
					(size 1.27 1.27)
					(thickness 0.15)
				)
			)
		)
		(property "Author" "Antmicro"
			(at -12.765 283.105 0)
			(layer "F.Fab")
			(hide yes)
			(effects
				(font
					(size 1 1)
					(thickness 0.15)
				)
			)
		)
		(property "License" "Apache-2.0"
			(at -12.765 283.105 0)
			(layer "F.Fab")
			(hide yes)
			(effects
				(font
					(size 1 1)
					(thickness 0.15)
				)
			)
		)
		(property "MPN" "CR0201-FX-0R00GLF"
			(at -12.765 283.105 0)
			(layer "F.Fab")
			(hide yes)
			(effects
				(font
					(size 1 1)
					(thickness 0.15)
				)
			)
		)
		(property "Manufacturer" "Bourns"
			(at -12.765 283.105 0)
			(layer "F.Fab")
			(hide yes)
			(effects
				(font
					(size 1 1)
					(thickness 0.15)
				)
			)
		)
		(property "Tolerance" "1%"
			(at -12.765 283.105 0)
			(layer "F.Fab")
			(hide yes)
			(effects
				(font
					(size 1 1)
					(thickness 0.15)
				)
			)
		)
		(property "Val" "0R"
			(at -12.765 283.105 0)
			(layer "F.Fab")
			(hide yes)
			(effects
				(font
					(size 1 1)
					(thickness 0.15)
				)
			)
		)
		(sheetname "KR to SFI #2")
		(sheetfile "kr_sfi.kicad_sch")
		(attr smd dnp)
		(fp_rect
			(start -0.7 -0.35)
			(end 0.7 0.35)
			(stroke
				(width 0.05)
				(type default)
			)
			(fill no)
			(layer "F.CrtYd")
		)
		(fp_rect
			(start -0.3 -0.15)
			(end 0.298 0.148)
			(stroke
				(width 0.15)
				(type solid)
			)
			(fill no)
			(layer "F.Fab")
		)
		(pad "" smd roundrect
			(at -0.346 0 270)
			(size 0.318 0.36)
			(layers "F.Paste")
			(roundrect_rratio 0.25)
			(teardrops
				(best_length_ratio 0.2)
				(max_length 1)
				(best_width_ratio 0.9)
				(max_width 2)
				(curved_edges yes)
				(filter_ratio 0.9)
				(enabled yes)
				(allow_two_segments yes)
				(prefer_zone_connections yes)
			)
		)
		(pad "" smd roundrect
			(at 0.344 0 270)
			(size 0.318 0.36)
			(layers "F.Paste")
			(roundrect_rratio 0.25)
			(teardrops
				(best_length_ratio 0.2)
				(max_length 1)
				(best_width_ratio 0.9)
				(max_width 2)
				(curved_edges yes)
				(filter_ratio 0.9)
				(enabled yes)
				(allow_two_segments yes)
				(prefer_zone_connections yes)
			)
		)
		(pad "1" smd roundrect
			(at -0.32 0 270)
			(size 0.46 0.4)
			(layers "F.Cu" "F.Mask")
			(roundrect_rratio 0.25)
			(net 427 "/2xSFP+/10GKR_SFP1.RX+")
			(pintype "passive")
			(teardrops
				(best_length_ratio 0.2)
				(max_length 1)
				(best_width_ratio 0.9)
				(max_width 2)
				(curved_edges yes)
				(filter_ratio 0.9)
				(enabled yes)
				(allow_two_segments yes)
				(prefer_zone_connections yes)
			)
		)
		(pad "2" smd roundrect
			(at 0.32 0 270)
			(size 0.46 0.4)
			(layers "F.Cu" "F.Mask")
			(roundrect_rratio 0.25)
			(net 949 "/2xSFP+/KR to SFI #2/BYP_RX+")
			(pintype "passive")
			(teardrops
				(best_length_ratio 0.2)
				(max_length 1)
				(best_width_ratio 0.9)
				(max_width 2)
				(curved_edges yes)
				(filter_ratio 0.9)
				(enabled yes)
				(allow_two_segments yes)
				(prefer_zone_connections yes)
			)
		)
	)
	(footprint "antmicro-footprints:R_0402_1005Metric"
		(layer "F.Cu")
		(at 263.25 92.437 90)
		(descr "Resistor SMD 0402")
		(tags "resistor SMD 0402")
		(property "Reference" "R147"
			(at 0.827 0.55 90)
			(layer "F.SilkS")
			(effects
				(font
					(size 0.7 0.7)
					(thickness 0.15)
				)
				(justify left bottom)
			)
		)
		(property "Value" "R_0R_0402"
			(at -1.011843 1.772047 90)
			(layer "F.Fab")
			(effects
				(font
					(size 0.7 0.7)
					(thickness 0.15)
				)
				(justify left bottom)
			)
		)
		(property "Datasheet" "https://industrial.panasonic.com/cdbs/www-data/pdf/RDA0000/AOA0000C301.pdf"
			(at 0 0 90)
			(layer "F.Fab")
			(hide yes)
			(effects
				(font
					(size 1.27 1.27)
					(thickness 0.15)
				)
			)
		)
		(property "Author" "Antmicro"
			(at 355.687 -170.813 0)
			(layer "F.Fab")
			(hide yes)
			(effects
				(font
					(size 1 1)
					(thickness 0.15)
				)
			)
		)
		(property "Current" "1A"
			(at 355.687 -170.813 0)
			(layer "F.Fab")
			(hide yes)
			(effects
				(font
					(size 1 1)
					(thickness 0.15)
				)
			)
		)
		(property "License" "Apache-2.0"
			(at 355.687 -170.813 0)
			(layer "F.Fab")
			(hide yes)
			(effects
				(font
					(size 1 1)
					(thickness 0.15)
				)
			)
		)
		(property "MPN" "ERJ2GE0R00X"
			(at 355.687 -170.813 0)
			(layer "F.Fab")
			(hide yes)
			(effects
				(font
					(size 1 1)
					(thickness 0.15)
				)
			)
		)
		(property "Manufacturer" "Panasonic"
			(at 355.687 -170.813 0)
			(layer "F.Fab")
			(hide yes)
			(effects
				(font
					(size 1 1)
					(thickness 0.15)
				)
			)
		)
		(property "Public" "False"
			(at 355.687 -170.813 0)
			(layer "F.Fab")
			(hide yes)
			(effects
				(font
					(size 1 1)
					(thickness 0.15)
				)
			)
		)
		(property "Tolerance" ""
			(at 355.687 -170.813 0)
			(layer "F.Fab")
			(hide yes)
			(effects
				(font
					(size 1 1)
					(thickness 0.15)
				)
			)
		)
		(property "Val" "0R"
			(at 355.687 -170.813 0)
			(layer "F.Fab")
			(hide yes)
			(effects
				(font
					(size 1 1)
					(thickness 0.15)
				)
			)
		)
		(sheetname "Misc")
		(sheetfile "misc.kicad_sch")
		(attr smd dnp)
		(fp_rect
			(start -0.925 -0.47)
			(end 0.925 0.47)
			(stroke
				(width 0.05)
				(type default)
			)
			(fill no)
			(layer "F.CrtYd")
		)
		(fp_rect
			(start -0.5 -0.25)
			(end 0.5 0.25)
			(stroke
				(width 0.15)
				(type solid)
			)
			(fill no)
			(layer "F.Fab")
		)
		(pad "1" smd roundrect
			(at -0.48 0 90)
			(size 0.59 0.64)
			(layers "F.Cu" "F.Mask" "F.Paste")
			(roundrect_rratio 0.25)
			(net 2 "+3V3")
			(pintype "passive")
			(teardrops
				(best_length_ratio 0.2)
				(max_length 1)
				(best_width_ratio 0.9)
				(max_width 2)
				(curved_edges yes)
				(filter_ratio 0.9)
				(enabled yes)
				(allow_two_segments yes)
				(prefer_zone_connections yes)
			)
		)
		(pad "2" smd roundrect
			(at 0.48 0 90)
			(size 0.59 0.64)
			(layers "F.Cu" "F.Mask" "F.Paste")
			(roundrect_rratio 0.25)
			(net 80 "Net-(Q6-D)")
			(pintype "passive")
			(teardrops
				(best_length_ratio 0.2)
				(max_length 1)
				(best_width_ratio 0.9)
				(max_width 2)
				(curved_edges yes)
				(filter_ratio 0.9)
				(enabled yes)
				(allow_two_segments yes)
				(prefer_zone_connections yes)
			)
		)
	)
	(footprint "antmicro-footprints:R_0402_1005Metric"
		(layer "F.Cu")
		(at 192.910913 140.884241 135)
		(descr "Resistor SMD 0402")
		(tags "resistor SMD 0402")
		(property "Reference" "R224"
			(at -1.064088 0.394744 135)
			(layer "F.SilkS")
			(effects
				(font
					(size 0.7 0.7)
					(thickness 0.15)
				)
				(justify left top)
			)
		)
		(property "Value" "R_1k_0402"
			(at -1.011843 1.772046 135)
			(layer "F.Fab")
			(effects
				(font
					(size 0.7 0.7)
					(thickness 0.15)
				)
				(justify left top)
			)
		)
		(property "Datasheet" "https://www.bourns.com/docs/product-datasheets/cr.pdf"
			(at 0 0 135)
			(layer "B.Fab")
			(hide yes)
			(effects
				(font
					(size 1.27 1.27)
					(thickness 0.15)
				)
				(justify mirror)
			)
		)
		(property "Author" "Antmicro"
			(at 331.56 54.689999 45)
			(layer "F.Fab")
			(hide yes)
			(effects
				(font
					(size 1 1)
					(thickness 0.15)
				)
			)
		)
		(property "License" "Apache-2.0"
			(at 331.56 54.689999 45)
			(layer "F.Fab")
			(hide yes)
			(effects
				(font
					(size 1 1)
					(thickness 0.15)
				)
			)
		)
		(property "MPN" "CR0402-FX-1001GLF"
			(at 331.56 54.689999 45)
			(layer "F.Fab")
			(hide yes)
			(effects
				(font
					(size 1 1)
					(thickness 0.15)
				)
			)
		)
		(property "Manufacturer" "Bourns"
			(at 331.56 54.689999 45)
			(layer "F.Fab")
			(hide yes)
			(effects
				(font
					(size 1 1)
					(thickness 0.15)
				)
			)
		)
		(property "Public" "False"
			(at 331.56 54.689999 45)
			(layer "F.Fab")
			(hide yes)
			(effects
				(font
					(size 1 1)
					(thickness 0.15)
				)
			)
		)
		(property "Tolerance" "1%"
			(at 331.56 54.689999 45)
			(layer "F.Fab")
			(hide yes)
			(effects
				(font
					(size 1 1)
					(thickness 0.15)
				)
			)
		)
		(property "Val" "1k"
			(at 331.56 54.689999 45)
			(layer "F.Fab")
			(hide yes)
			(effects
				(font
					(size 1 1)
					(thickness 0.15)
				)
			)
		)
		(sheetname "PCIe redriver")
		(sheetfile "pcie_redriver.kicad_sch")
		(attr smd)
		(fp_poly
			(pts
				(xy -0.925 -0.47) (xy 0.925 -0.47) (xy 0.925 0.47) (xy -0.925 0.47)
			)
			(stroke
				(width 0.05)
				(type default)
			)
			(fill no)
			(layer "F.CrtYd")
		)
		(fp_poly
			(pts
				(xy -0.5 -0.25) (xy 0.5 -0.25) (xy 0.5 0.25) (xy -0.5 0.25)
			)
			(stroke
				(width 0.15)
				(type solid)
			)
			(fill no)
			(layer "F.Fab")
		)
		(pad "1" smd roundrect
			(at -0.48 0 135)
			(size 0.59 0.64)
			(layers "F.Cu" "F.Mask" "F.Paste")
			(roundrect_rratio 0.25)
			(net 1 "GND")
			(pintype "passive")
			(teardrops
				(best_length_ratio 0.2)
				(max_length 1)
				(best_width_ratio 0.9)
				(max_width 2)
				(curved_edges yes)
				(filter_ratio 0.9)
				(enabled yes)
				(allow_two_segments yes)
				(prefer_zone_connections yes)
			)
		)
		(pad "2" smd roundrect
			(at 0.48 0 135)
			(size 0.59 0.64)
			(layers "F.Cu" "F.Mask" "F.Paste")
			(roundrect_rratio 0.25)
			(net 975 "/PCIe redriver/RX_FG0")
			(pintype "passive")
			(teardrops
				(best_length_ratio 0.2)
				(max_length 1)
				(best_width_ratio 0.9)
				(max_width 2)
				(curved_edges yes)
				(filter_ratio 0.9)
				(enabled yes)
				(allow_two_segments yes)
				(prefer_zone_connections yes)
			)
		)
	)
	(footprint "antmicro-footprints:R_0402_1005Metric"
		(layer "F.Cu")
		(at 112.9 146.86 180)
		(descr "Resistor SMD 0402")
		(tags "resistor SMD 0402")
		(property "Reference" "R205"
			(at 0.85 -0.45 0)
			(layer "F.SilkS")
			(effects
				(font
					(size 0.7 0.7)
					(thickness 0.15)
				)
				(justify right bottom)
			)
		)
		(property "Value" "R_1k_0402"
			(at -1.011843 1.772047 0)
			(layer "F.Fab")
			(effects
				(font
					(size 0.7 0.7)
					(thickness 0.15)
				)
				(justify right bottom)
			)
		)
		(property "Datasheet" "https://www.bourns.com/docs/product-datasheets/cr.pdf"
			(at 0 0 180)
			(layer "F.Fab")
			(hide yes)
			(effects
				(font
					(size 1.27 1.27)
					(thickness 0.15)
				)
			)
		)
		(property "Author" "Antmicro"
			(at 225.8 293.72 0)
			(layer "F.Fab")
			(hide yes)
			(effects
				(font
					(size 1 1)
					(thickness 0.15)
				)
			)
		)
		(property "License" "Apache-2.0"
			(at 225.8 293.72 0)
			(layer "F.Fab")
			(hide yes)
			(effects
				(font
					(size 1 1)
					(thickness 0.15)
				)
			)
		)
		(property "MPN" "CR0402-FX-1001GLF"
			(at 225.8 293.72 0)
			(layer "F.Fab")
			(hide yes)
			(effects
				(font
					(size 1 1)
					(thickness 0.15)
				)
			)
		)
		(property "Manufacturer" "Bourns"
			(at 225.8 293.72 0)
			(layer "F.Fab")
			(hide yes)
			(effects
				(font
					(size 1 1)
					(thickness 0.15)
				)
			)
		)
		(property "Public" "False"
			(at 225.8 293.72 0)
			(layer "F.Fab")
			(hide yes)
			(effects
				(font
					(size 1 1)
					(thickness 0.15)
				)
			)
		)
		(property "Tolerance" "1%"
			(at 225.8 293.72 0)
			(layer "F.Fab")
			(hide yes)
			(effects
				(font
					(size 1 1)
					(thickness 0.15)
				)
			)
		)
		(property "Val" "1k"
			(at 225.8 293.72 0)
			(layer "F.Fab")
			(hide yes)
			(effects
				(font
					(size 1 1)
					(thickness 0.15)
				)
			)
		)
		(sheetname "PCIe redriver")
		(sheetfile "pcie_redriver.kicad_sch")
		(attr smd)
		(fp_rect
			(start -0.925 -0.47)
			(end 0.925 0.47)
			(stroke
				(width 0.05)
				(type default)
			)
			(fill no)
			(layer "F.CrtYd")
		)
		(fp_rect
			(start -0.5 -0.25)
			(end 0.5 0.25)
			(stroke
				(width 0.15)
				(type solid)
			)
			(fill no)
			(layer "F.Fab")
		)
		(pad "1" smd roundrect
			(at -0.48 0 180)
			(size 0.59 0.64)
			(layers "F.Cu" "F.Mask" "F.Paste")
			(roundrect_rratio 0.25)
			(net 1 "GND")
			(pintype "passive")
			(teardrops
				(best_length_ratio 0.2)
				(max_length 1)
				(best_width_ratio 0.9)
				(max_width 2)
				(curved_edges yes)
				(filter_ratio 0.9)
				(enabled yes)
				(allow_two_segments yes)
				(prefer_zone_connections yes)
			)
		)
		(pad "2" smd roundrect
			(at 0.48 0 180)
			(size 0.59 0.64)
			(layers "F.Cu" "F.Mask" "F.Paste")
			(roundrect_rratio 0.25)
			(net 624 "/PCIe redriver/TX_EQ1")
			(pintype "passive")
			(teardrops
				(best_length_ratio 0.2)
				(max_length 1)
				(best_width_ratio 0.9)
				(max_width 2)
				(curved_edges yes)
				(filter_ratio 0.9)
				(enabled yes)
				(allow_two_segments yes)
				(prefer_zone_connections yes)
			)
		)
	)
	(footprint "antmicro-footprints:TP_SMD_0.75mm"
		(layer "F.Cu")
		(at 186.70861 72.802163 -90)
		(property "Reference" "TP101"
			(at 0 -0.6 90)
			(layer "F.SilkS")
			(hide yes)
			(effects
				(font
					(size 0.7 0.7)
					(thickness 0.15)
				)
				(justify right bottom)
			)
		)
		(property "Value" "TP_0.75mm_SMD"
			(at 0 1.2 90)
			(layer "F.Fab")
			(effects
				(font
					(size 0.7 0.7)
					(thickness 0.15)
				)
				(justify right bottom)
			)
		)
		(property "Author" "Antmicro"
			(at 113.906447 259.510773 0)
			(layer "F.Fab")
			(hide yes)
			(effects
				(font
					(size 1 1)
					(thickness 0.15)
				)
			)
		)
		(property "License" "Apache-2.0"
			(at 113.906447 259.510773 0)
			(layer "F.Fab")
			(hide yes)
			(effects
				(font
					(size 1 1)
					(thickness 0.15)
				)
			)
		)
		(property "MPN" ""
			(at 113.906447 259.510773 0)
			(layer "F.Fab")
			(hide yes)
			(effects
				(font
					(size 1 1)
					(thickness 0.15)
				)
			)
		)
		(property "Manufacturer" ""
			(at 113.906447 259.510773 0)
			(layer "F.Fab")
			(hide yes)
			(effects
				(font
					(size 1 1)
					(thickness 0.15)
				)
			)
		)
		(property "Public" "False"
			(at 113.906447 259.510773 0)
			(layer "F.Fab")
			(hide yes)
			(effects
				(font
					(size 1 1)
					(thickness 0.15)
				)
			)
		)
		(sheetname "Power")
		(sheetfile "power.kicad_sch")
		(attr exclude_from_pos_files exclude_from_bom)
		(fp_circle
			(center 0 0)
			(end 0.475 0)
			(stroke
				(width 0.05)
				(type default)
			)
			(fill no)
			(layer "F.CrtYd")
		)
		(pad "1" smd circle
			(at 0 0 270)
			(size 0.75 0.75)
			(layers "F.Cu" "F.Mask")
			(net 62 "+12V_AON")
			(pinfunction "1")
			(pintype "passive")
			(teardrops
				(best_length_ratio 0.4)
				(max_length 1)
				(best_width_ratio 0.9)
				(max_width 2)
				(curved_edges yes)
				(filter_ratio 0.9)
				(enabled yes)
				(allow_two_segments yes)
				(prefer_zone_connections yes)
			)
		)
	)
	(footprint "antmicro-footprints:C_0402_1005Metric"
		(layer "F.Cu")
		(at 247.350001 128.310001 -90)
		(descr "Capacitor SMD 0402")
		(tags "capacitor SMD 0402")
		(property "Reference" "C101"
			(at -3.650001 -0.399999 90)
			(layer "F.SilkS")
			(effects
				(font
					(size 0.7 0.7)
					(thickness 0.15)
				)
				(justify right bottom)
			)
		)
		(property "Value" "C_1u_25V_0402"
			(at -1.022927 2.155213 90)
			(layer "F.Fab")
			(effects
				(font
					(size 0.7 0.7)
					(thickness 0.15)
				)
				(justify right bottom)
			)
		)
		(property "Datasheet" "https://www.murata.com/products/productdetail?partno=GRM155R61E105KE11%23"
			(at 0 0 270)
			(layer "F.Fab")
			(hide yes)
			(effects
				(font
					(size 1.27 1.27)
					(thickness 0.15)
				)
			)
		)
		(property "Description" "SMD Multilayer Ceramic Capacitor, 1 µF, 25 V, 0402 [1005 Metric], ± 10%, X5R, GRM Series"
			(at 0 0 270)
			(layer "F.Fab")
			(hide yes)
			(effects
				(font
					(size 1.27 1.27)
					(thickness 0.15)
				)
			)
		)
		(property "Author" "Antmicro"
			(at 119.04 375.660002 0)
			(layer "F.Fab")
			(hide yes)
			(effects
				(font
					(size 1 1)
					(thickness 0.15)
				)
			)
		)
		(property "Dielectric" "X5R"
			(at 119.04 375.660002 0)
			(layer "F.Fab")
			(hide yes)
			(effects
				(font
					(size 1 1)
					(thickness 0.15)
				)
			)
		)
		(property "License" "Apache-2.0"
			(at 119.04 375.660002 0)
			(layer "F.Fab")
			(hide yes)
			(effects
				(font
					(size 1 1)
					(thickness 0.15)
				)
			)
		)
		(property "MPN" "GRM155R61E105KE11J"
			(at 119.04 375.660002 0)
			(layer "F.Fab")
			(hide yes)
			(effects
				(font
					(size 1 1)
					(thickness 0.15)
				)
			)
		)
		(property "Manufacturer" "Murata"
			(at 119.04 375.660002 0)
			(layer "F.Fab")
			(hide yes)
			(effects
				(font
					(size 1 1)
					(thickness 0.15)
				)
			)
		)
		(property "Val" "1u"
			(at 119.04 375.660002 0)
			(layer "F.Fab")
			(hide yes)
			(effects
				(font
					(size 1 1)
					(thickness 0.15)
				)
			)
		)
		(property "Voltage" "25V"
			(at 119.04 375.660002 0)
			(layer "F.Fab")
			(hide yes)
			(effects
				(font
					(size 1 1)
					(thickness 0.15)
				)
			)
		)
		(sheetname "Com Express 7 MGMT")
		(sheetfile "com_express_7_mgmt.kicad_sch")
		(attr smd)
		(fp_rect
			(start -0.925 -0.47)
			(end 0.925 0.47)
			(stroke
				(width 0.05)
				(type default)
			)
			(fill no)
			(layer "F.CrtYd")
		)
		(fp_line
			(start -0.494 0.248)
			(end -0.494 -0.25)
			(stroke
				(width 0.15)
				(type solid)
			)
			(layer "F.Fab")
		)
		(fp_line
			(start 0.504 0.248)
			(end -0.494 0.248)
			(stroke
				(width 0.15)
				(type solid)
			)
			(layer "F.Fab")
		)
		(fp_line
			(start -0.494 -0.25)
			(end 0.504 -0.25)
			(stroke
				(width 0.15)
				(type solid)
			)
			(layer "F.Fab")
		)
		(fp_line
			(start 0.504 -0.25)
			(end 0.504 0.248)
			(stroke
				(width 0.15)
				(type solid)
			)
			(layer "F.Fab")
		)
		(pad "1" smd roundrect
			(at -0.48 0 270)
			(size 0.59 0.64)
			(layers "F.Cu" "F.Mask" "F.Paste")
			(roundrect_rratio 0.25)
			(net 999 "Net-(C101-Pad1)")
			(pintype "passive")
			(teardrops
				(best_length_ratio 0.2)
				(max_length 1)
				(best_width_ratio 0.9)
				(max_width 2)
				(curved_edges yes)
				(filter_ratio 0.9)
				(enabled yes)
				(allow_two_segments yes)
				(prefer_zone_connections yes)
			)
		)
		(pad "2" smd roundrect
			(at 0.48 0 270)
			(size 0.59 0.64)
			(layers "F.Cu" "F.Mask" "F.Paste")
			(roundrect_rratio 0.25)
			(net 84 "/Com Express 7 MGMT/PWRBTN")
			(pintype "passive")
			(teardrops
				(best_length_ratio 0.2)
				(max_length 1)
				(best_width_ratio 0.9)
				(max_width 2)
				(curved_edges yes)
				(filter_ratio 0.9)
				(enabled yes)
				(allow_two_segments yes)
				(prefer_zone_connections yes)
			)
		)
	)
	(footprint "antmicro-footprints:C_0402_1005Metric"
		(layer "F.Cu")
		(at 302.500001 103.61 180)
		(descr "Capacitor SMD 0402")
		(tags "capacitor SMD 0402")
		(property "Reference" "C204"
			(at -1.399999 0.5 0)
			(layer "F.SilkS")
			(effects
				(font
					(size 0.7 0.7)
					(thickness 0.15)
				)
				(justify right bottom)
			)
		)
		(property "Value" "C_100n_0402"
			(at -1.022927 2.155213 0)
			(layer "F.Fab")
			(effects
				(font
					(size 0.7 0.7)
					(thickness 0.15)
				)
				(justify right bottom)
			)
		)
		(property "Datasheet" "https://www.murata.com/products/productdetail?partno=GRM155R61H104KE14%23"
			(at 0 0 180)
			(layer "F.Fab")
			(hide yes)
			(effects
				(font
					(size 1.27 1.27)
					(thickness 0.15)
				)
			)
		)
		(property "Author" "Antmicro"
			(at 605.000002 207.22 0)
			(layer "F.Fab")
			(hide yes)
			(effects
				(font
					(size 1 1)
					(thickness 0.15)
				)
			)
		)
		(property "Dielectric" "X5R"
			(at 605.000002 207.22 0)
			(layer "F.Fab")
			(hide yes)
			(effects
				(font
					(size 1 1)
					(thickness 0.15)
				)
			)
		)
		(property "License" "Apache-2.0"
			(at 605.000002 207.22 0)
			(layer "F.Fab")
			(hide yes)
			(effects
				(font
					(size 1 1)
					(thickness 0.15)
				)
			)
		)
		(property "MPN" "GRM155R61H104KE14D"
			(at 605.000002 207.22 0)
			(layer "F.Fab")
			(hide yes)
			(effects
				(font
					(size 1 1)
					(thickness 0.15)
				)
			)
		)
		(property "Manufacturer" "Murata"
			(at 605.000002 207.22 0)
			(layer "F.Fab")
			(hide yes)
			(effects
				(font
					(size 1 1)
					(thickness 0.15)
				)
			)
		)
		(property "Public" "False"
			(at 605.000002 207.22 0)
			(layer "F.Fab")
			(hide yes)
			(effects
				(font
					(size 1 1)
					(thickness 0.15)
				)
			)
		)
		(property "Val" "100n"
			(at 605.000002 207.22 0)
			(layer "F.Fab")
			(hide yes)
			(effects
				(font
					(size 1 1)
					(thickness 0.15)
				)
			)
		)
		(property "Voltage" "50V"
			(at 605.000002 207.22 0)
			(layer "F.Fab")
			(hide yes)
			(effects
				(font
					(size 1 1)
					(thickness 0.15)
				)
			)
		)
		(sheetname "Power")
		(sheetfile "power.kicad_sch")
		(attr smd)
		(fp_rect
			(start -0.925 -0.47)
			(end 0.925 0.47)
			(stroke
				(width 0.05)
				(type default)
			)
			(fill no)
			(layer "F.CrtYd")
		)
		(fp_line
			(start 0.504 0.248)
			(end -0.494 0.248)
			(stroke
				(width 0.15)
				(type solid)
			)
			(layer "F.Fab")
		)
		(fp_line
			(start 0.504 -0.25)
			(end 0.504 0.248)
			(stroke
				(width 0.15)
				(type solid)
			)
			(layer "F.Fab")
		)
		(fp_line
			(start -0.494 0.248)
			(end -0.494 -0.25)
			(stroke
				(width 0.15)
				(type solid)
			)
			(layer "F.Fab")
		)
		(fp_line
			(start -0.494 -0.25)
			(end 0.504 -0.25)
			(stroke
				(width 0.15)
				(type solid)
			)
			(layer "F.Fab")
		)
		(pad "1" smd roundrect
			(at -0.48 0 180)
			(size 0.59 0.64)
			(layers "F.Cu" "F.Mask" "F.Paste")
			(roundrect_rratio 0.25)
			(net 1 "GND")
			(pintype "passive")
			(teardrops
				(best_length_ratio 0.2)
				(max_length 1)
				(best_width_ratio 0.9)
				(max_width 2)
				(curved_edges yes)
				(filter_ratio 0.9)
				(enabled yes)
				(allow_two_segments yes)
				(prefer_zone_connections yes)
			)
		)
		(pad "2" smd roundrect
			(at 0.48 0 180)
			(size 0.59 0.64)
			(layers "F.Cu" "F.Mask" "F.Paste")
			(roundrect_rratio 0.25)
			(net 73 "+3V3_AON")
			(pintype "passive")
			(teardrops
				(best_length_ratio 0.2)
				(max_length 1)
				(best_width_ratio 0.9)
				(max_width 2)
				(curved_edges yes)
				(filter_ratio 0.9)
				(enabled yes)
				(allow_two_segments yes)
				(prefer_zone_connections yes)
			)
		)
	)
	(footprint "antmicro-footprints:R_0402_1005Metric"
		(layer "F.Cu")
		(at 259.12 161.08 -90)
		(descr "Resistor SMD 0402")
		(tags "resistor SMD 0402")
		(property "Reference" "R179"
			(at -3.65 -0.45 90)
			(layer "F.SilkS")
			(effects
				(font
					(size 0.7 0.7)
					(thickness 0.15)
				)
				(justify right bottom)
			)
		)
		(property "Value" "R_1k_0402"
			(at -1.011843 1.772046 90)
			(layer "F.Fab")
			(effects
				(font
					(size 0.7 0.7)
					(thickness 0.15)
				)
				(justify right bottom)
			)
		)
		(property "Datasheet" "https://www.bourns.com/docs/product-datasheets/cr.pdf"
			(at 0 0 90)
			(layer "F.Fab")
			(hide yes)
			(effects
				(font
					(size 1.27 1.27)
					(thickness 0.15)
				)
			)
		)
		(property "Author" "Antmicro"
			(at 337.8 293.82 90)
			(layer "F.Fab")
			(hide yes)
			(effects
				(font
					(size 1 1)
					(thickness 0.15)
				)
			)
		)
		(property "License" "Apache-2.0"
			(at 337.8 293.82 90)
			(layer "F.Fab")
			(hide yes)
			(effects
				(font
					(size 1 1)
					(thickness 0.15)
				)
			)
		)
		(property "MPN" "CR0402-FX-1001GLF"
			(at 337.8 293.82 90)
			(layer "F.Fab")
			(hide yes)
			(effects
				(font
					(size 1 1)
					(thickness 0.15)
				)
			)
		)
		(property "Manufacturer" "Bourns"
			(at 337.8 293.82 90)
			(layer "F.Fab")
			(hide yes)
			(effects
				(font
					(size 1 1)
					(thickness 0.15)
				)
			)
		)
		(property "Public" "False"
			(at 337.8 293.82 90)
			(layer "F.Fab")
			(hide yes)
			(effects
				(font
					(size 1 1)
					(thickness 0.15)
				)
			)
		)
		(property "Tolerance" "1%"
			(at 337.8 293.82 90)
			(layer "F.Fab")
			(hide yes)
			(effects
				(font
					(size 1 1)
					(thickness 0.15)
				)
			)
		)
		(property "Val" "1k"
			(at 337.8 293.82 90)
			(layer "F.Fab")
			(hide yes)
			(effects
				(font
					(size 1 1)
					(thickness 0.15)
				)
			)
		)
		(sheetname "Com Express 7 MGMT")
		(sheetfile "com_express_7_mgmt.kicad_sch")
		(attr smd)
		(fp_rect
			(start -0.925 -0.47)
			(end 0.925 0.47)
			(stroke
				(width 0.05)
				(type default)
			)
			(fill no)
			(layer "F.CrtYd")
		)
		(fp_rect
			(start -0.5 -0.25)
			(end 0.5 0.25)
			(stroke
				(width 0.15)
				(type solid)
			)
			(fill no)
			(layer "F.Fab")
		)
		(pad "1" smd roundrect
			(at -0.48 0 270)
			(size 0.59 0.64)
			(layers "F.Cu" "F.Mask" "F.Paste")
			(roundrect_rratio 0.25)
			(net 600 "Net-(U36-~{HOLD}(D3))")
			(pintype "passive")
			(teardrops
				(best_length_ratio 0.2)
				(max_length 1)
				(best_width_ratio 0.9)
				(max_width 2)
				(curved_edges yes)
				(filter_ratio 0.9)
				(enabled yes)
				(allow_two_segments yes)
				(prefer_zone_connections yes)
			)
		)
		(pad "2" smd roundrect
			(at 0.48 0 270)
			(size 0.59 0.64)
			(layers "F.Cu" "F.Mask" "F.Paste")
			(roundrect_rratio 0.25)
			(net 85 "/Com Express 7 MGMT/MAFS_POWER")
			(pintype "passive")
			(teardrops
				(best_length_ratio 0.2)
				(max_length 1)
				(best_width_ratio 0.9)
				(max_width 2)
				(curved_edges yes)
				(filter_ratio 0.9)
				(enabled yes)
				(allow_two_segments yes)
				(prefer_zone_connections yes)
			)
		)
	)
	(footprint "antmicro-footprints:R_0805_2012Metric"
		(layer "F.Cu")
		(at 304.25 116.43 180)
		(property "Reference" "R103"
			(at -1.4 -1.88 0)
			(layer "F.SilkS")
			(effects
				(font
					(size 0.7 0.7)
					(thickness 0.15)
				)
				(justify right bottom)
			)
		)
		(property "Value" "R_0R001_0805"
			(at 0 1.8 0)
			(layer "F.Fab")
			(effects
				(font
					(size 0.7 0.7)
					(thickness 0.15)
				)
				(justify right bottom)
			)
		)
		(property "Datasheet" "https://www.eaton.com/content/dam/eaton/products/electronic-components/resources/data-sheet/eaton-msma-automotive-smd-current-sense-resistor-metal-strip-data-sheet-elx1179.pdf"
			(at 0 0 180)
			(layer "F.Fab")
			(hide yes)
			(effects
				(font
					(size 1.27 1.27)
					(thickness 0.15)
				)
			)
		)
		(property "Author" "Antmicro"
			(at 608.5 232.86 0)
			(layer "F.Fab")
			(hide yes)
			(effects
				(font
					(size 1 1)
					(thickness 0.15)
				)
			)
		)
		(property "License" "Apache-2.0"
			(at 608.5 232.86 0)
			(layer "F.Fab")
			(hide yes)
			(effects
				(font
					(size 1 1)
					(thickness 0.15)
				)
			)
		)
		(property "MPN" "MSMA0805R0010FSM"
			(at 608.5 232.86 0)
			(layer "F.Fab")
			(hide yes)
			(effects
				(font
					(size 1 1)
					(thickness 0.15)
				)
			)
		)
		(property "Manufacturer" "Eaton"
			(at 608.5 232.86 0)
			(layer "F.Fab")
			(hide yes)
			(effects
				(font
					(size 1 1)
					(thickness 0.15)
				)
			)
		)
		(property "Public" "False"
			(at 608.5 232.86 0)
			(layer "F.Fab")
			(hide yes)
			(effects
				(font
					(size 1 1)
					(thickness 0.15)
				)
			)
		)
		(property "Tolerance" "1%"
			(at 608.5 232.86 0)
			(layer "F.Fab")
			(hide yes)
			(effects
				(font
					(size 1 1)
					(thickness 0.15)
				)
			)
		)
		(property "Val" "0R001"
			(at 608.5 232.86 0)
			(layer "F.Fab")
			(hide yes)
			(effects
				(font
					(size 1 1)
					(thickness 0.15)
				)
			)
		)
		(sheetname "Power")
		(sheetfile "power.kicad_sch")
		(attr smd)
		(fp_line
			(start -0.3 -0.701)
			(end 0.298 -0.701)
			(stroke
				(width 0.15)
				(type solid)
			)
			(layer "F.SilkS")
		)
		(fp_line
			(start -0.32 0.699)
			(end 0.28 0.699)
			(stroke
				(width 0.15)
				(type solid)
			)
			(layer "F.SilkS")
		)
		(fp_rect
			(start 1.95 -0.9)
			(end -1.95 0.9)
			(stroke
				(width 0.05)
				(type default)
			)
			(fill no)
			(layer "F.CrtYd")
		)
		(fp_line
			(start 0.949 -0.677)
			(end 0.949 0.675)
			(stroke
				(width 0.15)
				(type solid)
			)
			(layer "F.Fab")
		)
		(fp_line
			(start -0.951 0.68)
			(end 0.949 0.68)
			(stroke
				(width 0.15)
				(type solid)
			)
			(layer "F.Fab")
		)
		(fp_line
			(start -0.951 -0.677)
			(end -0.951 0.675)
			(stroke
				(width 0.15)
				(type solid)
			)
			(layer "F.Fab")
		)
		(fp_line
			(start -0.951 -0.682)
			(end 0.949 -0.682)
			(stroke
				(width 0.15)
				(type solid)
			)
			(layer "F.Fab")
		)
		(pad "1" smd roundrect
			(at -1.1 0 180)
			(size 1.2 1.3)
			(layers "F.Cu" "F.Mask" "F.Paste")
			(roundrect_rratio 0.25)
			(net 70 "Net-(C49-Pad2)")
			(pintype "passive")
			(teardrops
				(best_length_ratio 0.2)
				(max_length 1)
				(best_width_ratio 0.9)
				(max_width 2)
				(curved_edges yes)
				(filter_ratio 0.9)
				(enabled yes)
				(allow_two_segments yes)
				(prefer_zone_connections yes)
			)
		)
		(pad "2" smd roundrect
			(at 1.1 0 180)
			(size 1.2 1.3)
			(layers "F.Cu" "F.Mask" "F.Paste")
			(roundrect_rratio 0.25)
			(net 74 "+1V0")
			(pintype "passive")
			(teardrops
				(best_length_ratio 0.2)
				(max_length 1)
				(best_width_ratio 0.9)
				(max_width 2)
				(curved_edges yes)
				(filter_ratio 0.9)
				(enabled yes)
				(allow_two_segments yes)
				(prefer_zone_connections yes)
			)
		)
	)
	(footprint "antmicro-footprints:TP_SMD_0.75mm"
		(layer "F.Cu")
		(at 116.134999 78.9 90)
		(property "Reference" "TP9"
			(at -2.46 0.415001 90)
			(layer "F.SilkS")
			(effects
				(font
					(size 0.7 0.7)
					(thickness 0.15)
				)
				(justify left bottom)
			)
		)
		(property "Value" "TP_0.75mm_SMD"
			(at 0 1.2 90)
			(layer "F.Fab")
			(effects
				(font
					(size 0.7 0.7)
					(thickness 0.15)
				)
				(justify left bottom)
			)
		)
		(property "Author" "Antmicro"
			(at 195.034999 -37.234999 0)
			(layer "F.Fab")
			(hide yes)
			(effects
				(font
					(size 1 1)
					(thickness 0.15)
				)
			)
		)
		(property "License" "Apache-2.0"
			(at 195.034999 -37.234999 0)
			(layer "F.Fab")
			(hide yes)
			(effects
				(font
					(size 1 1)
					(thickness 0.15)
				)
			)
		)
		(property "MPN" ""
			(at 195.034999 -37.234999 0)
			(layer "F.Fab")
			(hide yes)
			(effects
				(font
					(size 1 1)
					(thickness 0.15)
				)
			)
		)
		(property "Manufacturer" ""
			(at 195.034999 -37.234999 0)
			(layer "F.Fab")
			(hide yes)
			(effects
				(font
					(size 1 1)
					(thickness 0.15)
				)
			)
		)
		(property "Public" "False"
			(at 195.034999 -37.234999 0)
			(layer "F.Fab")
			(hide yes)
			(effects
				(font
					(size 1 1)
					(thickness 0.15)
				)
			)
		)
		(sheetname "USB-C console")
		(sheetfile "usb-c_console.kicad_sch")
		(attr exclude_from_pos_files exclude_from_bom)
		(fp_circle
			(center 0 0)
			(end 0.475 0)
			(stroke
				(width 0.05)
				(type default)
			)
			(fill no)
			(layer "F.CrtYd")
		)
		(pad "1" smd circle
			(at 0 0 90)
			(size 0.75 0.75)
			(layers "F.Cu" "F.Mask")
			(net 701 "/USB-C console/FTDI_CBUS0")
			(pinfunction "1")
			(pintype "passive")
			(teardrops
				(best_length_ratio 0.4)
				(max_length 1)
				(best_width_ratio 0.9)
				(max_width 2)
				(curved_edges yes)
				(filter_ratio 0.9)
				(enabled yes)
				(allow_two_segments yes)
				(prefer_zone_connections yes)
			)
		)
	)
	(footprint "antmicro-footprints:C_0402_1005Metric"
		(layer "F.Cu")
		(at 308.7 118.71 180)
		(descr "Capacitor SMD 0402")
		(tags "capacitor SMD 0402")
		(property "Reference" "C49"
			(at 0.85 -0.45 0)
			(layer "F.SilkS")
			(effects
				(font
					(size 0.7 0.7)
					(thickness 0.15)
				)
				(justify right bottom)
			)
		)
		(property "Value" "C_1u_0402"
			(at -1.022927 2.155213 0)
			(layer "F.Fab")
			(effects
				(font
					(size 0.7 0.7)
					(thickness 0.15)
				)
				(justify right bottom)
			)
		)
		(property "Datasheet" "https://product.tdk.com/en/search/capacitor/ceramic/mlcc/info?part_no=C1005X6S1A105K050BC"
			(at 0 0 180)
			(layer "F.Fab")
			(hide yes)
			(effects
				(font
					(size 1.27 1.27)
					(thickness 0.15)
				)
			)
		)
		(property "Author" "Antmicro"
			(at 617.4 237.42 0)
			(layer "F.Fab")
			(hide yes)
			(effects
				(font
					(size 1 1)
					(thickness 0.15)
				)
			)
		)
		(property "Dielectric" ""
			(at 617.4 237.42 0)
			(layer "F.Fab")
			(hide yes)
			(effects
				(font
					(size 1 1)
					(thickness 0.15)
				)
			)
		)
		(property "License" "Apache-2.0"
			(at 617.4 237.42 0)
			(layer "F.Fab")
			(hide yes)
			(effects
				(font
					(size 1 1)
					(thickness 0.15)
				)
			)
		)
		(property "MPN" "C1005X6S1A105K050BC"
			(at 617.4 237.42 0)
			(layer "F.Fab")
			(hide yes)
			(effects
				(font
					(size 1 1)
					(thickness 0.15)
				)
			)
		)
		(property "Manufacturer" "TDK"
			(at 617.4 237.42 0)
			(layer "F.Fab")
			(hide yes)
			(effects
				(font
					(size 1 1)
					(thickness 0.15)
				)
			)
		)
		(property "Public" "False"
			(at 617.4 237.42 0)
			(layer "F.Fab")
			(hide yes)
			(effects
				(font
					(size 1 1)
					(thickness 0.15)
				)
			)
		)
		(property "Val" "1u"
			(at 617.4 237.42 0)
			(layer "F.Fab")
			(hide yes)
			(effects
				(font
					(size 1 1)
					(thickness 0.15)
				)
			)
		)
		(property "Voltage" ""
			(at 617.4 237.42 0)
			(layer "F.Fab")
			(hide yes)
			(effects
				(font
					(size 1 1)
					(thickness 0.15)
				)
			)
		)
		(sheetname "Power")
		(sheetfile "power.kicad_sch")
		(attr smd)
		(fp_rect
			(start -0.925 -0.47)
			(end 0.925 0.47)
			(stroke
				(width 0.05)
				(type default)
			)
			(fill no)
			(layer "F.CrtYd")
		)
		(fp_line
			(start 0.504 0.248)
			(end -0.494 0.248)
			(stroke
				(width 0.15)
				(type solid)
			)
			(layer "F.Fab")
		)
		(fp_line
			(start 0.504 -0.25)
			(end 0.504 0.248)
			(stroke
				(width 0.15)
				(type solid)
			)
			(layer "F.Fab")
		)
		(fp_line
			(start -0.494 0.248)
			(end -0.494 -0.25)
			(stroke
				(width 0.15)
				(type solid)
			)
			(layer "F.Fab")
		)
		(fp_line
			(start -0.494 -0.25)
			(end 0.504 -0.25)
			(stroke
				(width 0.15)
				(type solid)
			)
			(layer "F.Fab")
		)
		(pad "1" smd roundrect
			(at -0.48 0 180)
			(size 0.59 0.64)
			(layers "F.Cu" "F.Mask" "F.Paste")
			(roundrect_rratio 0.25)
			(net 1 "GND")
			(pintype "passive")
			(teardrops
				(best_length_ratio 0.2)
				(max_length 1)
				(best_width_ratio 0.9)
				(max_width 2)
				(curved_edges yes)
				(filter_ratio 0.9)
				(enabled yes)
				(allow_two_segments yes)
				(prefer_zone_connections yes)
			)
		)
		(pad "2" smd roundrect
			(at 0.48 0 180)
			(size 0.59 0.64)
			(layers "F.Cu" "F.Mask" "F.Paste")
			(roundrect_rratio 0.25)
			(net 70 "Net-(C49-Pad2)")
			(pintype "passive")
			(teardrops
				(best_length_ratio 0.2)
				(max_length 1)
				(best_width_ratio 0.9)
				(max_width 2)
				(curved_edges yes)
				(filter_ratio 0.9)
				(enabled yes)
				(allow_two_segments yes)
				(prefer_zone_connections yes)
			)
		)
	)
	(footprint "antmicro-footprints:R_0402_1005Metric"
		(layer "F.Cu")
		(at 130.12 118.85 180)
		(descr "Resistor SMD 0402")
		(tags "resistor SMD 0402")
		(property "Reference" "R21"
			(at 0.781 0.42 0)
			(layer "F.SilkS")
			(effects
				(font
					(size 0.7 0.7)
					(thickness 0.15)
				)
				(justify right top)
			)
		)
		(property "Value" "R_0R_0402"
			(at -1.011843 1.772046 0)
			(layer "F.Fab")
			(effects
				(font
					(size 0.7 0.7)
					(thickness 0.15)
				)
				(justify right top)
			)
		)
		(property "Datasheet" "https://industrial.panasonic.com/cdbs/www-data/pdf/RDA0000/AOA0000C301.pdf"
			(at 0 0 0)
			(layer "F.Fab")
			(hide yes)
			(effects
				(font
					(size 1.27 1.27)
					(thickness 0.15)
				)
			)
		)
		(property "Author" "Antmicro"
			(at 358.37 -62.19 90)
			(layer "F.Fab")
			(hide yes)
			(effects
				(font
					(size 1 1)
					(thickness 0.15)
				)
			)
		)
		(property "Current" "1A"
			(at 358.37 -62.19 90)
			(layer "F.Fab")
			(hide yes)
			(effects
				(font
					(size 1 1)
					(thickness 0.15)
				)
			)
		)
		(property "License" "Apache-2.0"
			(at 358.37 -62.19 90)
			(layer "F.Fab")
			(hide yes)
			(effects
				(font
					(size 1 1)
					(thickness 0.15)
				)
			)
		)
		(property "MPN" "ERJ2GE0R00X"
			(at 358.37 -62.19 90)
			(layer "F.Fab")
			(hide yes)
			(effects
				(font
					(size 1 1)
					(thickness 0.15)
				)
			)
		)
		(property "Manufacturer" "Panasonic"
			(at 358.37 -62.19 90)
			(layer "F.Fab")
			(hide yes)
			(effects
				(font
					(size 1 1)
					(thickness 0.15)
				)
			)
		)
		(property "Public" "False"
			(at 358.37 -62.19 90)
			(layer "F.Fab")
			(hide yes)
			(effects
				(font
					(size 1 1)
					(thickness 0.15)
				)
			)
		)
		(property "Tolerance" ""
			(at 358.37 -62.19 90)
			(layer "F.Fab")
			(hide yes)
			(effects
				(font
					(size 1 1)
					(thickness 0.15)
				)
			)
		)
		(property "Val" "0R"
			(at 358.37 -62.19 90)
			(layer "F.Fab")
			(hide yes)
			(effects
				(font
					(size 1 1)
					(thickness 0.15)
				)
			)
		)
		(sheetname "2xUSB3.0+RJ45")
		(sheetfile "usb3+rj45.kicad_sch")
		(attr smd)
		(fp_rect
			(start -0.925 -0.47)
			(end 0.925 0.47)
			(stroke
				(width 0.05)
				(type default)
			)
			(fill no)
			(layer "F.CrtYd")
		)
		(fp_rect
			(start -0.5 -0.25)
			(end 0.5 0.25)
			(stroke
				(width 0.15)
				(type solid)
			)
			(fill no)
			(layer "F.Fab")
		)
		(pad "1" smd roundrect
			(at -0.48 0 180)
			(size 0.59 0.64)
			(layers "F.Cu" "F.Mask" "F.Paste")
			(roundrect_rratio 0.25)
			(net 312 "/2xUSB3.0+RJ45/USB_1.D-")
			(pintype "passive")
			(teardrops
				(best_length_ratio 0.2)
				(max_length 1)
				(best_width_ratio 0.9)
				(max_width 2)
				(curved_edges yes)
				(filter_ratio 0.9)
				(enabled yes)
				(allow_two_segments yes)
				(prefer_zone_connections yes)
			)
		)
		(pad "2" smd roundrect
			(at 0.48 0 180)
			(size 0.59 0.64)
			(layers "F.Cu" "F.Mask" "F.Paste")
			(roundrect_rratio 0.25)
			(net 123 "/2xUSB3.0+RJ45/P1_D-")
			(pintype "passive")
			(teardrops
				(best_length_ratio 0.2)
				(max_length 1)
				(best_width_ratio 0.9)
				(max_width 2)
				(curved_edges yes)
				(filter_ratio 0.9)
				(enabled yes)
				(allow_two_segments yes)
				(prefer_zone_connections yes)
			)
		)
	)
	(footprint "antmicro-footprints:R_0402_1005Metric"
		(layer "F.Cu")
		(at 240 78.5 -90)
		(descr "Resistor SMD 0402")
		(tags "resistor SMD 0402")
		(property "Reference" "R161"
			(at 1.1 0.4 90)
			(layer "F.SilkS")
			(effects
				(font
					(size 0.7 0.7)
					(thickness 0.15)
				)
				(justify right top)
			)
		)
		(property "Value" "R_5k1_0402"
			(at -4.236842 54.437047 90)
			(layer "F.Fab")
			(hide yes)
			(effects
				(font
					(size 0.7 0.7)
					(thickness 0.15)
				)
				(justify right top)
			)
		)
		(property "Datasheet" "https://www.bourns.com/docs/product-datasheets/cr.pdf"
			(at 0 0 90)
			(layer "F.Fab")
			(hide yes)
			(effects
				(font
					(size 1.27 1.27)
					(thickness 0.15)
				)
			)
		)
		(property "Author" "Antmicro"
			(at 0 0 90)
			(layer "F.Fab")
			(hide yes)
			(effects
				(font
					(size 1 1)
					(thickness 0.15)
				)
			)
		)
		(property "License" "Apache-2.0"
			(at 0 0 90)
			(layer "F.Fab")
			(hide yes)
			(effects
				(font
					(size 1 1)
					(thickness 0.15)
				)
			)
		)
		(property "MPN" "CR0402-FX-5101GLF"
			(at 0 0 90)
			(layer "F.Fab")
			(hide yes)
			(effects
				(font
					(size 1 1)
					(thickness 0.15)
				)
			)
		)
		(property "Manufacturer" "Bourns"
			(at 0 0 90)
			(layer "F.Fab")
			(hide yes)
			(effects
				(font
					(size 1 1)
					(thickness 0.15)
				)
			)
		)
		(property "Public" "False"
			(at 0 0 90)
			(layer "F.Fab")
			(hide yes)
			(effects
				(font
					(size 1 1)
					(thickness 0.15)
				)
			)
		)
		(property "Tolerance" "1%"
			(at 0 0 90)
			(layer "F.Fab")
			(hide yes)
			(effects
				(font
					(size 1 1)
					(thickness 0.15)
				)
			)
		)
		(property "Val" "5k1"
			(at 0 0 90)
			(layer "F.Fab")
			(hide yes)
			(effects
				(font
					(size 1 1)
					(thickness 0.15)
				)
			)
		)
		(sheetname "Com Express 7 MGMT")
		(sheetfile "com_express_7_mgmt.kicad_sch")
		(attr smd)
		(fp_rect
			(start -0.925 -0.47)
			(end 0.925 0.47)
			(stroke
				(width 0.05)
				(type default)
			)
			(fill no)
			(layer "F.CrtYd")
		)
		(fp_rect
			(start -0.5 -0.25)
			(end 0.5 0.25)
			(stroke
				(width 0.15)
				(type solid)
			)
			(fill no)
			(layer "F.Fab")
		)
		(pad "1" smd roundrect
			(at -0.48 0 270)
			(size 0.59 0.64)
			(layers "F.Cu" "F.Mask" "F.Paste")
			(roundrect_rratio 0.25)
			(net 400 "/Com Express 7 MGMT/FAN_PWM")
			(pintype "passive")
			(teardrops
				(best_length_ratio 0.2)
				(max_length 1)
				(best_width_ratio 0.9)
				(max_width 2)
				(curved_edges yes)
				(filter_ratio 0.9)
				(enabled yes)
				(allow_two_segments yes)
				(prefer_zone_connections yes)
			)
		)
		(pad "2" smd roundrect
			(at 0.48 0 270)
			(size 0.59 0.64)
			(layers "F.Cu" "F.Mask" "F.Paste")
			(roundrect_rratio 0.25)
			(net 2 "+3V3")
			(pintype "passive")
			(teardrops
				(best_length_ratio 0.2)
				(max_length 1)
				(best_width_ratio 0.9)
				(max_width 2)
				(curved_edges yes)
				(filter_ratio 0.9)
				(enabled yes)
				(allow_two_segments yes)
				(prefer_zone_connections yes)
			)
		)
	)
	(footprint "antmicro-footprints:C_0402_1005Metric"
		(layer "B.Cu")
		(at 213.11 127.121 180)
		(descr "Capacitor SMD 0402")
		(tags "capacitor SMD 0402")
		(property "Reference" "C108"
			(at -1.64 0.461 0)
			(layer "B.SilkS")
			(effects
				(font
					(size 0.7 0.7)
					(thickness 0.15)
				)
				(justify left bottom mirror)
			)
		)
		(property "Value" "C_100n_0402"
			(at -1.022927 -2.155213 0)
			(layer "B.Fab")
			(effects
				(font
					(size 0.7 0.7)
					(thickness 0.15)
				)
				(justify left bottom mirror)
			)
		)
		(property "Datasheet" "https://www.murata.com/products/productdetail?partno=GRM155R61H104KE14%23"
			(at 0 0 180)
			(layer "F.Fab")
			(hide yes)
			(effects
				(font
					(size 1.27 1.27)
					(thickness 0.15)
				)
			)
		)
		(property "Author" "Antmicro"
			(at 426.22 254.242 0)
			(layer "B.Fab")
			(hide yes)
			(effects
				(font
					(size 1 1)
					(thickness 0.15)
				)
				(justify mirror)
			)
		)
		(property "Dielectric" "X5R"
			(at 426.22 254.242 0)
			(layer "B.Fab")
			(hide yes)
			(effects
				(font
					(size 1 1)
					(thickness 0.15)
				)
				(justify mirror)
			)
		)
		(property "License" "Apache-2.0"
			(at 426.22 254.242 0)
			(layer "B.Fab")
			(hide yes)
			(effects
				(font
					(size 1 1)
					(thickness 0.15)
				)
				(justify mirror)
			)
		)
		(property "MPN" "GRM155R61H104KE14D"
			(at 426.22 254.242 0)
			(layer "B.Fab")
			(hide yes)
			(effects
				(font
					(size 1 1)
					(thickness 0.15)
				)
				(justify mirror)
			)
		)
		(property "Manufacturer" "Murata"
			(at 426.22 254.242 0)
			(layer "B.Fab")
			(hide yes)
			(effects
				(font
					(size 1 1)
					(thickness 0.15)
				)
				(justify mirror)
			)
		)
		(property "Public" "False"
			(at 426.22 254.242 0)
			(layer "B.Fab")
			(hide yes)
			(effects
				(font
					(size 1 1)
					(thickness 0.15)
				)
				(justify mirror)
			)
		)
		(property "Val" "100n"
			(at 426.22 254.242 0)
			(layer "B.Fab")
			(hide yes)
			(effects
				(font
					(size 1 1)
					(thickness 0.15)
				)
				(justify mirror)
			)
		)
		(property "Voltage" "50V"
			(at 426.22 254.242 0)
			(layer "B.Fab")
			(hide yes)
			(effects
				(font
					(size 1 1)
					(thickness 0.15)
				)
				(justify mirror)
			)
		)
		(sheetname "PCIe misc")
		(sheetfile "pcie_misc.kicad_sch")
		(attr smd)
		(fp_rect
			(start -0.925 0.47)
			(end 0.925 -0.47)
			(stroke
				(width 0.05)
				(type default)
			)
			(fill no)
			(layer "B.CrtYd")
		)
		(fp_line
			(start 0.504 0.25)
			(end -0.494 0.25)
			(stroke
				(width 0.15)
				(type solid)
			)
			(layer "B.Fab")
		)
		(fp_line
			(start 0.504 -0.248)
			(end 0.504 0.25)
			(stroke
				(width 0.15)
				(type solid)
			)
			(layer "B.Fab")
		)
		(fp_line
			(start -0.494 0.25)
			(end -0.494 -0.248)
			(stroke
				(width 0.15)
				(type solid)
			)
			(layer "B.Fab")
		)
		(fp_line
			(start -0.494 -0.248)
			(end 0.504 -0.248)
			(stroke
				(width 0.15)
				(type solid)
			)
			(layer "B.Fab")
		)
		(pad "1" smd roundrect
			(at -0.48 0 180)
			(size 0.59 0.64)
			(layers "B.Cu" "B.Mask" "B.Paste")
			(roundrect_rratio 0.25)
			(net 1 "GND")
			(pintype "passive")
			(teardrops
				(best_length_ratio 0.2)
				(max_length 1)
				(best_width_ratio 0.9)
				(max_width 2)
				(curved_edges yes)
				(filter_ratio 0.9)
				(enabled yes)
				(allow_two_segments yes)
				(prefer_zone_connections yes)
			)
		)
		(pad "2" smd roundrect
			(at 0.48 0 180)
			(size 0.59 0.64)
			(layers "B.Cu" "B.Mask" "B.Paste")
			(roundrect_rratio 0.25)
			(net 2 "+3V3")
			(pintype "passive")
			(teardrops
				(best_length_ratio 0.2)
				(max_length 1)
				(best_width_ratio 0.9)
				(max_width 2)
				(curved_edges yes)
				(filter_ratio 0.9)
				(enabled yes)
				(allow_two_segments yes)
				(prefer_zone_connections yes)
			)
		)
	)
	(footprint "antmicro-footprints:C_0603_1608Metric"
		(layer "B.Cu")
		(at 104.65 154.46 180)
		(descr "Capacitor SMD 0603")
		(tags "capacitor 0603")
		(property "Reference" "C38"
			(at -3.3 -0.45 0)
			(layer "B.SilkS")
			(effects
				(font
					(size 0.7 0.7)
					(thickness 0.15)
				)
				(justify left bottom mirror)
			)
		)
		(property "Value" "C_22u_16V_0603"
			(at -1.42757 -1.770288 0)
			(layer "B.Fab")
			(effects
				(font
					(size 0.7 0.7)
					(thickness 0.15)
				)
				(justify left bottom mirror)
			)
		)
		(property "Datasheet" "https://product.samsungsem.com/mlcc/CL10A226MO7JZN.do"
			(at 0 0 180)
			(layer "F.Fab")
			(hide yes)
			(effects
				(font
					(size 1.27 1.27)
					(thickness 0.15)
				)
			)
		)
		(property "Author" "Antmicro"
			(at 209.3 308.92 0)
			(layer "B.Fab")
			(hide yes)
			(effects
				(font
					(size 1 1)
					(thickness 0.15)
				)
				(justify mirror)
			)
		)
		(property "Dielectric" ""
			(at 209.3 308.92 0)
			(layer "B.Fab")
			(hide yes)
			(effects
				(font
					(size 1 1)
					(thickness 0.15)
				)
				(justify mirror)
			)
		)
		(property "License" "Apache-2.0"
			(at 209.3 308.92 0)
			(layer "B.Fab")
			(hide yes)
			(effects
				(font
					(size 1 1)
					(thickness 0.15)
				)
				(justify mirror)
			)
		)
		(property "MPN" "CL10A226MO7JZNC"
			(at 209.3 308.92 0)
			(layer "B.Fab")
			(hide yes)
			(effects
				(font
					(size 1 1)
					(thickness 0.15)
				)
				(justify mirror)
			)
		)
		(property "Manufacturer" "Samsung Electro-Mechanics"
			(at 209.3 308.92 0)
			(layer "B.Fab")
			(hide yes)
			(effects
				(font
					(size 1 1)
					(thickness 0.15)
				)
				(justify mirror)
			)
		)
		(property "Public" "False"
			(at 209.3 308.92 0)
			(layer "B.Fab")
			(hide yes)
			(effects
				(font
					(size 1 1)
					(thickness 0.15)
				)
				(justify mirror)
			)
		)
		(property "Val" "22u"
			(at 209.3 308.92 0)
			(layer "B.Fab")
			(hide yes)
			(effects
				(font
					(size 1 1)
					(thickness 0.15)
				)
				(justify mirror)
			)
		)
		(property "Voltage" "16V"
			(at 209.3 308.92 0)
			(layer "B.Fab")
			(hide yes)
			(effects
				(font
					(size 1 1)
					(thickness 0.15)
				)
				(justify mirror)
			)
		)
		(sheetname "OCuLink")
		(sheetfile "oculink.kicad_sch")
		(attr smd)
		(fp_line
			(start 0.15 0.4)
			(end -0.15 0.4)
			(stroke
				(width 0.15)
				(type solid)
			)
			(layer "B.SilkS")
		)
		(fp_line
			(start 0.15 -0.4)
			(end -0.15 -0.4)
			(stroke
				(width 0.15)
				(type solid)
			)
			(layer "B.SilkS")
		)
		(fp_rect
			(start -1.25 0.65)
			(end 1.25 -0.65)
			(stroke
				(width 0.05)
				(type solid)
			)
			(fill no)
			(layer "B.CrtYd")
		)
		(fp_rect
			(start -0.8 0.4)
			(end 0.8 -0.4)
			(stroke
				(width 0.15)
				(type solid)
			)
			(fill no)
			(layer "B.Fab")
		)
		(pad "1" smd roundrect
			(at -0.7 0 180)
			(size 0.8 1)
			(layers "B.Cu" "B.Mask" "B.Paste")
			(roundrect_rratio 0.2)
			(net 1 "GND")
			(pintype "passive")
			(teardrops
				(best_length_ratio 0.2)
				(max_length 1)
				(best_width_ratio 0.9)
				(max_width 2)
				(curved_edges yes)
				(filter_ratio 0.9)
				(enabled yes)
				(allow_two_segments yes)
				(prefer_zone_connections yes)
			)
		)
		(pad "2" smd roundrect
			(at 0.7 0 180)
			(size 0.8 1)
			(layers "B.Cu" "B.Mask" "B.Paste")
			(roundrect_rratio 0.2)
			(net 61 "/OCuLink/5V_CONN0")
			(pintype "passive")
			(teardrops
				(best_length_ratio 0.2)
				(max_length 1)
				(best_width_ratio 0.9)
				(max_width 2)
				(curved_edges yes)
				(filter_ratio 0.9)
				(enabled yes)
				(allow_two_segments yes)
				(prefer_zone_connections yes)
			)
		)
	)
	(footprint "antmicro-footprints:C_0402_1005Metric"
		(layer "B.Cu")
		(at 152.05 168.24 -90)
		(descr "Capacitor SMD 0402")
		(tags "capacitor SMD 0402")
		(property "Reference" "C213"
			(at -1.43 -1.4 90)
			(layer "B.SilkS")
			(effects
				(font
					(size 0.7 0.7)
					(thickness 0.15)
				)
				(justify left bottom mirror)
			)
		)
		(property "Value" "C_100n_0402"
			(at -1.022927 -2.155213 90)
			(layer "B.Fab")
			(effects
				(font
					(size 0.7 0.7)
					(thickness 0.15)
				)
				(justify left bottom mirror)
			)
		)
		(property "Datasheet" "https://www.murata.com/products/productdetail?partno=GRM155R61H104KE14%23"
			(at 0 0 270)
			(layer "F.Fab")
			(hide yes)
			(effects
				(font
					(size 1.27 1.27)
					(thickness 0.15)
				)
			)
		)
		(property "Author" "Antmicro"
			(at -16.19 320.29 0)
			(layer "B.Fab")
			(hide yes)
			(effects
				(font
					(size 1 1)
					(thickness 0.15)
				)
				(justify mirror)
			)
		)
		(property "Dielectric" "X5R"
			(at -16.19 320.29 0)
			(layer "B.Fab")
			(hide yes)
			(effects
				(font
					(size 1 1)
					(thickness 0.15)
				)
				(justify mirror)
			)
		)
		(property "License" "Apache-2.0"
			(at -16.19 320.29 0)
			(layer "B.Fab")
			(hide yes)
			(effects
				(font
					(size 1 1)
					(thickness 0.15)
				)
				(justify mirror)
			)
		)
		(property "MPN" "GRM155R61H104KE14D"
			(at -16.19 320.29 0)
			(layer "B.Fab")
			(hide yes)
			(effects
				(font
					(size 1 1)
					(thickness 0.15)
				)
				(justify mirror)
			)
		)
		(property "Manufacturer" "Murata"
			(at -16.19 320.29 0)
			(layer "B.Fab")
			(hide yes)
			(effects
				(font
					(size 1 1)
					(thickness 0.15)
				)
				(justify mirror)
			)
		)
		(property "Public" "False"
			(at -16.19 320.29 0)
			(layer "B.Fab")
			(hide yes)
			(effects
				(font
					(size 1 1)
					(thickness 0.15)
				)
				(justify mirror)
			)
		)
		(property "Val" "100n"
			(at -16.19 320.29 0)
			(layer "B.Fab")
			(hide yes)
			(effects
				(font
					(size 1 1)
					(thickness 0.15)
				)
				(justify mirror)
			)
		)
		(property "Voltage" "50V"
			(at -16.19 320.29 0)
			(layer "B.Fab")
			(hide yes)
			(effects
				(font
					(size 1 1)
					(thickness 0.15)
				)
				(justify mirror)
			)
		)
		(sheetname "2xSFP+")
		(sheetfile "2xSFP+.kicad_sch")
		(attr smd)
		(fp_rect
			(start -0.925 0.47)
			(end 0.925 -0.47)
			(stroke
				(width 0.05)
				(type default)
			)
			(fill no)
			(layer "B.CrtYd")
		)
		(fp_line
			(start -0.494 0.25)
			(end -0.494 -0.248)
			(stroke
				(width 0.15)
				(type solid)
			)
			(layer "B.Fab")
		)
		(fp_line
			(start 0.504 0.25)
			(end -0.494 0.25)
			(stroke
				(width 0.15)
				(type solid)
			)
			(layer "B.Fab")
		)
		(fp_line
			(start -0.494 -0.248)
			(end 0.504 -0.248)
			(stroke
				(width 0.15)
				(type solid)
			)
			(layer "B.Fab")
		)
		(fp_line
			(start 0.504 -0.248)
			(end 0.504 0.25)
			(stroke
				(width 0.15)
				(type solid)
			)
			(layer "B.Fab")
		)
		(pad "1" smd roundrect
			(at -0.48 0 270)
			(size 0.59 0.64)
			(layers "B.Cu" "B.Mask" "B.Paste")
			(roundrect_rratio 0.25)
			(net 53 "/2xSFP+/SH")
			(pintype "passive")
			(teardrops
				(best_length_ratio 0.2)
				(max_length 1)
				(best_width_ratio 0.9)
				(max_width 2)
				(curved_edges yes)
				(filter_ratio 0.9)
				(enabled yes)
				(allow_two_segments yes)
				(prefer_zone_connections yes)
			)
		)
		(pad "2" smd roundrect
			(at 0.48 0 270)
			(size 0.59 0.64)
			(layers "B.Cu" "B.Mask" "B.Paste")
			(roundrect_rratio 0.25)
			(net 1 "GND")
			(pintype "passive")
			(teardrops
				(best_length_ratio 0.2)
				(max_length 1)
				(best_width_ratio 0.9)
				(max_width 2)
				(curved_edges yes)
				(filter_ratio 0.9)
				(enabled yes)
				(allow_two_segments yes)
				(prefer_zone_connections yes)
			)
		)
	)
	(footprint "antmicro-footprints:R_0402_1005Metric"
		(layer "B.Cu")
		(at 141.05 169.16 -90)
		(descr "Resistor SMD 0402")
		(tags "resistor SMD 0402")
		(property "Reference" "R56"
			(at -3.9 13.5 90)
			(layer "B.SilkS")
			(effects
				(font
					(size 0.7 0.7)
					(thickness 0.15)
				)
				(justify left bottom mirror)
			)
		)
		(property "Value" "R_1k_0402"
			(at -1.011843 -1.772047 90)
			(layer "B.Fab")
			(effects
				(font
					(size 0.7 0.7)
					(thickness 0.15)
				)
				(justify left bottom mirror)
			)
		)
		(property "Datasheet" "https://www.bourns.com/docs/product-datasheets/cr.pdf"
			(at 0 0 270)
			(layer "F.Fab")
			(hide yes)
			(effects
				(font
					(size 1.27 1.27)
					(thickness 0.15)
				)
			)
		)
		(property "Author" "Antmicro"
			(at -28.11 310.21 0)
			(layer "B.Fab")
			(hide yes)
			(effects
				(font
					(size 1 1)
					(thickness 0.15)
				)
				(justify mirror)
			)
		)
		(property "License" "Apache-2.0"
			(at -28.11 310.21 0)
			(layer "B.Fab")
			(hide yes)
			(effects
				(font
					(size 1 1)
					(thickness 0.15)
				)
				(justify mirror)
			)
		)
		(property "MPN" "CR0402-FX-1001GLF"
			(at -28.11 310.21 0)
			(layer "B.Fab")
			(hide yes)
			(effects
				(font
					(size 1 1)
					(thickness 0.15)
				)
				(justify mirror)
			)
		)
		(property "Manufacturer" "Bourns"
			(at -28.11 310.21 0)
			(layer "B.Fab")
			(hide yes)
			(effects
				(font
					(size 1 1)
					(thickness 0.15)
				)
				(justify mirror)
			)
		)
		(property "Public" "False"
			(at -28.11 310.21 0)
			(layer "B.Fab")
			(hide yes)
			(effects
				(font
					(size 1 1)
					(thickness 0.15)
				)
				(justify mirror)
			)
		)
		(property "Tolerance" "1%"
			(at -28.11 310.21 0)
			(layer "B.Fab")
			(hide yes)
			(effects
				(font
					(size 1 1)
					(thickness 0.15)
				)
				(justify mirror)
			)
		)
		(property "Val" "1k"
			(at -28.11 310.21 0)
			(layer "B.Fab")
			(hide yes)
			(effects
				(font
					(size 1 1)
					(thickness 0.15)
				)
				(justify mirror)
			)
		)
		(sheetname "2xSFP+")
		(sheetfile "2xSFP+.kicad_sch")
		(attr smd)
		(fp_rect
			(start -0.925 0.47)
			(end 0.925 -0.47)
			(stroke
				(width 0.05)
				(type default)
			)
			(fill no)
			(layer "B.CrtYd")
		)
		(fp_rect
			(start -0.5 0.25)
			(end 0.5 -0.25)
			(stroke
				(width 0.15)
				(type solid)
			)
			(fill no)
			(layer "B.Fab")
		)
		(pad "1" smd roundrect
			(at -0.48 0 270)
			(size 0.59 0.64)
			(layers "B.Cu" "B.Mask" "B.Paste")
			(roundrect_rratio 0.25)
			(net 894 "Net-(J2B-MOD_{ABS})")
			(pintype "passive")
			(teardrops
				(best_length_ratio 0.2)
				(max_length 1)
				(best_width_ratio 0.9)
				(max_width 2)
				(curved_edges yes)
				(filter_ratio 0.9)
				(enabled yes)
				(allow_two_segments yes)
				(prefer_zone_connections yes)
			)
		)
		(pad "2" smd roundrect
			(at 0.48 0 270)
			(size 0.59 0.64)
			(layers "B.Cu" "B.Mask" "B.Paste")
			(roundrect_rratio 0.25)
			(net 2 "+3V3")
			(pintype "passive")
			(teardrops
				(best_length_ratio 0.2)
				(max_length 1)
				(best_width_ratio 0.9)
				(max_width 2)
				(curved_edges yes)
				(filter_ratio 0.9)
				(enabled yes)
				(allow_two_segments yes)
				(prefer_zone_connections yes)
			)
		)
	)
	(footprint "antmicro-footprints:R_0402_1005Metric"
		(layer "B.Cu")
		(at 308.824999 101.76 -90)
		(descr "Resistor SMD 0402")
		(tags "resistor SMD 0402")
		(property "Reference" "R87"
			(at -3.06 -0.455001 90)
			(layer "B.SilkS")
			(effects
				(font
					(size 0.7 0.7)
					(thickness 0.15)
				)
				(justify left bottom mirror)
			)
		)
		(property "Value" "R_30k_0402"
			(at -1.011843 -1.772047 90)
			(layer "B.Fab")
			(effects
				(font
					(size 0.7 0.7)
					(thickness 0.15)
				)
				(justify left bottom mirror)
			)
		)
		(property "Datasheet" "https://www.bourns.com/docs/product-datasheets/cr.pdf"
			(at 0 0 270)
			(layer "F.Fab")
			(hide yes)
			(effects
				(font
					(size 1.27 1.27)
					(thickness 0.15)
				)
			)
		)
		(property "Author" "Antmicro"
			(at 207.064999 410.584999 0)
			(layer "B.Fab")
			(hide yes)
			(effects
				(font
					(size 1 1)
					(thickness 0.15)
				)
				(justify mirror)
			)
		)
		(property "License" "Apache-2.0"
			(at 207.064999 410.584999 0)
			(layer "B.Fab")
			(hide yes)
			(effects
				(font
					(size 1 1)
					(thickness 0.15)
				)
				(justify mirror)
			)
		)
		(property "MPN" "CR0402-FX-3002GLF"
			(at 207.064999 410.584999 0)
			(layer "B.Fab")
			(hide yes)
			(effects
				(font
					(size 1 1)
					(thickness 0.15)
				)
				(justify mirror)
			)
		)
		(property "Manufacturer" "Bourns"
			(at 207.064999 410.584999 0)
			(layer "B.Fab")
			(hide yes)
			(effects
				(font
					(size 1 1)
					(thickness 0.15)
				)
				(justify mirror)
			)
		)
		(property "Public" "False"
			(at 207.064999 410.584999 0)
			(layer "B.Fab")
			(hide yes)
			(effects
				(font
					(size 1 1)
					(thickness 0.15)
				)
				(justify mirror)
			)
		)
		(property "Tolerance" "1%"
			(at 207.064999 410.584999 0)
			(layer "B.Fab")
			(hide yes)
			(effects
				(font
					(size 1 1)
					(thickness 0.15)
				)
				(justify mirror)
			)
		)
		(property "Val" "30k"
			(at 207.064999 410.584999 0)
			(layer "B.Fab")
			(hide yes)
			(effects
				(font
					(size 1 1)
					(thickness 0.15)
				)
				(justify mirror)
			)
		)
		(sheetname "Power")
		(sheetfile "power.kicad_sch")
		(attr smd)
		(fp_rect
			(start -0.925 0.47)
			(end 0.925 -0.47)
			(stroke
				(width 0.05)
				(type default)
			)
			(fill no)
			(layer "B.CrtYd")
		)
		(fp_rect
			(start -0.5 0.25)
			(end 0.5 -0.25)
			(stroke
				(width 0.15)
				(type solid)
			)
			(fill no)
			(layer "B.Fab")
		)
		(pad "1" smd roundrect
			(at -0.48 0 270)
			(size 0.59 0.64)
			(layers "B.Cu" "B.Mask" "B.Paste")
			(roundrect_rratio 0.25)
			(net 574 "Net-(U19-EN)")
			(pintype "passive")
			(teardrops
				(best_length_ratio 0.2)
				(max_length 1)
				(best_width_ratio 0.9)
				(max_width 2)
				(curved_edges yes)
				(filter_ratio 0.9)
				(enabled yes)
				(allow_two_segments yes)
				(prefer_zone_connections yes)
			)
		)
		(pad "2" smd roundrect
			(at 0.48 0 270)
			(size 0.59 0.64)
			(layers "B.Cu" "B.Mask" "B.Paste")
			(roundrect_rratio 0.25)
			(net 1 "GND")
			(pintype "passive")
			(teardrops
				(best_length_ratio 0.2)
				(max_length 1)
				(best_width_ratio 0.9)
				(max_width 2)
				(curved_edges yes)
				(filter_ratio 0.9)
				(enabled yes)
				(allow_two_segments yes)
				(prefer_zone_connections yes)
			)
		)
	)
	(footprint "antmicro-footprints:C_0402_1005Metric"
		(layer "B.Cu")
		(at 143.377 149.258 -90)
		(descr "Capacitor SMD 0402")
		(tags "capacitor SMD 0402")
		(property "Reference" "C149"
			(at -1.398 1.427 90)
			(layer "B.SilkS")
			(effects
				(font
					(size 0.7 0.7)
					(thickness 0.15)
				)
				(justify left bottom mirror)
			)
		)
		(property "Value" "C_100n_0402"
			(at -1.022927 -2.155213 90)
			(layer "B.Fab")
			(effects
				(font
					(size 0.7 0.7)
					(thickness 0.15)
				)
				(justify left bottom mirror)
			)
		)
		(property "Datasheet" "https://www.murata.com/products/productdetail?partno=GRM155R61H104KE14%23"
			(at 0 0 270)
			(layer "F.Fab")
			(hide yes)
			(effects
				(font
					(size 1.27 1.27)
					(thickness 0.15)
				)
			)
		)
		(property "Author" "Antmicro"
			(at -5.881 292.635 0)
			(layer "B.Fab")
			(hide yes)
			(effects
				(font
					(size 1 1)
					(thickness 0.15)
				)
				(justify mirror)
			)
		)
		(property "Dielectric" "X5R"
			(at -5.881 292.635 0)
			(layer "B.Fab")
			(hide yes)
			(effects
				(font
					(size 1 1)
					(thickness 0.15)
				)
				(justify mirror)
			)
		)
		(property "License" "Apache-2.0"
			(at -5.881 292.635 0)
			(layer "B.Fab")
			(hide yes)
			(effects
				(font
					(size 1 1)
					(thickness 0.15)
				)
				(justify mirror)
			)
		)
		(property "MPN" "GRM155R61H104KE14D"
			(at -5.881 292.635 0)
			(layer "B.Fab")
			(hide yes)
			(effects
				(font
					(size 1 1)
					(thickness 0.15)
				)
				(justify mirror)
			)
		)
		(property "Manufacturer" "Murata"
			(at -5.881 292.635 0)
			(layer "B.Fab")
			(hide yes)
			(effects
				(font
					(size 1 1)
					(thickness 0.15)
				)
				(justify mirror)
			)
		)
		(property "Public" "False"
			(at -5.881 292.635 0)
			(layer "B.Fab")
			(hide yes)
			(effects
				(font
					(size 1 1)
					(thickness 0.15)
				)
				(justify mirror)
			)
		)
		(property "Val" "100n"
			(at -5.881 292.635 0)
			(layer "B.Fab")
			(hide yes)
			(effects
				(font
					(size 1 1)
					(thickness 0.15)
				)
				(justify mirror)
			)
		)
		(property "Voltage" "50V"
			(at -5.881 292.635 0)
			(layer "B.Fab")
			(hide yes)
			(effects
				(font
					(size 1 1)
					(thickness 0.15)
				)
				(justify mirror)
			)
		)
		(sheetname "KR to SFI #1")
		(sheetfile "kr_sfi.kicad_sch")
		(attr smd)
		(fp_rect
			(start -0.925 0.47)
			(end 0.925 -0.47)
			(stroke
				(width 0.05)
				(type default)
			)
			(fill no)
			(layer "B.CrtYd")
		)
		(fp_line
			(start -0.494 0.25)
			(end -0.494 -0.248)
			(stroke
				(width 0.15)
				(type solid)
			)
			(layer "B.Fab")
		)
		(fp_line
			(start 0.504 0.25)
			(end -0.494 0.25)
			(stroke
				(width 0.15)
				(type solid)
			)
			(layer "B.Fab")
		)
		(fp_line
			(start -0.494 -0.248)
			(end 0.504 -0.248)
			(stroke
				(width 0.15)
				(type solid)
			)
			(layer "B.Fab")
		)
		(fp_line
			(start 0.504 -0.248)
			(end 0.504 0.25)
			(stroke
				(width 0.15)
				(type solid)
			)
			(layer "B.Fab")
		)
		(pad "1" smd roundrect
			(at -0.48 0 270)
			(size 0.59 0.64)
			(layers "B.Cu" "B.Mask" "B.Paste")
			(roundrect_rratio 0.25)
			(net 1 "GND")
			(pintype "passive")
			(teardrops
				(best_length_ratio 0.2)
				(max_length 1)
				(best_width_ratio 0.9)
				(max_width 2)
				(curved_edges yes)
				(filter_ratio 0.9)
				(enabled yes)
				(allow_two_segments yes)
				(prefer_zone_connections yes)
			)
		)
		(pad "2" smd roundrect
			(at 0.48 0 270)
			(size 0.59 0.64)
			(layers "B.Cu" "B.Mask" "B.Paste")
			(roundrect_rratio 0.25)
			(net 2 "+3V3")
			(pintype "passive")
			(teardrops
				(best_length_ratio 0.2)
				(max_length 1)
				(best_width_ratio 0.9)
				(max_width 2)
				(curved_edges yes)
				(filter_ratio 0.9)
				(enabled yes)
				(allow_two_segments yes)
				(prefer_zone_connections yes)
			)
		)
	)
	(footprint "antmicro-footprints:C_0603_1608Metric"
		(layer "B.Cu")
		(at 237.495708 74.06 180)
		(descr "Capacitor SMD 0603")
		(tags "capacitor 0603")
		(property "Reference" "C7"
			(at -0.825 -1.55 0)
			(layer "B.SilkS")
			(effects
				(font
					(size 0.7 0.7)
					(thickness 0.15)
				)
				(justify left bottom mirror)
			)
		)
		(property "Value" "C_22u_16V_0603"
			(at -1.42757 -1.770288 0)
			(layer "B.Fab")
			(effects
				(font
					(size 0.7 0.7)
					(thickness 0.15)
				)
				(justify left bottom mirror)
			)
		)
		(property "Datasheet" "https://product.samsungsem.com/mlcc/CL10A226MO7JZN.do"
			(at 0 0 180)
			(layer "F.Fab")
			(hide yes)
			(effects
				(font
					(size 1.27 1.27)
					(thickness 0.15)
				)
			)
		)
		(property "Author" "Antmicro"
			(at 474.991416 148.12 0)
			(layer "B.Fab")
			(hide yes)
			(effects
				(font
					(size 1 1)
					(thickness 0.15)
				)
				(justify mirror)
			)
		)
		(property "Dielectric" ""
			(at 474.991416 148.12 0)
			(layer "B.Fab")
			(hide yes)
			(effects
				(font
					(size 1 1)
					(thickness 0.15)
				)
				(justify mirror)
			)
		)
		(property "License" "Apache-2.0"
			(at 474.991416 148.12 0)
			(layer "B.Fab")
			(hide yes)
			(effects
				(font
					(size 1 1)
					(thickness 0.15)
				)
				(justify mirror)
			)
		)
		(property "MPN" "CL10A226MO7JZNC"
			(at 474.991416 148.12 0)
			(layer "B.Fab")
			(hide yes)
			(effects
				(font
					(size 1 1)
					(thickness 0.15)
				)
				(justify mirror)
			)
		)
		(property "Manufacturer" "Samsung Electro-Mechanics"
			(at 474.991416 148.12 0)
			(layer "B.Fab")
			(hide yes)
			(effects
				(font
					(size 1 1)
					(thickness 0.15)
				)
				(justify mirror)
			)
		)
		(property "Public" "False"
			(at 474.991416 148.12 0)
			(layer "B.Fab")
			(hide yes)
			(effects
				(font
					(size 1 1)
					(thickness 0.15)
				)
				(justify mirror)
			)
		)
		(property "Val" "22u"
			(at 474.991416 148.12 0)
			(layer "B.Fab")
			(hide yes)
			(effects
				(font
					(size 1 1)
					(thickness 0.15)
				)
				(justify mirror)
			)
		)
		(property "Voltage" "16V"
			(at 474.991416 148.12 0)
			(layer "B.Fab")
			(hide yes)
			(effects
				(font
					(size 1 1)
					(thickness 0.15)
				)
				(justify mirror)
			)
		)
		(sheetname "Misc")
		(sheetfile "misc.kicad_sch")
		(attr smd)
		(fp_line
			(start 0.15 0.4)
			(end -0.15 0.4)
			(stroke
				(width 0.15)
				(type solid)
			)
			(layer "B.SilkS")
		)
		(fp_line
			(start 0.15 -0.4)
			(end -0.15 -0.4)
			(stroke
				(width 0.15)
				(type solid)
			)
			(layer "B.SilkS")
		)
		(fp_rect
			(start -1.25 0.65)
			(end 1.25 -0.65)
			(stroke
				(width 0.05)
				(type solid)
			)
			(fill no)
			(layer "B.CrtYd")
		)
		(fp_rect
			(start -0.8 0.4)
			(end 0.8 -0.4)
			(stroke
				(width 0.15)
				(type solid)
			)
			(fill no)
			(layer "B.Fab")
		)
		(pad "1" smd roundrect
			(at -0.7 0 180)
			(size 0.8 1)
			(layers "B.Cu" "B.Mask" "B.Paste")
			(roundrect_rratio 0.2)
			(net 1 "GND")
			(pintype "passive")
			(teardrops
				(best_length_ratio 0.2)
				(max_length 1)
				(best_width_ratio 0.9)
				(max_width 2)
				(curved_edges yes)
				(filter_ratio 0.9)
				(enabled yes)
				(allow_two_segments yes)
				(prefer_zone_connections yes)
			)
		)
		(pad "2" smd roundrect
			(at 0.7 0 180)
			(size 0.8 1)
			(layers "B.Cu" "B.Mask" "B.Paste")
			(roundrect_rratio 0.2)
			(net 81 "/Misc/FAN_12V")
			(pintype "passive")
			(teardrops
				(best_length_ratio 0.2)
				(max_length 1)
				(best_width_ratio 0.9)
				(max_width 2)
				(curved_edges yes)
				(filter_ratio 0.9)
				(enabled yes)
				(allow_two_segments yes)
				(prefer_zone_connections yes)
			)
		)
	)
	(footprint "antmicro-footprints:C_0402_1005Metric"
		(layer "B.Cu")
		(at 132.29 138.36 -90)
		(descr "Capacitor SMD 0402")
		(tags "capacitor SMD 0402")
		(property "Reference" "C199"
			(at -0.35 0.54 90)
			(layer "B.SilkS")
			(effects
				(font
					(size 0.7 0.7)
					(thickness 0.15)
				)
				(justify left bottom mirror)
			)
		)
		(property "Value" "C_100n_0402"
			(at -1.022927 -2.155213 90)
			(layer "B.Fab")
			(effects
				(font
					(size 0.7 0.7)
					(thickness 0.15)
				)
				(justify left bottom mirror)
			)
		)
		(property "Datasheet" "https://www.murata.com/products/productdetail?partno=GRM155R61H104KE14%23"
			(at 0 0 270)
			(layer "F.Fab")
			(hide yes)
			(effects
				(font
					(size 1.27 1.27)
					(thickness 0.15)
				)
			)
		)
		(property "Author" "Antmicro"
			(at -6.07 270.65 0)
			(layer "B.Fab")
			(hide yes)
			(effects
				(font
					(size 1 1)
					(thickness 0.15)
				)
				(justify mirror)
			)
		)
		(property "Dielectric" "X5R"
			(at -6.07 270.65 0)
			(layer "B.Fab")
			(hide yes)
			(effects
				(font
					(size 1 1)
					(thickness 0.15)
				)
				(justify mirror)
			)
		)
		(property "License" "Apache-2.0"
			(at -6.07 270.65 0)
			(layer "B.Fab")
			(hide yes)
			(effects
				(font
					(size 1 1)
					(thickness 0.15)
				)
				(justify mirror)
			)
		)
		(property "MPN" "GRM155R61H104KE14D"
			(at -6.07 270.65 0)
			(layer "B.Fab")
			(hide yes)
			(effects
				(font
					(size 1 1)
					(thickness 0.15)
				)
				(justify mirror)
			)
		)
		(property "Manufacturer" "Murata"
			(at -6.07 270.65 0)
			(layer "B.Fab")
			(hide yes)
			(effects
				(font
					(size 1 1)
					(thickness 0.15)
				)
				(justify mirror)
			)
		)
		(property "Public" "False"
			(at -6.07 270.65 0)
			(layer "B.Fab")
			(hide yes)
			(effects
				(font
					(size 1 1)
					(thickness 0.15)
				)
				(justify mirror)
			)
		)
		(property "Val" "100n"
			(at -6.07 270.65 0)
			(layer "B.Fab")
			(hide yes)
			(effects
				(font
					(size 1 1)
					(thickness 0.15)
				)
				(justify mirror)
			)
		)
		(property "Voltage" "50V"
			(at -6.07 270.65 0)
			(layer "B.Fab")
			(hide yes)
			(effects
				(font
					(size 1 1)
					(thickness 0.15)
				)
				(justify mirror)
			)
		)
		(sheetname "KR to SFI #2")
		(sheetfile "kr_sfi.kicad_sch")
		(attr smd)
		(fp_rect
			(start -0.925 0.47)
			(end 0.925 -0.47)
			(stroke
				(width 0.05)
				(type default)
			)
			(fill no)
			(layer "B.CrtYd")
		)
		(fp_line
			(start -0.494 0.25)
			(end -0.494 -0.248)
			(stroke
				(width 0.15)
				(type solid)
			)
			(layer "B.Fab")
		)
		(fp_line
			(start 0.504 0.25)
			(end -0.494 0.25)
			(stroke
				(width 0.15)
				(type solid)
			)
			(layer "B.Fab")
		)
		(fp_line
			(start -0.494 -0.248)
			(end 0.504 -0.248)
			(stroke
				(width 0.15)
				(type solid)
			)
			(layer "B.Fab")
		)
		(fp_line
			(start 0.504 -0.248)
			(end 0.504 0.25)
			(stroke
				(width 0.15)
				(type solid)
			)
			(layer "B.Fab")
		)
		(pad "1" smd roundrect
			(at -0.48 0 270)
			(size 0.59 0.64)
			(layers "B.Cu" "B.Mask" "B.Paste")
			(roundrect_rratio 0.25)
			(net 1 "GND")
			(pintype "passive")
			(teardrops
				(best_length_ratio 0.2)
				(max_length 1)
				(best_width_ratio 0.9)
				(max_width 2)
				(curved_edges yes)
				(filter_ratio 0.9)
				(enabled yes)
				(allow_two_segments yes)
				(prefer_zone_connections yes)
			)
		)
		(pad "2" smd roundrect
			(at 0.48 0 270)
			(size 0.59 0.64)
			(layers "B.Cu" "B.Mask" "B.Paste")
			(roundrect_rratio 0.25)
			(net 74 "+1V0")
			(pintype "passive")
			(teardrops
				(best_length_ratio 0.2)
				(max_length 1)
				(best_width_ratio 0.9)
				(max_width 2)
				(curved_edges yes)
				(filter_ratio 0.9)
				(enabled yes)
				(allow_two_segments yes)
				(prefer_zone_connections yes)
			)
		)
	)
	(footprint "antmicro-footprints:TP_SMD_0.75mm"
		(layer "B.Cu")
		(at 186.7 169.9 180)
		(property "Reference" "TP34"
			(at 0.45 0.499999 0)
			(layer "B.SilkS")
			(effects
				(font
					(size 0.7 0.7)
					(thickness 0.15)
				)
				(justify left top mirror)
			)
		)
		(property "Value" "TP_0.75mm_SMD"
			(at 0 -1.2 0)
			(layer "B.Fab")
			(effects
				(font
					(size 0.7 0.7)
					(thickness 0.15)
				)
				(justify left top mirror)
			)
		)
		(property "Author" "Antmicro"
			(at 363.960001 -65.84 90)
			(layer "B.Fab")
			(hide yes)
			(effects
				(font
					(size 1 1)
					(thickness 0.15)
				)
				(justify mirror)
			)
		)
		(property "License" "Apache-2.0"
			(at 363.960001 -65.84 90)
			(layer "B.Fab")
			(hide yes)
			(effects
				(font
					(size 1 1)
					(thickness 0.15)
				)
				(justify mirror)
			)
		)
		(property "MPN" ""
			(at 363.960001 -65.84 90)
			(layer "B.Fab")
			(hide yes)
			(effects
				(font
					(size 1 1)
					(thickness 0.15)
				)
				(justify mirror)
			)
		)
		(property "Manufacturer" ""
			(at 363.960001 -65.84 90)
			(layer "B.Fab")
			(hide yes)
			(effects
				(font
					(size 1 1)
					(thickness 0.15)
				)
				(justify mirror)
			)
		)
		(property "Public" "False"
			(at 363.960001 -65.84 90)
			(layer "B.Fab")
			(hide yes)
			(effects
				(font
					(size 1 1)
					(thickness 0.15)
				)
				(justify mirror)
			)
		)
		(sheetname "Com Express 7 MGMT")
		(sheetfile "com_express_7_mgmt.kicad_sch")
		(attr exclude_from_pos_files exclude_from_bom)
		(fp_circle
			(center 0 0)
			(end 0.475 0)
			(stroke
				(width 0.05)
				(type default)
			)
			(fill no)
			(layer "B.CrtYd")
		)
		(pad "1" smd circle
			(at 0 0 180)
			(size 0.75 0.75)
			(layers "B.Cu" "B.Mask")
			(net 311 "Net-(J12D-~{THRMTRIP})")
			(pinfunction "1")
			(pintype "passive")
			(teardrops
				(best_length_ratio 0.4)
				(max_length 1)
				(best_width_ratio 0.9)
				(max_width 2)
				(curved_edges yes)
				(filter_ratio 0.9)
				(enabled yes)
				(allow_two_segments yes)
				(prefer_zone_connections yes)
			)
		)
	)
	(footprint "antmicro-footprints:TP_SMD_0.75mm"
		(layer "B.Cu")
		(at 217.58 124.85 45)
		(property "Reference" "TP46"
			(at 0.572756 0.021213 90)
			(layer "B.SilkS")
			(effects
				(font
					(size 0.7 0.7)
					(thickness 0.15)
				)
				(justify right bottom mirror)
			)
		)
		(property "Value" "TP_0.75mm_SMD"
			(at 0 -1.2 45)
			(layer "B.Fab")
			(effects
				(font
					(size 0.7 0.7)
					(thickness 0.15)
				)
				(justify right bottom mirror)
			)
		)
		(property "Author" "Antmicro"
			(at 152.009988 -117.284575 0)
			(layer "B.Fab")
			(hide yes)
			(effects
				(font
					(size 1 1)
					(thickness 0.15)
				)
				(justify mirror)
			)
		)
		(property "License" "Apache-2.0"
			(at 152.009988 -117.284575 0)
			(layer "B.Fab")
			(hide yes)
			(effects
				(font
					(size 1 1)
					(thickness 0.15)
				)
				(justify mirror)
			)
		)
		(property "MPN" ""
			(at 152.009988 -117.284575 0)
			(layer "B.Fab")
			(hide yes)
			(effects
				(font
					(size 1 1)
					(thickness 0.15)
				)
				(justify mirror)
			)
		)
		(property "Manufacturer" ""
			(at 152.009988 -117.284575 0)
			(layer "B.Fab")
			(hide yes)
			(effects
				(font
					(size 1 1)
					(thickness 0.15)
				)
				(justify mirror)
			)
		)
		(property "Public" "False"
			(at 152.009988 -117.284575 0)
			(layer "B.Fab")
			(hide yes)
			(effects
				(font
					(size 1 1)
					(thickness 0.15)
				)
				(justify mirror)
			)
		)
		(sheetname "PCIe misc")
		(sheetfile "pcie_misc.kicad_sch")
		(attr exclude_from_pos_files exclude_from_bom)
		(fp_circle
			(center 0 0)
			(end 0.475 0)
			(stroke
				(width 0.05)
				(type default)
			)
			(fill no)
			(layer "B.CrtYd")
		)
		(pad "1" smd circle
			(at 0 0 45)
			(size 0.75 0.75)
			(layers "B.Cu" "B.Mask")
			(net 711 "Net-(U37-SADR_{TRI})")
			(pinfunction "1")
			(pintype "passive")
			(teardrops
				(best_length_ratio 0.4)
				(max_length 1)
				(best_width_ratio 0.9)
				(max_width 2)
				(curved_edges yes)
				(filter_ratio 0.9)
				(enabled yes)
				(allow_two_segments yes)
				(prefer_zone_connections yes)
			)
		)
	)
	(footprint "antmicro-footprints:C_0402_1005Metric"
		(layer "B.Cu")
		(at 151.25 160.23 -90)
		(descr "Capacitor SMD 0402")
		(tags "capacitor SMD 0402")
		(property "Reference" "C24"
			(at -1.12 -2.45 90)
			(layer "B.SilkS")
			(effects
				(font
					(size 0.7 0.7)
					(thickness 0.15)
				)
				(justify left bottom mirror)
			)
		)
		(property "Value" "C_100n_0402"
			(at -1.022927 -2.155213 90)
			(layer "B.Fab")
			(effects
				(font
					(size 0.7 0.7)
					(thickness 0.15)
				)
				(justify left bottom mirror)
			)
		)
		(property "Datasheet" "https://www.murata.com/products/productdetail?partno=GRM155R61H104KE14%23"
			(at 0 0 270)
			(layer "F.Fab")
			(hide yes)
			(effects
				(font
					(size 1.27 1.27)
					(thickness 0.15)
				)
			)
		)
		(property "Author" "Antmicro"
			(at -8.98 311.48 0)
			(layer "B.Fab")
			(hide yes)
			(effects
				(font
					(size 1 1)
					(thickness 0.15)
				)
				(justify mirror)
			)
		)
		(property "Dielectric" "X5R"
			(at -8.98 311.48 0)
			(layer "B.Fab")
			(hide yes)
			(effects
				(font
					(size 1 1)
					(thickness 0.15)
				)
				(justify mirror)
			)
		)
		(property "License" "Apache-2.0"
			(at -8.98 311.48 0)
			(layer "B.Fab")
			(hide yes)
			(effects
				(font
					(size 1 1)
					(thickness 0.15)
				)
				(justify mirror)
			)
		)
		(property "MPN" "GRM155R61H104KE14D"
			(at -8.98 311.48 0)
			(layer "B.Fab")
			(hide yes)
			(effects
				(font
					(size 1 1)
					(thickness 0.15)
				)
				(justify mirror)
			)
		)
		(property "Manufacturer" "Murata"
			(at -8.98 311.48 0)
			(layer "B.Fab")
			(hide yes)
			(effects
				(font
					(size 1 1)
					(thickness 0.15)
				)
				(justify mirror)
			)
		)
		(property "Public" "False"
			(at -8.98 311.48 0)
			(layer "B.Fab")
			(hide yes)
			(effects
				(font
					(size 1 1)
					(thickness 0.15)
				)
				(justify mirror)
			)
		)
		(property "Val" "100n"
			(at -8.98 311.48 0)
			(layer "B.Fab")
			(hide yes)
			(effects
				(font
					(size 1 1)
					(thickness 0.15)
				)
				(justify mirror)
			)
		)
		(property "Voltage" "50V"
			(at -8.98 311.48 0)
			(layer "B.Fab")
			(hide yes)
			(effects
				(font
					(size 1 1)
					(thickness 0.15)
				)
				(justify mirror)
			)
		)
		(sheetname "2xSFP+")
		(sheetfile "2xSFP+.kicad_sch")
		(attr smd)
		(fp_rect
			(start -0.925 0.47)
			(end 0.925 -0.47)
			(stroke
				(width 0.05)
				(type default)
			)
			(fill no)
			(layer "B.CrtYd")
		)
		(fp_line
			(start -0.494 0.25)
			(end -0.494 -0.248)
			(stroke
				(width 0.15)
				(type solid)
			)
			(layer "B.Fab")
		)
		(fp_line
			(start 0.504 0.25)
			(end -0.494 0.25)
			(stroke
				(width 0.15)
				(type solid)
			)
			(layer "B.Fab")
		)
		(fp_line
			(start -0.494 -0.248)
			(end 0.504 -0.248)
			(stroke
				(width 0.15)
				(type solid)
			)
			(layer "B.Fab")
		)
		(fp_line
			(start 0.504 -0.248)
			(end 0.504 0.25)
			(stroke
				(width 0.15)
				(type solid)
			)
			(layer "B.Fab")
		)
		(pad "1" smd roundrect
			(at -0.48 0 270)
			(size 0.59 0.64)
			(layers "B.Cu" "B.Mask" "B.Paste")
			(roundrect_rratio 0.25)
			(net 1 "GND")
			(pintype "passive")
			(teardrops
				(best_length_ratio 0.2)
				(max_length 1)
				(best_width_ratio 0.9)
				(max_width 2)
				(curved_edges yes)
				(filter_ratio 0.9)
				(enabled yes)
				(allow_two_segments yes)
				(prefer_zone_connections yes)
			)
		)
		(pad "2" smd roundrect
			(at 0.48 0 270)
			(size 0.59 0.64)
			(layers "B.Cu" "B.Mask" "B.Paste")
			(roundrect_rratio 0.25)
			(net 2 "+3V3")
			(pintype "passive")
			(teardrops
				(best_length_ratio 0.2)
				(max_length 1)
				(best_width_ratio 0.9)
				(max_width 2)
				(curved_edges yes)
				(filter_ratio 0.9)
				(enabled yes)
				(allow_two_segments yes)
				(prefer_zone_connections yes)
			)
		)
	)
	(footprint "antmicro-footprints:C_0402_1005Metric"
		(layer "B.Cu")
		(at 132.29 136.36 -90)
		(descr "Capacitor SMD 0402")
		(tags "capacitor SMD 0402")
		(property "Reference" "C186"
			(at -1.25 0.54 90)
			(layer "B.SilkS")
			(effects
				(font
					(size 0.7 0.7)
					(thickness 0.15)
				)
				(justify left bottom mirror)
			)
		)
		(property "Value" "C_100n_0402"
			(at -1.022927 -2.155213 90)
			(layer "B.Fab")
			(effects
				(font
					(size 0.7 0.7)
					(thickness 0.15)
				)
				(justify left bottom mirror)
			)
		)
		(property "Datasheet" "https://www.murata.com/products/productdetail?partno=GRM155R61H104KE14%23"
			(at 0 0 270)
			(layer "F.Fab")
			(hide yes)
			(effects
				(font
					(size 1.27 1.27)
					(thickness 0.15)
				)
			)
		)
		(property "Author" "Antmicro"
			(at -4.07 268.65 0)
			(layer "B.Fab")
			(hide yes)
			(effects
				(font
					(size 1 1)
					(thickness 0.15)
				)
				(justify mirror)
			)
		)
		(property "Dielectric" "X5R"
			(at -4.07 268.65 0)
			(layer "B.Fab")
			(hide yes)
			(effects
				(font
					(size 1 1)
					(thickness 0.15)
				)
				(justify mirror)
			)
		)
		(property "License" "Apache-2.0"
			(at -4.07 268.65 0)
			(layer "B.Fab")
			(hide yes)
			(effects
				(font
					(size 1 1)
					(thickness 0.15)
				)
				(justify mirror)
			)
		)
		(property "MPN" "GRM155R61H104KE14D"
			(at -4.07 268.65 0)
			(layer "B.Fab")
			(hide yes)
			(effects
				(font
					(size 1 1)
					(thickness 0.15)
				)
				(justify mirror)
			)
		)
		(property "Manufacturer" "Murata"
			(at -4.07 268.65 0)
			(layer "B.Fab")
			(hide yes)
			(effects
				(font
					(size 1 1)
					(thickness 0.15)
				)
				(justify mirror)
			)
		)
		(property "Public" "False"
			(at -4.07 268.65 0)
			(layer "B.Fab")
			(hide yes)
			(effects
				(font
					(size 1 1)
					(thickness 0.15)
				)
				(justify mirror)
			)
		)
		(property "Val" "100n"
			(at -4.07 268.65 0)
			(layer "B.Fab")
			(hide yes)
			(effects
				(font
					(size 1 1)
					(thickness 0.15)
				)
				(justify mirror)
			)
		)
		(property "Voltage" "50V"
			(at -4.07 268.65 0)
			(layer "B.Fab")
			(hide yes)
			(effects
				(font
					(size 1 1)
					(thickness 0.15)
				)
				(justify mirror)
			)
		)
		(sheetname "KR to SFI #2")
		(sheetfile "kr_sfi.kicad_sch")
		(attr smd)
		(fp_rect
			(start -0.925 0.47)
			(end 0.925 -0.47)
			(stroke
				(width 0.05)
				(type default)
			)
			(fill no)
			(layer "B.CrtYd")
		)
		(fp_line
			(start -0.494 0.25)
			(end -0.494 -0.248)
			(stroke
				(width 0.15)
				(type solid)
			)
			(layer "B.Fab")
		)
		(fp_line
			(start 0.504 0.25)
			(end -0.494 0.25)
			(stroke
				(width 0.15)
				(type solid)
			)
			(layer "B.Fab")
		)
		(fp_line
			(start -0.494 -0.248)
			(end 0.504 -0.248)
			(stroke
				(width 0.15)
				(type solid)
			)
			(layer "B.Fab")
		)
		(fp_line
			(start 0.504 -0.248)
			(end 0.504 0.25)
			(stroke
				(width 0.15)
				(type solid)
			)
			(layer "B.Fab")
		)
		(pad "1" smd roundrect
			(at -0.48 0 270)
			(size 0.59 0.64)
			(layers "B.Cu" "B.Mask" "B.Paste")
			(roundrect_rratio 0.25)
			(net 1 "GND")
			(pintype "passive")
			(teardrops
				(best_length_ratio 0.2)
				(max_length 1)
				(best_width_ratio 0.9)
				(max_width 2)
				(curved_edges yes)
				(filter_ratio 0.9)
				(enabled yes)
				(allow_two_segments yes)
				(prefer_zone_connections yes)
			)
		)
		(pad "2" smd roundrect
			(at 0.48 0 270)
			(size 0.59 0.64)
			(layers "B.Cu" "B.Mask" "B.Paste")
			(roundrect_rratio 0.25)
			(net 74 "+1V0")
			(pintype "passive")
			(teardrops
				(best_length_ratio 0.2)
				(max_length 1)
				(best_width_ratio 0.9)
				(max_width 2)
				(curved_edges yes)
				(filter_ratio 0.9)
				(enabled yes)
				(allow_two_segments yes)
				(prefer_zone_connections yes)
			)
		)
	)
	(footprint "antmicro-footprints:R_0402_1005Metric"
		(layer "B.Cu")
		(at 137.05 169.16 -90)
		(descr "Resistor SMD 0402")
		(tags "resistor SMD 0402")
		(property "Reference" "R60"
			(at -3.9 13.5 90)
			(layer "B.SilkS")
			(effects
				(font
					(size 0.7 0.7)
					(thickness 0.15)
				)
				(justify left bottom mirror)
			)
		)
		(property "Value" "R_0R_0402"
			(at -1.011843 -1.772047 90)
			(layer "B.Fab")
			(effects
				(font
					(size 0.7 0.7)
					(thickness 0.15)
				)
				(justify left bottom mirror)
			)
		)
		(property "Datasheet" "https://industrial.panasonic.com/cdbs/www-data/pdf/RDA0000/AOA0000C301.pdf"
			(at 0 0 270)
			(layer "F.Fab")
			(hide yes)
			(effects
				(font
					(size 1.27 1.27)
					(thickness 0.15)
				)
			)
		)
		(property "Author" "Antmicro"
			(at -32.11 306.21 0)
			(layer "B.Fab")
			(hide yes)
			(effects
				(font
					(size 1 1)
					(thickness 0.15)
				)
				(justify mirror)
			)
		)
		(property "Current" "1A"
			(at -32.11 306.21 0)
			(layer "B.Fab")
			(hide yes)
			(effects
				(font
					(size 1 1)
					(thickness 0.15)
				)
				(justify mirror)
			)
		)
		(property "License" "Apache-2.0"
			(at -32.11 306.21 0)
			(layer "B.Fab")
			(hide yes)
			(effects
				(font
					(size 1 1)
					(thickness 0.15)
				)
				(justify mirror)
			)
		)
		(property "MPN" "ERJ2GE0R00X"
			(at -32.11 306.21 0)
			(layer "B.Fab")
			(hide yes)
			(effects
				(font
					(size 1 1)
					(thickness 0.15)
				)
				(justify mirror)
			)
		)
		(property "Manufacturer" "Panasonic"
			(at -32.11 306.21 0)
			(layer "B.Fab")
			(hide yes)
			(effects
				(font
					(size 1 1)
					(thickness 0.15)
				)
				(justify mirror)
			)
		)
		(property "Public" "False"
			(at -32.11 306.21 0)
			(layer "B.Fab")
			(hide yes)
			(effects
				(font
					(size 1 1)
					(thickness 0.15)
				)
				(justify mirror)
			)
		)
		(property "Tolerance" ""
			(at -32.11 306.21 0)
			(layer "B.Fab")
			(hide yes)
			(effects
				(font
					(size 1 1)
					(thickness 0.15)
				)
				(justify mirror)
			)
		)
		(property "Val" "0R"
			(at -32.11 306.21 0)
			(layer "B.Fab")
			(hide yes)
			(effects
				(font
					(size 1 1)
					(thickness 0.15)
				)
				(justify mirror)
			)
		)
		(sheetname "2xSFP+")
		(sheetfile "2xSFP+.kicad_sch")
		(attr smd)
		(fp_rect
			(start -0.925 0.47)
			(end 0.925 -0.47)
			(stroke
				(width 0.05)
				(type default)
			)
			(fill no)
			(layer "B.CrtYd")
		)
		(fp_rect
			(start -0.5 0.25)
			(end 0.5 -0.25)
			(stroke
				(width 0.15)
				(type solid)
			)
			(fill no)
			(layer "B.Fab")
		)
		(pad "1" smd roundrect
			(at -0.48 0 270)
			(size 0.59 0.64)
			(layers "B.Cu" "B.Mask" "B.Paste")
			(roundrect_rratio 0.25)
			(net 897 "Net-(J2B-RS1)")
			(pintype "passive")
			(teardrops
				(best_length_ratio 0.2)
				(max_length 1)
				(best_width_ratio 0.9)
				(max_width 2)
				(curved_edges yes)
				(filter_ratio 0.9)
				(enabled yes)
				(allow_two_segments yes)
				(prefer_zone_connections yes)
			)
		)
		(pad "2" smd roundrect
			(at 0.48 0 270)
			(size 0.59 0.64)
			(layers "B.Cu" "B.Mask" "B.Paste")
			(roundrect_rratio 0.25)
			(net 1 "GND")
			(pintype "passive")
			(teardrops
				(best_length_ratio 0.2)
				(max_length 1)
				(best_width_ratio 0.9)
				(max_width 2)
				(curved_edges yes)
				(filter_ratio 0.9)
				(enabled yes)
				(allow_two_segments yes)
				(prefer_zone_connections yes)
			)
		)
	)
	(footprint "antmicro-footprints:R_0402_1005Metric"
		(layer "B.Cu")
		(at 123.4 111.81 180)
		(descr "Resistor SMD 0402")
		(tags "resistor SMD 0402")
		(property "Reference" "R5"
			(at -2.35 -0.45 0)
			(layer "B.SilkS")
			(effects
				(font
					(size 0.7 0.7)
					(thickness 0.15)
				)
				(justify left bottom mirror)
			)
		)
		(property "Value" "R_0R_0402"
			(at -1.011843 -1.772047 0)
			(layer "B.Fab")
			(effects
				(font
					(size 0.7 0.7)
					(thickness 0.15)
				)
				(justify left bottom mirror)
			)
		)
		(property "Datasheet" "https://industrial.panasonic.com/cdbs/www-data/pdf/RDA0000/AOA0000C301.pdf"
			(at 0 0 180)
			(layer "F.Fab")
			(hide yes)
			(effects
				(font
					(size 1.27 1.27)
					(thickness 0.15)
				)
			)
		)
		(property "Author" "Antmicro"
			(at 246.8 223.62 0)
			(layer "B.Fab")
			(hide yes)
			(effects
				(font
					(size 1 1)
					(thickness 0.15)
				)
				(justify mirror)
			)
		)
		(property "Current" "1A"
			(at 246.8 223.62 0)
			(layer "B.Fab")
			(hide yes)
			(effects
				(font
					(size 1 1)
					(thickness 0.15)
				)
				(justify mirror)
			)
		)
		(property "License" "Apache-2.0"
			(at 246.8 223.62 0)
			(layer "B.Fab")
			(hide yes)
			(effects
				(font
					(size 1 1)
					(thickness 0.15)
				)
				(justify mirror)
			)
		)
		(property "MPN" "ERJ2GE0R00X"
			(at 246.8 223.62 0)
			(layer "B.Fab")
			(hide yes)
			(effects
				(font
					(size 1 1)
					(thickness 0.15)
				)
				(justify mirror)
			)
		)
		(property "Manufacturer" "Panasonic"
			(at 246.8 223.62 0)
			(layer "B.Fab")
			(hide yes)
			(effects
				(font
					(size 1 1)
					(thickness 0.15)
				)
				(justify mirror)
			)
		)
		(property "Public" "False"
			(at 246.8 223.62 0)
			(layer "B.Fab")
			(hide yes)
			(effects
				(font
					(size 1 1)
					(thickness 0.15)
				)
				(justify mirror)
			)
		)
		(property "Tolerance" ""
			(at 246.8 223.62 0)
			(layer "B.Fab")
			(hide yes)
			(effects
				(font
					(size 1 1)
					(thickness 0.15)
				)
				(justify mirror)
			)
		)
		(property "Val" "0R"
			(at 246.8 223.62 0)
			(layer "B.Fab")
			(hide yes)
			(effects
				(font
					(size 1 1)
					(thickness 0.15)
				)
				(justify mirror)
			)
		)
		(sheetname "2xUSB3.0+RJ45")
		(sheetfile "usb3+rj45.kicad_sch")
		(attr smd)
		(fp_rect
			(start -0.925 0.47)
			(end 0.925 -0.47)
			(stroke
				(width 0.05)
				(type default)
			)
			(fill no)
			(layer "B.CrtYd")
		)
		(fp_rect
			(start -0.5 0.25)
			(end 0.5 -0.25)
			(stroke
				(width 0.15)
				(type solid)
			)
			(fill no)
			(layer "B.Fab")
		)
		(pad "1" smd roundrect
			(at -0.48 0 180)
			(size 0.59 0.64)
			(layers "B.Cu" "B.Mask" "B.Paste")
			(roundrect_rratio 0.25)
			(net 288 "/2xUSB3.0+RJ45/~{GBE0_LINK_1000}")
			(pintype "passive")
			(teardrops
				(best_length_ratio 0.2)
				(max_length 1)
				(best_width_ratio 0.9)
				(max_width 2)
				(curved_edges yes)
				(filter_ratio 0.9)
				(enabled yes)
				(allow_two_segments yes)
				(prefer_zone_connections yes)
			)
		)
		(pad "2" smd roundrect
			(at 0.48 0 180)
			(size 0.59 0.64)
			(layers "B.Cu" "B.Mask" "B.Paste")
			(roundrect_rratio 0.25)
			(net 157 "Net-(J1A-LED_D4)")
			(pintype "passive")
			(teardrops
				(best_length_ratio 0.2)
				(max_length 1)
				(best_width_ratio 0.9)
				(max_width 2)
				(curved_edges yes)
				(filter_ratio 0.9)
				(enabled yes)
				(allow_two_segments yes)
				(prefer_zone_connections yes)
			)
		)
	)
	(footprint "antmicro-footprints:C_0402_1005Metric"
		(layer "B.Cu")
		(at 136.79 133.86 180)
		(descr "Capacitor SMD 0402")
		(tags "capacitor SMD 0402")
		(property "Reference" "C185"
			(at -2.36 -2.65 135)
			(layer "B.SilkS")
			(effects
				(font
					(size 0.7 0.7)
					(thickness 0.15)
				)
				(justify left bottom mirror)
			)
		)
		(property "Value" "C_100n_0402"
			(at -1.022927 -2.155213 0)
			(layer "B.Fab")
			(effects
				(font
					(size 0.7 0.7)
					(thickness 0.15)
				)
				(justify left bottom mirror)
			)
		)
		(property "Datasheet" "https://www.murata.com/products/productdetail?partno=GRM155R61H104KE14%23"
			(at 0 0 180)
			(layer "F.Fab")
			(hide yes)
			(effects
				(font
					(size 1.27 1.27)
					(thickness 0.15)
				)
			)
		)
		(property "Author" "Antmicro"
			(at 273.58 267.72 0)
			(layer "B.Fab")
			(hide yes)
			(effects
				(font
					(size 1 1)
					(thickness 0.15)
				)
				(justify mirror)
			)
		)
		(property "Dielectric" "X5R"
			(at 273.58 267.72 0)
			(layer "B.Fab")
			(hide yes)
			(effects
				(font
					(size 1 1)
					(thickness 0.15)
				)
				(justify mirror)
			)
		)
		(property "License" "Apache-2.0"
			(at 273.58 267.72 0)
			(layer "B.Fab")
			(hide yes)
			(effects
				(font
					(size 1 1)
					(thickness 0.15)
				)
				(justify mirror)
			)
		)
		(property "MPN" "GRM155R61H104KE14D"
			(at 273.58 267.72 0)
			(layer "B.Fab")
			(hide yes)
			(effects
				(font
					(size 1 1)
					(thickness 0.15)
				)
				(justify mirror)
			)
		)
		(property "Manufacturer" "Murata"
			(at 273.58 267.72 0)
			(layer "B.Fab")
			(hide yes)
			(effects
				(font
					(size 1 1)
					(thickness 0.15)
				)
				(justify mirror)
			)
		)
		(property "Public" "False"
			(at 273.58 267.72 0)
			(layer "B.Fab")
			(hide yes)
			(effects
				(font
					(size 1 1)
					(thickness 0.15)
				)
				(justify mirror)
			)
		)
		(property "Val" "100n"
			(at 273.58 267.72 0)
			(layer "B.Fab")
			(hide yes)
			(effects
				(font
					(size 1 1)
					(thickness 0.15)
				)
				(justify mirror)
			)
		)
		(property "Voltage" "50V"
			(at 273.58 267.72 0)
			(layer "B.Fab")
			(hide yes)
			(effects
				(font
					(size 1 1)
					(thickness 0.15)
				)
				(justify mirror)
			)
		)
		(sheetname "KR to SFI #2")
		(sheetfile "kr_sfi.kicad_sch")
		(attr smd)
		(fp_rect
			(start -0.925 0.47)
			(end 0.925 -0.47)
			(stroke
				(width 0.05)
				(type default)
			)
			(fill no)
			(layer "B.CrtYd")
		)
		(fp_line
			(start 0.504 0.25)
			(end -0.494 0.25)
			(stroke
				(width 0.15)
				(type solid)
			)
			(layer "B.Fab")
		)
		(fp_line
			(start 0.504 -0.248)
			(end 0.504 0.25)
			(stroke
				(width 0.15)
				(type solid)
			)
			(layer "B.Fab")
		)
		(fp_line
			(start -0.494 0.25)
			(end -0.494 -0.248)
			(stroke
				(width 0.15)
				(type solid)
			)
			(layer "B.Fab")
		)
		(fp_line
			(start -0.494 -0.248)
			(end 0.504 -0.248)
			(stroke
				(width 0.15)
				(type solid)
			)
			(layer "B.Fab")
		)
		(pad "1" smd roundrect
			(at -0.48 0 180)
			(size 0.59 0.64)
			(layers "B.Cu" "B.Mask" "B.Paste")
			(roundrect_rratio 0.25)
			(net 1 "GND")
			(pintype "passive")
			(teardrops
				(best_length_ratio 0.2)
				(max_length 1)
				(best_width_ratio 0.9)
				(max_width 2)
				(curved_edges yes)
				(filter_ratio 0.9)
				(enabled yes)
				(allow_two_segments yes)
				(prefer_zone_connections yes)
			)
		)
		(pad "2" smd roundrect
			(at 0.48 0 180)
			(size 0.59 0.64)
			(layers "B.Cu" "B.Mask" "B.Paste")
			(roundrect_rratio 0.25)
			(net 78 "+1V8")
			(pintype "passive")
			(teardrops
				(best_length_ratio 0.2)
				(max_length 1)
				(best_width_ratio 0.9)
				(max_width 2)
				(curved_edges yes)
				(filter_ratio 0.9)
				(enabled yes)
				(allow_two_segments yes)
				(prefer_zone_connections yes)
			)
		)
	)
	(footprint "antmicro-footprints:R_0402_1005Metric"
		(layer "B.Cu")
		(at 308.824999 121.96 -90)
		(descr "Resistor SMD 0402")
		(tags "resistor SMD 0402")
		(property "Reference" "R89"
			(at 0.8 -0.475001 90)
			(layer "B.SilkS")
			(effects
				(font
					(size 0.7 0.7)
					(thickness 0.15)
				)
				(justify left bottom mirror)
			)
		)
		(property "Value" "R_10k_0402"
			(at -1.011843 -1.772047 90)
			(layer "B.Fab")
			(effects
				(font
					(size 0.7 0.7)
					(thickness 0.15)
				)
				(justify left bottom mirror)
			)
		)
		(property "Datasheet" "https://www.bourns.com/docs/product-datasheets/cr.pdf"
			(at 0 0 270)
			(layer "F.Fab")
			(hide yes)
			(effects
				(font
					(size 1.27 1.27)
					(thickness 0.15)
				)
			)
		)
		(property "Author" "Antmicro"
			(at 186.864999 430.784999 0)
			(layer "B.Fab")
			(hide yes)
			(effects
				(font
					(size 1 1)
					(thickness 0.15)
				)
				(justify mirror)
			)
		)
		(property "License" "Apache-2.0"
			(at 186.864999 430.784999 0)
			(layer "B.Fab")
			(hide yes)
			(effects
				(font
					(size 1 1)
					(thickness 0.15)
				)
				(justify mirror)
			)
		)
		(property "MPN" "CR0402-FX-1002GLF"
			(at 186.864999 430.784999 0)
			(layer "B.Fab")
			(hide yes)
			(effects
				(font
					(size 1 1)
					(thickness 0.15)
				)
				(justify mirror)
			)
		)
		(property "Manufacturer" "Bourns"
			(at 186.864999 430.784999 0)
			(layer "B.Fab")
			(hide yes)
			(effects
				(font
					(size 1 1)
					(thickness 0.15)
				)
				(justify mirror)
			)
		)
		(property "Public" "False"
			(at 186.864999 430.784999 0)
			(layer "B.Fab")
			(hide yes)
			(effects
				(font
					(size 1 1)
					(thickness 0.15)
				)
				(justify mirror)
			)
		)
		(property "Tolerance" "1%"
			(at 186.864999 430.784999 0)
			(layer "B.Fab")
			(hide yes)
			(effects
				(font
					(size 1 1)
					(thickness 0.15)
				)
				(justify mirror)
			)
		)
		(property "Val" "10k"
			(at 186.864999 430.784999 0)
			(layer "B.Fab")
			(hide yes)
			(effects
				(font
					(size 1 1)
					(thickness 0.15)
				)
				(justify mirror)
			)
		)
		(sheetname "Power")
		(sheetfile "power.kicad_sch")
		(attr smd)
		(fp_rect
			(start -0.925 0.47)
			(end 0.925 -0.47)
			(stroke
				(width 0.05)
				(type default)
			)
			(fill no)
			(layer "B.CrtYd")
		)
		(fp_rect
			(start -0.5 0.25)
			(end 0.5 -0.25)
			(stroke
				(width 0.15)
				(type solid)
			)
			(fill no)
			(layer "B.Fab")
		)
		(pad "1" smd roundrect
			(at -0.48 0 270)
			(size 0.59 0.64)
			(layers "B.Cu" "B.Mask" "B.Paste")
			(roundrect_rratio 0.25)
			(net 1 "GND")
			(pintype "passive")
			(teardrops
				(best_length_ratio 0.2)
				(max_length 1)
				(best_width_ratio 0.9)
				(max_width 2)
				(curved_edges yes)
				(filter_ratio 0.9)
				(enabled yes)
				(allow_two_segments yes)
				(prefer_zone_connections yes)
			)
		)
		(pad "2" smd roundrect
			(at 0.48 0 270)
			(size 0.59 0.64)
			(layers "B.Cu" "B.Mask" "B.Paste")
			(roundrect_rratio 0.25)
			(net 575 "Net-(U18-MODE)")
			(pintype "passive")
			(teardrops
				(best_length_ratio 0.2)
				(max_length 1)
				(best_width_ratio 0.9)
				(max_width 2)
				(curved_edges yes)
				(filter_ratio 0.9)
				(enabled yes)
				(allow_two_segments yes)
				(prefer_zone_connections yes)
			)
		)
	)
	(footprint "antmicro-footprints:C_0402_1005Metric"
		(layer "B.Cu")
		(at 134.79 132.86)
		(descr "Capacitor SMD 0402")
		(tags "capacitor SMD 0402")
		(property "Reference" "C200"
			(at -1.84 1.35 0)
			(layer "B.SilkS")
			(effects
				(font
					(size 0.7 0.7)
					(thickness 0.15)
				)
				(justify right bottom mirror)
			)
		)
		(property "Value" "C_100n_0402"
			(at -1.022927 -2.155213 0)
			(layer "B.Fab")
			(effects
				(font
					(size 0.7 0.7)
					(thickness 0.15)
				)
				(justify right bottom mirror)
			)
		)
		(property "Datasheet" "https://www.murata.com/products/productdetail?partno=GRM155R61H104KE14%23"
			(at 0 0 0)
			(layer "F.Fab")
			(hide yes)
			(effects
				(font
					(size 1.27 1.27)
					(thickness 0.15)
				)
			)
		)
		(property "Author" "Antmicro"
			(at 0 0 0)
			(layer "B.Fab")
			(hide yes)
			(effects
				(font
					(size 1 1)
					(thickness 0.15)
				)
				(justify mirror)
			)
		)
		(property "Dielectric" "X5R"
			(at 0 0 0)
			(layer "B.Fab")
			(hide yes)
			(effects
				(font
					(size 1 1)
					(thickness 0.15)
				)
				(justify mirror)
			)
		)
		(property "License" "Apache-2.0"
			(at 0 0 0)
			(layer "B.Fab")
			(hide yes)
			(effects
				(font
					(size 1 1)
					(thickness 0.15)
				)
				(justify mirror)
			)
		)
		(property "MPN" "GRM155R61H104KE14D"
			(at 0 0 0)
			(layer "B.Fab")
			(hide yes)
			(effects
				(font
					(size 1 1)
					(thickness 0.15)
				)
				(justify mirror)
			)
		)
		(property "Manufacturer" "Murata"
			(at 0 0 0)
			(layer "B.Fab")
			(hide yes)
			(effects
				(font
					(size 1 1)
					(thickness 0.15)
				)
				(justify mirror)
			)
		)
		(property "Public" "False"
			(at 0 0 0)
			(layer "B.Fab")
			(hide yes)
			(effects
				(font
					(size 1 1)
					(thickness 0.15)
				)
				(justify mirror)
			)
		)
		(property "Val" "100n"
			(at 0 0 0)
			(layer "B.Fab")
			(hide yes)
			(effects
				(font
					(size 1 1)
					(thickness 0.15)
				)
				(justify mirror)
			)
		)
		(property "Voltage" "50V"
			(at 0 0 0)
			(layer "B.Fab")
			(hide yes)
			(effects
				(font
					(size 1 1)
					(thickness 0.15)
				)
				(justify mirror)
			)
		)
		(sheetname "KR to SFI #2")
		(sheetfile "kr_sfi.kicad_sch")
		(attr smd)
		(fp_rect
			(start -0.925 0.47)
			(end 0.925 -0.47)
			(stroke
				(width 0.05)
				(type default)
			)
			(fill no)
			(layer "B.CrtYd")
		)
		(fp_line
			(start -0.494 -0.248)
			(end 0.504 -0.248)
			(stroke
				(width 0.15)
				(type solid)
			)
			(layer "B.Fab")
		)
		(fp_line
			(start -0.494 0.25)
			(end -0.494 -0.248)
			(stroke
				(width 0.15)
				(type solid)
			)
			(layer "B.Fab")
		)
		(fp_line
			(start 0.504 -0.248)
			(end 0.504 0.25)
			(stroke
				(width 0.15)
				(type solid)
			)
			(layer "B.Fab")
		)
		(fp_line
			(start 0.504 0.25)
			(end -0.494 0.25)
			(stroke
				(width 0.15)
				(type solid)
			)
			(layer "B.Fab")
		)
		(pad "1" smd roundrect
			(at -0.48 0)
			(size 0.59 0.64)
			(layers "B.Cu" "B.Mask" "B.Paste")
			(roundrect_rratio 0.25)
			(net 1 "GND")
			(pintype "passive")
			(teardrops
				(best_length_ratio 0.2)
				(max_length 1)
				(best_width_ratio 0.9)
				(max_width 2)
				(curved_edges yes)
				(filter_ratio 0.9)
				(enabled yes)
				(allow_two_segments yes)
				(prefer_zone_connections yes)
			)
		)
		(pad "2" smd roundrect
			(at 0.48 0)
			(size 0.59 0.64)
			(layers "B.Cu" "B.Mask" "B.Paste")
			(roundrect_rratio 0.25)
			(net 74 "+1V0")
			(pintype "passive")
			(teardrops
				(best_length_ratio 0.2)
				(max_length 1)
				(best_width_ratio 0.9)
				(max_width 2)
				(curved_edges yes)
				(filter_ratio 0.9)
				(enabled yes)
				(allow_two_segments yes)
				(prefer_zone_connections yes)
			)
		)
	)
	(footprint "antmicro-footprints:TP_SMD_0.75mm"
		(layer "B.Cu")
		(at 175.15 163.8 180)
		(property "Reference" "TP28"
			(at -0.35 3.3 90)
			(layer "B.SilkS")
			(effects
				(font
					(size 0.7 0.7)
					(thickness 0.15)
				)
				(justify left bottom mirror)
			)
		)
		(property "Value" "TP_0.75mm_SMD"
			(at 3.225 -53.865 0)
			(layer "B.Fab")
			(hide yes)
			(effects
				(font
					(size 0.7 0.7)
					(thickness 0.15)
				)
				(justify left bottom mirror)
			)
		)
		(property "Author" "Antmicro"
			(at 459.7 308.02 0)
			(layer "B.Fab")
			(hide yes)
			(effects
				(font
					(size 1 1)
					(thickness 0.15)
				)
				(justify mirror)
			)
		)
		(property "License" "Apache-2.0"
			(at 459.7 308.02 0)
			(layer "B.Fab")
			(hide yes)
			(effects
				(font
					(size 1 1)
					(thickness 0.15)
				)
				(justify mirror)
			)
		)
		(property "MPN" ""
			(at 459.7 308.02 0)
			(layer "B.Fab")
			(hide yes)
			(effects
				(font
					(size 1 1)
					(thickness 0.15)
				)
				(justify mirror)
			)
		)
		(property "Manufacturer" ""
			(at 459.7 308.02 0)
			(layer "B.Fab")
			(hide yes)
			(effects
				(font
					(size 1 1)
					(thickness 0.15)
				)
				(justify mirror)
			)
		)
		(property "Public" "False"
			(at 459.7 308.02 0)
			(layer "B.Fab")
			(hide yes)
			(effects
				(font
					(size 1 1)
					(thickness 0.15)
				)
				(justify mirror)
			)
		)
		(sheetname "Com Express 7 MGMT")
		(sheetfile "com_express_7_mgmt.kicad_sch")
		(attr exclude_from_pos_files exclude_from_bom)
		(fp_circle
			(center 0 0)
			(end 0.475 0)
			(stroke
				(width 0.05)
				(type default)
			)
			(fill no)
			(layer "B.CrtYd")
		)
		(pad "1" smd circle
			(at 0 0 180)
			(size 0.75 0.75)
			(layers "B.Cu" "B.Mask")
			(net 348 "Net-(J12D-~{LPC_FRAME}{slash}~{ESPI_CS0})")
			(pinfunction "1")
			(pintype "passive")
			(teardrops
				(best_length_ratio 0.4)
				(max_length 1)
				(best_width_ratio 0.9)
				(max_width 2)
				(curved_edges yes)
				(filter_ratio 0.9)
				(enabled yes)
				(allow_two_segments yes)
				(prefer_zone_connections yes)
			)
		)
	)
	(footprint "antmicro-footprints:R_0402_1005Metric"
		(layer "B.Cu")
		(at 99.3 74.81)
		(descr "Resistor SMD 0402")
		(tags "resistor SMD 0402")
		(property "Reference" "R152"
			(at -3.65 0.4 0)
			(layer "B.SilkS")
			(effects
				(font
					(size 0.7 0.7)
					(thickness 0.15)
				)
				(justify right bottom mirror)
			)
		)
		(property "Value" "R_10k_0402"
			(at -1.011843 -1.772047 0)
			(layer "B.Fab")
			(effects
				(font
					(size 0.7 0.7)
					(thickness 0.15)
				)
				(justify right bottom mirror)
			)
		)
		(property "Datasheet" "https://www.bourns.com/docs/product-datasheets/cr.pdf"
			(at 0 0 0)
			(layer "F.Fab")
			(hide yes)
			(effects
				(font
					(size 1.27 1.27)
					(thickness 0.15)
				)
			)
		)
		(property "Description" "SMD Chip Resistor, 10 kohm, ± 1%, 62.5 mW, 0402 [1005 Metric], Thick Film, General Purpose"
			(at 0 0 0)
			(layer "F.Fab")
			(hide yes)
			(effects
				(font
					(size 1.27 1.27)
					(thickness 0.15)
				)
			)
		)
		(property "Author" "Antmicro"
			(at 0 0 0)
			(layer "B.Fab")
			(hide yes)
			(effects
				(font
					(size 1 1)
					(thickness 0.15)
				)
				(justify mirror)
			)
		)
		(property "License" "Apache-2.0"
			(at 0 0 0)
			(layer "B.Fab")
			(hide yes)
			(effects
				(font
					(size 1 1)
					(thickness 0.15)
				)
				(justify mirror)
			)
		)
		(property "MPN" "CR0402-FX-1002GLF"
			(at 0 0 0)
			(layer "B.Fab")
			(hide yes)
			(effects
				(font
					(size 1 1)
					(thickness 0.15)
				)
				(justify mirror)
			)
		)
		(property "Manufacturer" "Bourns"
			(at 0 0 0)
			(layer "B.Fab")
			(hide yes)
			(effects
				(font
					(size 1 1)
					(thickness 0.15)
				)
				(justify mirror)
			)
		)
		(property "Tolerance" "1%"
			(at 0 0 0)
			(layer "B.Fab")
			(hide yes)
			(effects
				(font
					(size 1 1)
					(thickness 0.15)
				)
				(justify mirror)
			)
		)
		(property "Val" "10k"
			(at 0 0 0)
			(layer "B.Fab")
			(hide yes)
			(effects
				(font
					(size 1 1)
					(thickness 0.15)
				)
				(justify mirror)
			)
		)
		(sheetname "Misc")
		(sheetfile "misc.kicad_sch")
		(attr smd)
		(fp_rect
			(start -0.925 0.47)
			(end 0.925 -0.47)
			(stroke
				(width 0.05)
				(type default)
			)
			(fill no)
			(layer "B.CrtYd")
		)
		(fp_rect
			(start -0.5 0.25)
			(end 0.5 -0.25)
			(stroke
				(width 0.15)
				(type solid)
			)
			(fill no)
			(layer "B.Fab")
		)
		(pad "1" smd roundrect
			(at -0.48 0)
			(size 0.59 0.64)
			(layers "B.Cu" "B.Mask" "B.Paste")
			(roundrect_rratio 0.25)
			(net 539 "/Misc/~{PWR_OK}")
			(pintype "passive")
			(teardrops
				(best_length_ratio 0.2)
				(max_length 1)
				(best_width_ratio 0.9)
				(max_width 2)
				(curved_edges yes)
				(filter_ratio 0.9)
				(enabled yes)
				(allow_two_segments yes)
				(prefer_zone_connections yes)
			)
		)
		(pad "2" smd roundrect
			(at 0.48 0)
			(size 0.59 0.64)
			(layers "B.Cu" "B.Mask" "B.Paste")
			(roundrect_rratio 0.25)
			(net 133 "Net-(D18-C_{G})")
			(pintype "passive")
			(teardrops
				(best_length_ratio 0.2)
				(max_length 1)
				(best_width_ratio 0.9)
				(max_width 2)
				(curved_edges yes)
				(filter_ratio 0.9)
				(enabled yes)
				(allow_two_segments yes)
				(prefer_zone_connections yes)
			)
		)
	)
	(footprint "antmicro-footprints:R_0402_1005Metric"
		(layer "B.Cu")
		(at 99.3 78.81)
		(descr "Resistor SMD 0402")
		(tags "resistor SMD 0402")
		(property "Reference" "R142"
			(at -3.65 0.4 0)
			(layer "B.SilkS")
			(effects
				(font
					(size 0.7 0.7)
					(thickness 0.15)
				)
				(justify right bottom mirror)
			)
		)
		(property "Value" "R_10k_0402"
			(at -1.011843 -1.772047 0)
			(layer "B.Fab")
			(effects
				(font
					(size 0.7 0.7)
					(thickness 0.15)
				)
				(justify right bottom mirror)
			)
		)
		(property "Datasheet" "https://www.bourns.com/docs/product-datasheets/cr.pdf"
			(at 0 0 0)
			(layer "F.Fab")
			(hide yes)
			(effects
				(font
					(size 1.27 1.27)
					(thickness 0.15)
				)
			)
		)
		(property "Description" "SMD Chip Resistor, 10 kohm, ± 1%, 62.5 mW, 0402 [1005 Metric], Thick Film, General Purpose"
			(at 0 0 0)
			(layer "F.Fab")
			(hide yes)
			(effects
				(font
					(size 1.27 1.27)
					(thickness 0.15)
				)
			)
		)
		(property "Author" "Antmicro"
			(at 0 0 0)
			(layer "B.Fab")
			(hide yes)
			(effects
				(font
					(size 1 1)
					(thickness 0.15)
				)
				(justify mirror)
			)
		)
		(property "License" "Apache-2.0"
			(at 0 0 0)
			(layer "B.Fab")
			(hide yes)
			(effects
				(font
					(size 1 1)
					(thickness 0.15)
				)
				(justify mirror)
			)
		)
		(property "MPN" "CR0402-FX-1002GLF"
			(at 0 0 0)
			(layer "B.Fab")
			(hide yes)
			(effects
				(font
					(size 1 1)
					(thickness 0.15)
				)
				(justify mirror)
			)
		)
		(property "Manufacturer" "Bourns"
			(at 0 0 0)
			(layer "B.Fab")
			(hide yes)
			(effects
				(font
					(size 1 1)
					(thickness 0.15)
				)
				(justify mirror)
			)
		)
		(property "Tolerance" "1%"
			(at 0 0 0)
			(layer "B.Fab")
			(hide yes)
			(effects
				(font
					(size 1 1)
					(thickness 0.15)
				)
				(justify mirror)
			)
		)
		(property "Val" "10k"
			(at 0 0 0)
			(layer "B.Fab")
			(hide yes)
			(effects
				(font
					(size 1 1)
					(thickness 0.15)
				)
				(justify mirror)
			)
		)
		(sheetname "Misc")
		(sheetfile "misc.kicad_sch")
		(attr smd)
		(fp_rect
			(start -0.925 0.47)
			(end 0.925 -0.47)
			(stroke
				(width 0.05)
				(type default)
			)
			(fill no)
			(layer "B.CrtYd")
		)
		(fp_rect
			(start -0.5 0.25)
			(end 0.5 -0.25)
			(stroke
				(width 0.15)
				(type solid)
			)
			(fill no)
			(layer "B.Fab")
		)
		(pad "1" smd roundrect
			(at -0.48 0)
			(size 0.59 0.64)
			(layers "B.Cu" "B.Mask" "B.Paste")
			(roundrect_rratio 0.25)
			(net 944 "/GPIO expander/GPIOEX2")
			(pintype "passive")
			(teardrops
				(best_length_ratio 0.2)
				(max_length 1)
				(best_width_ratio 0.9)
				(max_width 2)
				(curved_edges yes)
				(filter_ratio 0.9)
				(enabled yes)
				(allow_two_segments yes)
				(prefer_zone_connections yes)
			)
		)
		(pad "2" smd roundrect
			(at 0.48 0)
			(size 0.59 0.64)
			(layers "B.Cu" "B.Mask" "B.Paste")
			(roundrect_rratio 0.25)
			(net 129 "Net-(D17-C_{R})")
			(pintype "passive")
			(teardrops
				(best_length_ratio 0.2)
				(max_length 1)
				(best_width_ratio 0.9)
				(max_width 2)
				(curved_edges yes)
				(filter_ratio 0.9)
				(enabled yes)
				(allow_two_segments yes)
				(prefer_zone_connections yes)
			)
		)
	)
	(footprint "antmicro-footprints:C_0402_1005Metric"
		(layer "B.Cu")
		(at 150.45 141.36 90)
		(descr "Capacitor SMD 0402")
		(tags "capacitor SMD 0402")
		(property "Reference" "C161"
			(at -3.7 0.4 90)
			(layer "B.SilkS")
			(effects
				(font
					(size 0.7 0.7)
					(thickness 0.15)
				)
				(justify right bottom mirror)
			)
		)
		(property "Value" "C_100n_0402"
			(at -1.022927 -2.155213 90)
			(layer "B.Fab")
			(effects
				(font
					(size 0.7 0.7)
					(thickness 0.15)
				)
				(justify right bottom mirror)
			)
		)
		(property "Datasheet" "https://www.murata.com/products/productdetail?partno=GRM155R61H104KE14%23"
			(at 0 0 90)
			(layer "F.Fab")
			(hide yes)
			(effects
				(font
					(size 1.27 1.27)
					(thickness 0.15)
				)
			)
		)
		(property "Author" "Antmicro"
			(at 291.81 -9.09 0)
			(layer "B.Fab")
			(hide yes)
			(effects
				(font
					(size 1 1)
					(thickness 0.15)
				)
				(justify mirror)
			)
		)
		(property "Dielectric" "X5R"
			(at 291.81 -9.09 0)
			(layer "B.Fab")
			(hide yes)
			(effects
				(font
					(size 1 1)
					(thickness 0.15)
				)
				(justify mirror)
			)
		)
		(property "License" "Apache-2.0"
			(at 291.81 -9.09 0)
			(layer "B.Fab")
			(hide yes)
			(effects
				(font
					(size 1 1)
					(thickness 0.15)
				)
				(justify mirror)
			)
		)
		(property "MPN" "GRM155R61H104KE14D"
			(at 291.81 -9.09 0)
			(layer "B.Fab")
			(hide yes)
			(effects
				(font
					(size 1 1)
					(thickness 0.15)
				)
				(justify mirror)
			)
		)
		(property "Manufacturer" "Murata"
			(at 291.81 -9.09 0)
			(layer "B.Fab")
			(hide yes)
			(effects
				(font
					(size 1 1)
					(thickness 0.15)
				)
				(justify mirror)
			)
		)
		(property "Public" "False"
			(at 291.81 -9.09 0)
			(layer "B.Fab")
			(hide yes)
			(effects
				(font
					(size 1 1)
					(thickness 0.15)
				)
				(justify mirror)
			)
		)
		(property "Val" "100n"
			(at 291.81 -9.09 0)
			(layer "B.Fab")
			(hide yes)
			(effects
				(font
					(size 1 1)
					(thickness 0.15)
				)
				(justify mirror)
			)
		)
		(property "Voltage" "50V"
			(at 291.81 -9.09 0)
			(layer "B.Fab")
			(hide yes)
			(effects
				(font
					(size 1 1)
					(thickness 0.15)
				)
				(justify mirror)
			)
		)
		(sheetname "KR to SFI #1")
		(sheetfile "kr_sfi.kicad_sch")
		(attr smd)
		(fp_rect
			(start -0.925 0.47)
			(end 0.925 -0.47)
			(stroke
				(width 0.05)
				(type default)
			)
			(fill no)
			(layer "B.CrtYd")
		)
		(fp_line
			(start 0.504 -0.248)
			(end 0.504 0.25)
			(stroke
				(width 0.15)
				(type solid)
			)
			(layer "B.Fab")
		)
		(fp_line
			(start -0.494 -0.248)
			(end 0.504 -0.248)
			(stroke
				(width 0.15)
				(type solid)
			)
			(layer "B.Fab")
		)
		(fp_line
			(start 0.504 0.25)
			(end -0.494 0.25)
			(stroke
				(width 0.15)
				(type solid)
			)
			(layer "B.Fab")
		)
		(fp_line
			(start -0.494 0.25)
			(end -0.494 -0.248)
			(stroke
				(width 0.15)
				(type solid)
			)
			(layer "B.Fab")
		)
		(pad "1" smd roundrect
			(at -0.48 0 90)
			(size 0.59 0.64)
			(layers "B.Cu" "B.Mask" "B.Paste")
			(roundrect_rratio 0.25)
			(net 1 "GND")
			(pintype "passive")
			(teardrops
				(best_length_ratio 0.2)
				(max_length 1)
				(best_width_ratio 0.9)
				(max_width 2)
				(curved_edges yes)
				(filter_ratio 0.9)
				(enabled yes)
				(allow_two_segments yes)
				(prefer_zone_connections yes)
			)
		)
		(pad "2" smd roundrect
			(at 0.48 0 90)
			(size 0.59 0.64)
			(layers "B.Cu" "B.Mask" "B.Paste")
			(roundrect_rratio 0.25)
			(net 74 "+1V0")
			(pintype "passive")
			(teardrops
				(best_length_ratio 0.2)
				(max_length 1)
				(best_width_ratio 0.9)
				(max_width 2)
				(curved_edges yes)
				(filter_ratio 0.9)
				(enabled yes)
				(allow_two_segments yes)
				(prefer_zone_connections yes)
			)
		)
	)
	(footprint "antmicro-footprints:R_0402_1005Metric"
		(layer "B.Cu")
		(at 144.25 138.06)
		(descr "Resistor SMD 0402")
		(tags "resistor SMD 0402")
		(property "Reference" "R263"
			(at -1.45 5.4 0)
			(layer "B.SilkS")
			(effects
				(font
					(size 0.7 0.7)
					(thickness 0.15)
				)
				(justify right bottom mirror)
			)
		)
		(property "Value" "R_10k_0402"
			(at -1.011843 -1.772047 0)
			(layer "B.Fab")
			(effects
				(font
					(size 0.7 0.7)
					(thickness 0.15)
				)
				(justify right bottom mirror)
			)
		)
		(property "Datasheet" "https://www.bourns.com/docs/product-datasheets/cr.pdf"
			(at 0 0 0)
			(layer "F.Fab")
			(hide yes)
			(effects
				(font
					(size 1.27 1.27)
					(thickness 0.15)
				)
			)
		)
		(property "Author" "Antmicro"
			(at 0 0 0)
			(layer "B.Fab")
			(hide yes)
			(effects
				(font
					(size 1 1)
					(thickness 0.15)
				)
				(justify mirror)
			)
		)
		(property "License" "Apache-2.0"
			(at 0 0 0)
			(layer "B.Fab")
			(hide yes)
			(effects
				(font
					(size 1 1)
					(thickness 0.15)
				)
				(justify mirror)
			)
		)
		(property "MPN" "CR0402-FX-1002GLF"
			(at 0 0 0)
			(layer "B.Fab")
			(hide yes)
			(effects
				(font
					(size 1 1)
					(thickness 0.15)
				)
				(justify mirror)
			)
		)
		(property "Manufacturer" "Bourns"
			(at 0 0 0)
			(layer "B.Fab")
			(hide yes)
			(effects
				(font
					(size 1 1)
					(thickness 0.15)
				)
				(justify mirror)
			)
		)
		(property "Public" "False"
			(at 0 0 0)
			(layer "B.Fab")
			(hide yes)
			(effects
				(font
					(size 1 1)
					(thickness 0.15)
				)
				(justify mirror)
			)
		)
		(property "Tolerance" "1%"
			(at 0 0 0)
			(layer "B.Fab")
			(hide yes)
			(effects
				(font
					(size 1 1)
					(thickness 0.15)
				)
				(justify mirror)
			)
		)
		(property "Val" "10k"
			(at 0 0 0)
			(layer "B.Fab")
			(hide yes)
			(effects
				(font
					(size 1 1)
					(thickness 0.15)
				)
				(justify mirror)
			)
		)
		(sheetname "KR to SFI #1")
		(sheetfile "kr_sfi.kicad_sch")
		(attr smd)
		(fp_rect
			(start -0.925 0.47)
			(end 0.925 -0.47)
			(stroke
				(width 0.05)
				(type default)
			)
			(fill no)
			(layer "B.CrtYd")
		)
		(fp_rect
			(start -0.5 0.25)
			(end 0.5 -0.25)
			(stroke
				(width 0.15)
				(type solid)
			)
			(fill no)
			(layer "B.Fab")
		)
		(pad "1" smd roundrect
			(at -0.48 0)
			(size 0.59 0.64)
			(layers "B.Cu" "B.Mask" "B.Paste")
			(roundrect_rratio 0.25)
			(net 1 "GND")
			(pintype "passive")
			(teardrops
				(best_length_ratio 0.2)
				(max_length 1)
				(best_width_ratio 0.9)
				(max_width 2)
				(curved_edges yes)
				(filter_ratio 0.9)
				(enabled yes)
				(allow_two_segments yes)
				(prefer_zone_connections yes)
			)
		)
		(pad "2" smd roundrect
			(at 0.48 0)
			(size 0.59 0.64)
			(layers "B.Cu" "B.Mask" "B.Paste")
			(roundrect_rratio 0.25)
			(net 656 "Net-(U43C-PRTAD1)")
			(pintype "passive")
			(teardrops
				(best_length_ratio 0.2)
				(max_length 1)
				(best_width_ratio 0.9)
				(max_width 2)
				(curved_edges yes)
				(filter_ratio 0.9)
				(enabled yes)
				(allow_two_segments yes)
				(prefer_zone_connections yes)
			)
		)
	)
	(footprint "antmicro-footprints:Bus_M.2_Socket_Key_M_Amphenol_MDT180M03001"
		(layer "B.Cu")
		(at 180.15 102.11 -90)
		(property "Reference" "J5"
			(at -12.26 5 90)
			(layer "B.SilkS")
			(effects
				(font
					(size 0.7 0.7)
					(thickness 0.15)
				)
				(justify left bottom mirror)
			)
		)
		(property "Value" "Bus_M.2_MDT180M03001"
			(at 0 -6.3 90)
			(layer "B.Fab")
			(hide yes)
			(effects
				(font
					(size 0.7 0.7)
					(thickness 0.15)
				)
				(justify left bottom mirror)
			)
		)
		(property "Datasheet" "https://cdn.amphenol-cs.com/media/wysiwyg/files/drawing/mdt180xxx001.pdf"
			(at 0 0 90)
			(layer "B.Fab")
			(hide yes)
			(effects
				(font
					(size 1.27 1.27)
					(thickness 0.15)
				)
				(justify mirror)
			)
		)
		(property "Manufacturer" "Amphenol"
			(at 0 0 270)
			(unlocked yes)
			(layer "B.Fab")
			(hide yes)
			(effects
				(font
					(size 1 1)
					(thickness 0.15)
				)
				(justify mirror)
			)
		)
		(property "MPN" "MDT180M03001"
			(at 0 0 270)
			(unlocked yes)
			(layer "B.Fab")
			(hide yes)
			(effects
				(font
					(size 1 1)
					(thickness 0.15)
				)
				(justify mirror)
			)
		)
		(property "Author" "Antmicro"
			(at 0 0 270)
			(unlocked yes)
			(layer "B.Fab")
			(hide yes)
			(effects
				(font
					(size 1 1)
					(thickness 0.15)
				)
				(justify mirror)
			)
		)
		(property "License" "Apache-2.0"
			(at 0 0 270)
			(unlocked yes)
			(layer "B.Fab")
			(hide yes)
			(effects
				(font
					(size 1 1)
					(thickness 0.15)
				)
				(justify mirror)
			)
		)
		(sheetname "M.2 key M #1")
		(sheetfile "m2keym_low.kicad_sch")
		(attr smd)
		(fp_line
			(start -12.05 4.7)
			(end -10.2 4.7)
			(stroke
				(width 0.15)
				(type solid)
			)
			(layer "B.SilkS")
		)
		(fp_line
			(start -10.2 4.7)
			(end -10.2 3)
			(stroke
				(width 0.15)
				(type solid)
			)
			(layer "B.SilkS")
		)
		(fp_line
			(start 10.2 4.7)
			(end 12.05 4.7)
			(stroke
				(width 0.15)
				(type solid)
			)
			(layer "B.SilkS")
		)
		(fp_line
			(start 12.05 4.7)
			(end 12.05 3.3)
			(stroke
				(width 0.15)
				(type solid)
			)
			(layer "B.SilkS")
		)
		(fp_line
			(start 10.2 3.3)
			(end 10.2 4.7)
			(stroke
				(width 0.15)
				(type solid)
			)
			(layer "B.SilkS")
		)
		(fp_line
			(start -10.2 1.8)
			(end -10.2 0.72)
			(stroke
				(width 0.15)
				(type solid)
			)
			(layer "B.SilkS")
		)
		(fp_line
			(start 12.05 1.5)
			(end 12.05 -0.882)
			(stroke
				(width 0.15)
				(type solid)
			)
			(layer "B.SilkS")
		)
		(fp_line
			(start -9.464 0.72)
			(end -10.2 0.72)
			(stroke
				(width 0.15)
				(type solid)
			)
			(layer "B.SilkS")
		)
		(fp_line
			(start 9.464 0.72)
			(end 10.2 0.72)
			(stroke
				(width 0.15)
				(type solid)
			)
			(layer "B.SilkS")
		)
		(fp_line
			(start 10.2 0.72)
			(end 10.2 1.5)
			(stroke
				(width 0.15)
				(type solid)
			)
			(layer "B.SilkS")
		)
		(fp_line
			(start -12.05 -0.882)
			(end -12.05 4.7)
			(stroke
				(width 0.15)
				(type solid)
			)
			(layer "B.SilkS")
		)
		(fp_line
			(start -12.05 -4.8)
			(end -12.05 -4.258)
			(stroke
				(width 0.15)
				(type solid)
			)
			(layer "B.SilkS")
		)
		(fp_line
			(start 12.05 -4.8)
			(end 12.05 -4.258)
			(stroke
				(width 0.15)
				(type solid)
			)
			(layer "B.SilkS")
		)
		(fp_circle
			(center -9.8 4.85)
			(end -9.7 4.85)
			(stroke
				(width 0.15)
				(type solid)
			)
			(fill yes)
			(layer "B.SilkS")
		)
		(fp_rect
			(start -12.38 5.1)
			(end 12.38 -5)
			(stroke
				(width 0.05)
				(type solid)
			)
			(fill no)
			(layer "B.CrtYd")
		)
		(fp_line
			(start -12.05 4.7)
			(end -10.2 4.7)
			(stroke
				(width 0.15)
				(type solid)
			)
			(layer "B.Fab")
		)
		(fp_line
			(start -10.2 4.7)
			(end -10.2 0.72)
			(stroke
				(width 0.15)
				(type solid)
			)
			(layer "B.Fab")
		)
		(fp_line
			(start 10.2 4.7)
			(end 12.05 4.7)
			(stroke
				(width 0.15)
				(type solid)
			)
			(layer "B.Fab")
		)
		(fp_line
			(start 12.05 4.7)
			(end 12.05 -4.8)
			(stroke
				(width 0.15)
				(type solid)
			)
			(layer "B.Fab")
		)
		(fp_line
			(start -10.2 0.72)
			(end 10.2 0.72)
			(stroke
				(width 0.15)
				(type solid)
			)
			(layer "B.Fab")
		)
		(fp_line
			(start 10.2 0.72)
			(end 10.2 4.7)
			(stroke
				(width 0.15)
				(type solid)
			)
			(layer "B.Fab")
		)
		(fp_line
			(start -12.05 -4.8)
			(end -12.05 4.7)
			(stroke
				(width 0.15)
				(type solid)
			)
			(layer "B.Fab")
		)
		(fp_line
			(start 12.05 -4.8)
			(end -12.05 -4.8)
			(stroke
				(width 0.15)
				(type solid)
			)
			(layer "B.Fab")
		)
		(pad "" np_thru_hole circle
			(at -11 2.4 270)
			(size 1.15 1.15)
			(drill 1.15)
			(layers "*.Cu" "*.Mask")
		)
		(pad "" np_thru_hole circle
			(at 11 2.4 270)
			(size 1.65 1.65)
			(drill 1.65)
			(layers "*.Cu" "*.Mask")
		)
		(pad "1" smd rect
			(at -9.25 3.95 270)
			(size 0.3 1.5)
			(layers "B.Cu" "B.Mask" "B.Paste")
			(net 1 "GND")
			(pinfunction "GND")
			(pintype "power_in")
			(teardrops
				(best_length_ratio 0.2)
				(max_length 1)
				(best_width_ratio 0.9)
				(max_width 2)
				(curved_edges yes)
				(filter_ratio 0.9)
				(enabled yes)
				(allow_two_segments yes)
				(prefer_zone_connections yes)
			)
		)
		(pad "2" smd rect
			(at -9 1.31 270)
			(size 0.3 1.5)
			(layers "B.Cu" "B.Mask" "B.Paste")
			(net 969 "/M.2 key M #1/M2_3V3")
			(pinfunction "3V3")
			(pintype "passive")
			(teardrops
				(best_length_ratio 0.2)
				(max_length 1)
				(best_width_ratio 0.9)
				(max_width 2)
				(curved_edges yes)
				(filter_ratio 0.9)
				(enabled yes)
				(allow_two_segments yes)
				(prefer_zone_connections yes)
			)
		)
		(pad "3" smd rect
			(at -8.75 3.95 270)
			(size 0.3 1.5)
			(layers "B.Cu" "B.Mask" "B.Paste")
			(net 1 "GND")
			(pinfunction "GND")
			(pintype "passive")
			(teardrops
				(best_length_ratio 0.2)
				(max_length 1)
				(best_width_ratio 0.9)
				(max_width 2)
				(curved_edges yes)
				(filter_ratio 0.9)
				(enabled yes)
				(allow_two_segments yes)
				(prefer_zone_connections yes)
			)
		)
		(pad "4" smd rect
			(at -8.5 1.31 270)
			(size 0.3 1.5)
			(layers "B.Cu" "B.Mask" "B.Paste")
			(net 969 "/M.2 key M #1/M2_3V3")
			(pinfunction "3V3")
			(pintype "passive")
			(teardrops
				(best_length_ratio 0.2)
				(max_length 1)
				(best_width_ratio 0.9)
				(max_width 2)
				(curved_edges yes)
				(filter_ratio 0.9)
				(enabled yes)
				(allow_two_segments yes)
				(prefer_zone_connections yes)
			)
		)
		(pad "5" smd rect
			(at -8.25 3.95 270)
			(size 0.3 1.5)
			(layers "B.Cu" "B.Mask" "B.Paste")
			(net 239 "/Com Express 7 Interfaces/PCIe_{B2Bx4}.RX3+")
			(pinfunction "PER3_N")
			(pintype "output")
			(teardrops
				(best_length_ratio 0.2)
				(max_length 1)
				(best_width_ratio 0.9)
				(max_width 2)
				(curved_edges yes)
				(filter_ratio 0.9)
				(enabled yes)
				(allow_two_segments yes)
				(prefer_zone_connections yes)
			)
		)
		(pad "6" smd rect
			(at -8 1.31 270)
			(size 0.3 1.5)
			(layers "B.Cu" "B.Mask" "B.Paste")
			(net 223 "unconnected-(J5-NC-Pad6)")
			(pinfunction "NC")
			(pintype "no_connect")
			(teardrops
				(best_length_ratio 0.2)
				(max_length 1)
				(best_width_ratio 0.9)
				(max_width 2)
				(curved_edges yes)
				(filter_ratio 0.9)
				(enabled yes)
				(allow_two_segments yes)
				(prefer_zone_connections yes)
			)
		)
		(pad "7" smd rect
			(at -7.75 3.95 270)
			(size 0.3 1.5)
			(layers "B.Cu" "B.Mask" "B.Paste")
			(net 237 "/Com Express 7 Interfaces/PCIe_{B2Bx4}.RX3-")
			(pinfunction "PER3_P")
			(pintype "output")
			(teardrops
				(best_length_ratio 0.2)
				(max_length 1)
				(best_width_ratio 0.9)
				(max_width 2)
				(curved_edges yes)
				(filter_ratio 0.9)
				(enabled yes)
				(allow_two_segments yes)
				(prefer_zone_connections yes)
			)
		)
		(pad "8" smd rect
			(at -7.5 1.31 270)
			(size 0.3 1.5)
			(layers "B.Cu" "B.Mask" "B.Paste")
			(net 224 "unconnected-(J5-NC-Pad8)")
			(pinfunction "NC")
			(pintype "no_connect")
			(teardrops
				(best_length_ratio 0.2)
				(max_length 1)
				(best_width_ratio 0.9)
				(max_width 2)
				(curved_edges yes)
				(filter_ratio 0.9)
				(enabled yes)
				(allow_two_segments yes)
				(prefer_zone_connections yes)
			)
		)
		(pad "9" smd rect
			(at -7.25 3.95 270)
			(size 0.3 1.5)
			(layers "B.Cu" "B.Mask" "B.Paste")
			(net 1 "GND")
			(pinfunction "GND")
			(pintype "passive")
			(teardrops
				(best_length_ratio 0.2)
				(max_length 1)
				(best_width_ratio 0.9)
				(max_width 2)
				(curved_edges yes)
				(filter_ratio 0.9)
				(enabled yes)
				(allow_two_segments yes)
				(prefer_zone_connections yes)
			)
		)
		(pad "10" smd rect
			(at -7 1.31 270)
			(size 0.3 1.5)
			(layers "B.Cu" "B.Mask" "B.Paste")
			(net 935 "Net-(D13-C)")
			(pinfunction "LED")
			(pintype "passive")
			(teardrops
				(best_length_ratio 0.2)
				(max_length 1)
				(best_width_ratio 0.9)
				(max_width 2)
				(curved_edges yes)
				(filter_ratio 0.9)
				(enabled yes)
				(allow_two_segments yes)
				(prefer_zone_connections yes)
			)
		)
		(pad "11" smd rect
			(at -6.75 3.95 270)
			(size 0.3 1.5)
			(layers "B.Cu" "B.Mask" "B.Paste")
			(net 242 "/Com Express 7 Interfaces/PCIe_{B2Bx4}.TX3+")
			(pinfunction "PET3_N")
			(pintype "input")
			(teardrops
				(best_length_ratio 0.2)
				(max_length 1)
				(best_width_ratio 0.9)
				(max_width 2)
				(curved_edges yes)
				(filter_ratio 0.9)
				(enabled yes)
				(allow_two_segments yes)
				(prefer_zone_connections yes)
			)
		)
		(pad "12" smd rect
			(at -6.5 1.31 270)
			(size 0.3 1.5)
			(layers "B.Cu" "B.Mask" "B.Paste")
			(net 969 "/M.2 key M #1/M2_3V3")
			(pinfunction "3V3")
			(pintype "passive")
			(teardrops
				(best_length_ratio 0.2)
				(max_length 1)
				(best_width_ratio 0.9)
				(max_width 2)
				(curved_edges yes)
				(filter_ratio 0.9)
				(enabled yes)
				(allow_two_segments yes)
				(prefer_zone_connections yes)
			)
		)
		(pad "13" smd rect
			(at -6.25 3.95 270)
			(size 0.3 1.5)
			(layers "B.Cu" "B.Mask" "B.Paste")
			(net 241 "/Com Express 7 Interfaces/PCIe_{B2Bx4}.TX3-")
			(pinfunction "PET3_P")
			(pintype "input")
			(teardrops
				(best_length_ratio 0.2)
				(max_length 1)
				(best_width_ratio 0.9)
				(max_width 2)
				(curved_edges yes)
				(filter_ratio 0.9)
				(enabled yes)
				(allow_two_segments yes)
				(prefer_zone_connections yes)
			)
		)
		(pad "14" smd rect
			(at -6 1.31 270)
			(size 0.3 1.5)
			(layers "B.Cu" "B.Mask" "B.Paste")
			(net 969 "/M.2 key M #1/M2_3V3")
			(pinfunction "3V3")
			(pintype "passive")
			(teardrops
				(best_length_ratio 0.2)
				(max_length 1)
				(best_width_ratio 0.9)
				(max_width 2)
				(curved_edges yes)
				(filter_ratio 0.9)
				(enabled yes)
				(allow_two_segments yes)
				(prefer_zone_connections yes)
			)
		)
		(pad "15" smd rect
			(at -5.75 3.95 270)
			(size 0.3 1.5)
			(layers "B.Cu" "B.Mask" "B.Paste")
			(net 1 "GND")
			(pinfunction "GND")
			(pintype "passive")
			(teardrops
				(best_length_ratio 0.2)
				(max_length 1)
				(best_width_ratio 0.9)
				(max_width 2)
				(curved_edges yes)
				(filter_ratio 0.9)
				(enabled yes)
				(allow_two_segments yes)
				(prefer_zone_connections yes)
			)
		)
		(pad "16" smd rect
			(at -5.5 1.31 270)
			(size 0.3 1.5)
			(layers "B.Cu" "B.Mask" "B.Paste")
			(net 969 "/M.2 key M #1/M2_3V3")
			(pinfunction "3V3")
			(pintype "passive")
			(teardrops
				(best_length_ratio 0.2)
				(max_length 1)
				(best_width_ratio 0.9)
				(max_width 2)
				(curved_edges yes)
				(filter_ratio 0.9)
				(enabled yes)
				(allow_two_segments yes)
				(prefer_zone_connections yes)
			)
		)
		(pad "17" smd rect
			(at -5.25 3.95 270)
			(size 0.3 1.5)
			(layers "B.Cu" "B.Mask" "B.Paste")
			(net 244 "/Com Express 7 Interfaces/PCIe_{B2Bx4}.RX2+")
			(pinfunction "PER2_N")
			(pintype "output")
			(teardrops
				(best_length_ratio 0.2)
				(max_length 1)
				(best_width_ratio 0.9)
				(max_width 2)
				(curved_edges yes)
				(filter_ratio 0.9)
				(enabled yes)
				(allow_two_segments yes)
				(prefer_zone_connections yes)
			)
		)
		(pad "18" smd rect
			(at -5 1.31 270)
			(size 0.3 1.5)
			(layers "B.Cu" "B.Mask" "B.Paste")
			(net 969 "/M.2 key M #1/M2_3V3")
			(pinfunction "3V3")
			(pintype "passive")
			(teardrops
				(best_length_ratio 0.2)
				(max_length 1)
				(best_width_ratio 0.9)
				(max_width 2)
				(curved_edges yes)
				(filter_ratio 0.9)
				(enabled yes)
				(allow_two_segments yes)
				(prefer_zone_connections yes)
			)
		)
		(pad "19" smd rect
			(at -4.75 3.95 270)
			(size 0.3 1.5)
			(layers "B.Cu" "B.Mask" "B.Paste")
			(net 243 "/Com Express 7 Interfaces/PCIe_{B2Bx4}.RX2-")
			(pinfunction "PER2_P")
			(pintype "output")
			(teardrops
				(best_length_ratio 0.2)
				(max_length 1)
				(best_width_ratio 0.9)
				(max_width 2)
				(curved_edges yes)
				(filter_ratio 0.9)
				(enabled yes)
				(allow_two_segments yes)
				(prefer_zone_connections yes)
			)
		)
		(pad "20" smd rect
			(at -4.5 1.31 270)
			(size 0.3 1.5)
			(layers "B.Cu" "B.Mask" "B.Paste")
			(net 226 "unconnected-(J5-NC-Pad20)")
			(pinfunction "NC")
			(pintype "no_connect")
			(teardrops
				(best_length_ratio 0.2)
				(max_length 1)
				(best_width_ratio 0.9)
				(max_width 2)
				(curved_edges yes)
				(filter_ratio 0.9)
				(enabled yes)
				(allow_two_segments yes)
				(prefer_zone_connections yes)
			)
		)
		(pad "21" smd rect
			(at -4.25 3.95 270)
			(size 0.3 1.5)
			(layers "B.Cu" "B.Mask" "B.Paste")
			(net 1 "GND")
			(pinfunction "GND")
			(pintype "passive")
			(teardrops
				(best_length_ratio 0.2)
				(max_length 1)
				(best_width_ratio 0.9)
				(max_width 2)
				(curved_edges yes)
				(filter_ratio 0.9)
				(enabled yes)
				(allow_two_segments yes)
				(prefer_zone_connections yes)
			)
		)
		(pad "22" smd rect
			(at -4 1.31 270)
			(size 0.3 1.5)
			(layers "B.Cu" "B.Mask" "B.Paste")
			(net 230 "unconnected-(J5-NC-Pad22)")
			(pinfunction "NC")
			(pintype "no_connect")
			(teardrops
				(best_length_ratio 0.2)
				(max_length 1)
				(best_width_ratio 0.9)
				(max_width 2)
				(curved_edges yes)
				(filter_ratio 0.9)
				(enabled yes)
				(allow_two_segments yes)
				(prefer_zone_connections yes)
			)
		)
		(pad "23" smd rect
			(at -3.75 3.95 270)
			(size 0.3 1.5)
			(layers "B.Cu" "B.Mask" "B.Paste")
			(net 249 "/Com Express 7 Interfaces/PCIe_{B2Bx4}.TX2+")
			(pinfunction "PET2_N")
			(pintype "input")
			(teardrops
				(best_length_ratio 0.2)
				(max_length 1)
				(best_width_ratio 0.9)
				(max_width 2)
				(curved_edges yes)
				(filter_ratio 0.9)
				(enabled yes)
				(allow_two_segments yes)
				(prefer_zone_connections yes)
			)
		)
		(pad "24" smd rect
			(at -3.5 1.31 270)
			(size 0.3 1.5)
			(layers "B.Cu" "B.Mask" "B.Paste")
			(net 232 "unconnected-(J5-NC-Pad24)")
			(pinfunction "NC")
			(pintype "no_connect")
			(teardrops
				(best_length_ratio 0.2)
				(max_length 1)
				(best_width_ratio 0.9)
				(max_width 2)
				(curved_edges yes)
				(filter_ratio 0.9)
				(enabled yes)
				(allow_two_segments yes)
				(prefer_zone_connections yes)
			)
		)
		(pad "25" smd rect
			(at -3.25 3.95 270)
			(size 0.3 1.5)
			(layers "B.Cu" "B.Mask" "B.Paste")
			(net 247 "/Com Express 7 Interfaces/PCIe_{B2Bx4}.TX2-")
			(pinfunction "PET2_P")
			(pintype "input")
			(teardrops
				(best_length_ratio 0.2)
				(max_length 1)
				(best_width_ratio 0.9)
				(max_width 2)
				(curved_edges yes)
				(filter_ratio 0.9)
				(enabled yes)
				(allow_two_segments yes)
				(prefer_zone_connections yes)
			)
		)
		(pad "26" smd rect
			(at -3 1.31 270)
			(size 0.3 1.5)
			(layers "B.Cu" "B.Mask" "B.Paste")
			(net 233 "unconnected-(J5-NC-Pad26)")
			(pinfunction "NC")
			(pintype "no_connect")
			(teardrops
				(best_length_ratio 0.2)
				(max_length 1)
				(best_width_ratio 0.9)
				(max_width 2)
				(curved_edges yes)
				(filter_ratio 0.9)
				(enabled yes)
				(allow_two_segments yes)
				(prefer_zone_connections yes)
			)
		)
		(pad "27" smd rect
			(at -2.75 3.95 270)
			(size 0.3 1.5)
			(layers "B.Cu" "B.Mask" "B.Paste")
			(net 1 "GND")
			(pinfunction "GND")
			(pintype "passive")
			(teardrops
				(best_length_ratio 0.2)
				(max_length 1)
				(best_width_ratio 0.9)
				(max_width 2)
				(curved_edges yes)
				(filter_ratio 0.9)
				(enabled yes)
				(allow_two_segments yes)
				(prefer_zone_connections yes)
			)
		)
		(pad "28" smd rect
			(at -2.5 1.31 270)
			(size 0.3 1.5)
			(layers "B.Cu" "B.Mask" "B.Paste")
			(net 234 "unconnected-(J5-NC-Pad28)")
			(pinfunction "NC")
			(pintype "no_connect")
			(teardrops
				(best_length_ratio 0.2)
				(max_length 1)
				(best_width_ratio 0.9)
				(max_width 2)
				(curved_edges yes)
				(filter_ratio 0.9)
				(enabled yes)
				(allow_two_segments yes)
				(prefer_zone_connections yes)
			)
		)
		(pad "29" smd rect
			(at -2.25 3.95 270)
			(size 0.3 1.5)
			(layers "B.Cu" "B.Mask" "B.Paste")
			(net 254 "/Com Express 7 Interfaces/PCIe_{B2Bx4}.RX1+")
			(pinfunction "PER1_N")
			(pintype "output")
			(teardrops
				(best_length_ratio 0.2)
				(max_length 1)
				(best_width_ratio 0.9)
				(max_width 2)
				(curved_edges yes)
				(filter_ratio 0.9)
				(enabled yes)
				(allow_two_segments yes)
				(prefer_zone_connections yes)
			)
		)
		(pad "30" smd rect
			(at -2 1.31 270)
			(size 0.3 1.5)
			(layers "B.Cu" "B.Mask" "B.Paste")
			(net 235 "unconnected-(J5-NC-Pad30)")
			(pinfunction "NC")
			(pintype "no_connect")
			(teardrops
				(best_length_ratio 0.2)
				(max_length 1)
				(best_width_ratio 0.9)
				(max_width 2)
				(curved_edges yes)
				(filter_ratio 0.9)
				(enabled yes)
				(allow_two_segments yes)
				(prefer_zone_connections yes)
			)
		)
		(pad "31" smd rect
			(at -1.75 3.95 270)
			(size 0.3 1.5)
			(layers "B.Cu" "B.Mask" "B.Paste")
			(net 252 "/Com Express 7 Interfaces/PCIe_{B2Bx4}.RX1-")
			(pinfunction "PER1_P")
			(pintype "output")
			(teardrops
				(best_length_ratio 0.2)
				(max_length 1)
				(best_width_ratio 0.9)
				(max_width 2)
				(curved_edges yes)
				(filter_ratio 0.9)
				(enabled yes)
				(allow_two_segments yes)
				(prefer_zone_connections yes)
			)
		)
		(pad "32" smd rect
			(at -1.5 1.31 270)
			(size 0.3 1.5)
			(layers "B.Cu" "B.Mask" "B.Paste")
			(net 236 "unconnected-(J5-NC-Pad32)")
			(pinfunction "NC")
			(pintype "no_connect")
			(teardrops
				(best_length_ratio 0.2)
				(max_length 1)
				(best_width_ratio 0.9)
				(max_width 2)
				(curved_edges yes)
				(filter_ratio 0.9)
				(enabled yes)
				(allow_two_segments yes)
				(prefer_zone_connections yes)
			)
		)
		(pad "33" smd rect
			(at -1.25 3.95 270)
			(size 0.3 1.5)
			(layers "B.Cu" "B.Mask" "B.Paste")
			(net 1 "GND")
			(pinfunction "GND")
			(pintype "passive")
			(teardrops
				(best_length_ratio 0.2)
				(max_length 1)
				(best_width_ratio 0.9)
				(max_width 2)
				(curved_edges yes)
				(filter_ratio 0.9)
				(enabled yes)
				(allow_two_segments yes)
				(prefer_zone_connections yes)
			)
		)
		(pad "34" smd rect
			(at -1 1.31 270)
			(size 0.3 1.5)
			(layers "B.Cu" "B.Mask" "B.Paste")
			(net 914 "unconnected-(J5-NC-Pad34)")
			(pinfunction "NC")
			(pintype "no_connect")
			(teardrops
				(best_length_ratio 0.2)
				(max_length 1)
				(best_width_ratio 0.9)
				(max_width 2)
				(curved_edges yes)
				(filter_ratio 0.9)
				(enabled yes)
				(allow_two_segments yes)
				(prefer_zone_connections yes)
			)
		)
		(pad "35" smd rect
			(at -0.75 3.95 270)
			(size 0.3 1.5)
			(layers "B.Cu" "B.Mask" "B.Paste")
			(net 259 "/Com Express 7 Interfaces/PCIe_{B2Bx4}.TX1+")
			(pinfunction "PET1_N")
			(pintype "input")
			(teardrops
				(best_length_ratio 0.2)
				(max_length 1)
				(best_width_ratio 0.9)
				(max_width 2)
				(curved_edges yes)
				(filter_ratio 0.9)
				(enabled yes)
				(allow_two_segments yes)
				(prefer_zone_connections yes)
			)
		)
		(pad "36" smd rect
			(at -0.5 1.31 270)
			(size 0.3 1.5)
			(layers "B.Cu" "B.Mask" "B.Paste")
			(net 915 "unconnected-(J5-NC-Pad36)")
			(pinfunction "NC")
			(pintype "no_connect")
			(teardrops
				(best_length_ratio 0.2)
				(max_length 1)
				(best_width_ratio 0.9)
				(max_width 2)
				(curved_edges yes)
				(filter_ratio 0.9)
				(enabled yes)
				(allow_two_segments yes)
				(prefer_zone_connections yes)
			)
		)
		(pad "37" smd rect
			(at -0.25 3.95 270)
			(size 0.3 1.5)
			(layers "B.Cu" "B.Mask" "B.Paste")
			(net 257 "/Com Express 7 Interfaces/PCIe_{B2Bx4}.TX1-")
			(pinfunction "PET1_P")
			(pintype "input")
			(teardrops
				(best_length_ratio 0.2)
				(max_length 1)
				(best_width_ratio 0.9)
				(max_width 2)
				(curved_edges yes)
				(filter_ratio 0.9)
				(enabled yes)
				(allow_two_segments yes)
				(prefer_zone_connections yes)
			)
		)
		(pad "38" smd rect
			(at 0 1.31 270)
			(size 0.3 1.5)
			(layers "B.Cu" "B.Mask" "B.Paste")
			(net 916 "unconnected-(J5-NC-Pad38)")
			(pinfunction "NC")
			(pintype "no_connect")
			(teardrops
				(best_length_ratio 0.2)
				(max_length 1)
				(best_width_ratio 0.9)
				(max_width 2)
				(curved_edges yes)
				(filter_ratio 0.9)
				(enabled yes)
				(allow_two_segments yes)
				(prefer_zone_connections yes)
			)
		)
		(pad "39" smd rect
			(at 0.25 3.95 270)
			(size 0.3 1.5)
			(layers "B.Cu" "B.Mask" "B.Paste")
			(net 1 "GND")
			(pinfunction "GND")
			(pintype "passive")
			(teardrops
				(best_length_ratio 0.2)
				(max_length 1)
				(best_width_ratio 0.9)
				(max_width 2)
				(curved_edges yes)
				(filter_ratio 0.9)
				(enabled yes)
				(allow_two_segments yes)
				(prefer_zone_connections yes)
			)
		)
		(pad "40" smd rect
			(at 0.5 1.31 270)
			(size 0.3 1.5)
			(layers "B.Cu" "B.Mask" "B.Paste")
			(net 917 "unconnected-(J5-SMB_CLK-Pad40)")
			(pinfunction "SMB_CLK")
			(pintype "input+no_connect")
			(teardrops
				(best_length_ratio 0.2)
				(max_length 1)
				(best_width_ratio 0.9)
				(max_width 2)
				(curved_edges yes)
				(filter_ratio 0.9)
				(enabled yes)
				(allow_two_segments yes)
				(prefer_zone_connections yes)
			)
		)
		(pad "41" smd rect
			(at 0.75 3.95 270)
			(size 0.3 1.5)
			(layers "B.Cu" "B.Mask" "B.Paste")
			(net 264 "/Com Express 7 Interfaces/PCIe_{B2Bx4}.RX0+")
			(pinfunction "PER0_N")
			(pintype "output")
			(teardrops
				(best_length_ratio 0.2)
				(max_length 1)
				(best_width_ratio 0.9)
				(max_width 2)
				(curved_edges yes)
				(filter_ratio 0.9)
				(enabled yes)
				(allow_two_segments yes)
				(prefer_zone_connections yes)
			)
		)
		(pad "42" smd rect
			(at 1 1.31 270)
			(size 0.3 1.5)
			(layers "B.Cu" "B.Mask" "B.Paste")
			(net 918 "unconnected-(J5-SMB_DATA-Pad42)")
			(pinfunction "SMB_DATA")
			(pintype "bidirectional+no_connect")
			(teardrops
				(best_length_ratio 0.2)
				(max_length 1)
				(best_width_ratio 0.9)
				(max_width 2)
				(curved_edges yes)
				(filter_ratio 0.9)
				(enabled yes)
				(allow_two_segments yes)
				(prefer_zone_connections yes)
			)
		)
		(pad "43" smd rect
			(at 1.25 3.95 270)
			(size 0.3 1.5)
			(layers "B.Cu" "B.Mask" "B.Paste")
			(net 262 "/Com Express 7 Interfaces/PCIe_{B2Bx4}.RX0-")
			(pinfunction "PER0_P")
			(pintype "output")
			(teardrops
				(best_length_ratio 0.2)
				(max_length 1)
				(best_width_ratio 0.9)
				(max_width 2)
				(curved_edges yes)
				(filter_ratio 0.9)
				(enabled yes)
				(allow_two_segments yes)
				(prefer_zone_connections yes)
			)
		)
		(pad "44" smd rect
			(at 1.5 1.31 270)
			(size 0.3 1.5)
			(layers "B.Cu" "B.Mask" "B.Paste")
			(net 919 "unconnected-(J5-ALERT-Pad44)")
			(pinfunction "ALERT")
			(pintype "output+no_connect")
			(teardrops
				(best_length_ratio 0.2)
				(max_length 1)
				(best_width_ratio 0.9)
				(max_width 2)
				(curved_edges yes)
				(filter_ratio 0.9)
				(enabled yes)
				(allow_two_segments yes)
				(prefer_zone_connections yes)
			)
		)
		(pad "45" smd rect
			(at 1.75 3.95 270)
			(size 0.3 1.5)
			(layers "B.Cu" "B.Mask" "B.Paste")
			(net 1 "GND")
			(pinfunction "GND")
			(pintype "passive")
			(teardrops
				(best_length_ratio 0.2)
				(max_length 1)
				(best_width_ratio 0.9)
				(max_width 2)
				(curved_edges yes)
				(filter_ratio 0.9)
				(enabled yes)
				(allow_two_segments yes)
				(prefer_zone_connections yes)
			)
		)
		(pad "46" smd rect
			(at 2 1.31 270)
			(size 0.3 1.5)
			(layers "B.Cu" "B.Mask" "B.Paste")
			(net 920 "unconnected-(J5-NC-Pad46)")
			(pinfunction "NC")
			(pintype "no_connect")
			(teardrops
				(best_length_ratio 0.2)
				(max_length 1)
				(best_width_ratio 0.9)
				(max_width 2)
				(curved_edges yes)
				(filter_ratio 0.9)
				(enabled yes)
				(allow_two_segments yes)
				(prefer_zone_connections yes)
			)
		)
		(pad "47" smd rect
			(at 2.25 3.95 270)
			(size 0.3 1.5)
			(layers "B.Cu" "B.Mask" "B.Paste")
			(net 269 "/Com Express 7 Interfaces/PCIe_{B2Bx4}.TX0+")
			(pinfunction "PET0_N")
			(pintype "input")
			(teardrops
				(best_length_ratio 0.2)
				(max_length 1)
				(best_width_ratio 0.9)
				(max_width 2)
				(curved_edges yes)
				(filter_ratio 0.9)
				(enabled yes)
				(allow_two_segments yes)
				(prefer_zone_connections yes)
			)
		)
		(pad "48" smd rect
			(at 2.5 1.31 270)
			(size 0.3 1.5)
			(layers "B.Cu" "B.Mask" "B.Paste")
			(net 921 "unconnected-(J5-NC-Pad48)")
			(pinfunction "NC")
			(pintype "no_connect")
			(teardrops
				(best_length_ratio 0.2)
				(max_length 1)
				(best_width_ratio 0.9)
				(max_width 2)
				(curved_edges yes)
				(filter_ratio 0.9)
				(enabled yes)
				(allow_two_segments yes)
				(prefer_zone_connections yes)
			)
		)
		(pad "49" smd rect
			(at 2.75 3.95 270)
			(size 0.3 1.5)
			(layers "B.Cu" "B.Mask" "B.Paste")
			(net 267 "/Com Express 7 Interfaces/PCIe_{B2Bx4}.TX0-")
			(pinfunction "PET0_P")
			(pintype "input")
			(teardrops
				(best_length_ratio 0.2)
				(max_length 1)
				(best_width_ratio 0.9)
				(max_width 2)
				(curved_edges yes)
				(filter_ratio 0.9)
				(enabled yes)
				(allow_two_segments yes)
				(prefer_zone_connections yes)
			)
		)
		(pad "50" smd rect
			(at 3 1.31 270)
			(size 0.3 1.5)
			(layers "B.Cu" "B.Mask" "B.Paste")
			(net 228 "/M.2 key M #1/~{PERST_D}")
			(pinfunction "~{PERST}")
			(pintype "input")
			(teardrops
				(best_length_ratio 0.2)
				(max_length 1)
				(best_width_ratio 0.9)
				(max_width 2)
				(curved_edges yes)
				(filter_ratio 0.9)
				(enabled yes)
				(allow_two_segments yes)
				(prefer_zone_connections yes)
			)
		)
		(pad "51" smd rect
			(at 3.25 3.95 270)
			(size 0.3 1.5)
			(layers "B.Cu" "B.Mask" "B.Paste")
			(net 1 "GND")
			(pinfunction "GND")
			(pintype "passive")
			(teardrops
				(best_length_ratio 0.2)
				(max_length 1)
				(best_width_ratio 0.9)
				(max_width 2)
				(curved_edges yes)
				(filter_ratio 0.9)
				(enabled yes)
				(allow_two_segments yes)
				(prefer_zone_connections yes)
			)
		)
		(pad "52" smd rect
			(at 3.5 1.31 270)
			(size 0.3 1.5)
			(layers "B.Cu" "B.Mask" "B.Paste")
			(net 529 "/M.2 key M #1/~{CLKREQ}")
			(pinfunction "~{CLKREQ}")
			(pintype "output")
			(teardrops
				(best_length_ratio 0.2)
				(max_length 1)
				(best_width_ratio 0.9)
				(max_width 2)
				(curved_edges yes)
				(filter_ratio 0.9)
				(enabled yes)
				(allow_two_segments yes)
				(prefer_zone_connections yes)
			)
		)
		(pad "53" smd rect
			(at 3.75 3.95 270)
			(size 0.3 1.5)
			(layers "B.Cu" "B.Mask" "B.Paste")
			(net 229 "/M.2 key M #1/PCIE_{REF}.CK-")
			(pinfunction "REFCLK_N")
			(pintype "input")
			(teardrops
				(best_length_ratio 0.2)
				(max_length 1)
				(best_width_ratio 0.9)
				(max_width 2)
				(curved_edges yes)
				(filter_ratio 0.9)
				(enabled yes)
				(allow_two_segments yes)
				(prefer_zone_connections yes)
			)
		)
		(pad "54" smd rect
			(at 4 1.31 270)
			(size 0.3 1.5)
			(layers "B.Cu" "B.Mask" "B.Paste")
			(net 922 "unconnected-(J5-~{PEWAKE}-Pad54)")
			(pinfunction "~{PEWAKE}")
			(pintype "input+no_connect")
			(teardrops
				(best_length_ratio 0.2)
				(max_length 1)
				(best_width_ratio 0.9)
				(max_width 2)
				(curved_edges yes)
				(filter_ratio 0.9)
				(enabled yes)
				(allow_two_segments yes)
				(prefer_zone_connections yes)
			)
		)
		(pad "55" smd rect
			(at 4.25 3.95 270)
			(size 0.3 1.5)
			(layers "B.Cu" "B.Mask" "B.Paste")
			(net 231 "/M.2 key M #1/PCIE_{REF}.CK+")
			(pinfunction "REFCLK_P")
			(pintype "input")
			(teardrops
				(best_length_ratio 0.2)
				(max_length 1)
				(best_width_ratio 0.9)
				(max_width 2)
				(curved_edges yes)
				(filter_ratio 0.9)
				(enabled yes)
				(allow_two_segments yes)
				(prefer_zone_connections yes)
			)
		)
		(pad "56" smd rect
			(at 4.5 1.31 270)
			(size 0.3 1.5)
			(layers "B.Cu" "B.Mask" "B.Paste")
			(net 923 "unconnected-(J5-NC-Pad56)")
			(pinfunction "NC")
			(pintype "no_connect")
			(teardrops
				(best_length_ratio 0.2)
				(max_length 1)
				(best_width_ratio 0.9)
				(max_width 2)
				(curved_edges yes)
				(filter_ratio 0.9)
				(enabled yes)
				(allow_two_segments yes)
				(prefer_zone_connections yes)
			)
		)
		(pad "57" smd rect
			(at 4.75 3.95 270)
			(size 0.3 1.5)
			(layers "B.Cu" "B.Mask" "B.Paste")
			(net 1 "GND")
			(pinfunction "GND")
			(pintype "passive")
			(teardrops
				(best_length_ratio 0.2)
				(max_length 1)
				(best_width_ratio 0.9)
				(max_width 2)
				(curved_edges yes)
				(filter_ratio 0.9)
				(enabled yes)
				(allow_two_segments yes)
				(prefer_zone_connections yes)
			)
		)
		(pad "58" smd rect
			(at 5 1.31 270)
			(size 0.3 1.5)
			(layers "B.Cu" "B.Mask" "B.Paste")
			(net 924 "unconnected-(J5-NC-Pad58)")
			(pinfunction "NC")
			(pintype "no_connect")
			(teardrops
				(best_length_ratio 0.2)
				(max_length 1)
				(best_width_ratio 0.9)
				(max_width 2)
				(curved_edges yes)
				(filter_ratio 0.9)
				(enabled yes)
				(allow_two_segments yes)
				(prefer_zone_connections yes)
			)
		)
		(pad "67" smd rect
			(at 7.25 3.95 270)
			(size 0.3 1.5)
			(layers "B.Cu" "B.Mask" "B.Paste")
			(net 925 "unconnected-(J5-NC-Pad67)")
			(pinfunction "NC")
			(pintype "no_connect")
			(teardrops
				(best_length_ratio 0.2)
				(max_length 1)
				(best_width_ratio 0.9)
				(max_width 2)
				(curved_edges yes)
				(filter_ratio 0.9)
				(enabled yes)
				(allow_two_segments yes)
				(prefer_zone_connections yes)
			)
		)
		(pad "68" smd rect
			(at 7.5 1.31 270)
			(size 0.3 1.5)
			(layers "B.Cu" "B.Mask" "B.Paste")
			(net 926 "Net-(J5-SUSCLK)")
			(pinfunction "SUSCLK")
			(pintype "input")
			(teardrops
				(best_length_ratio 0.2)
				(max_length 1)
				(best_width_ratio 0.9)
				(max_width 2)
				(curved_edges yes)
				(filter_ratio 0.9)
				(enabled yes)
				(allow_two_segments yes)
				(prefer_zone_connections yes)
			)
		)
		(pad "69" smd rect
			(at 7.75 3.95 270)
			(size 0.3 1.5)
			(layers "B.Cu" "B.Mask" "B.Paste")
			(net 927 "unconnected-(J5-NC-Pad69)")
			(pinfunction "NC")
			(pintype "no_connect")
			(teardrops
				(best_length_ratio 0.2)
				(max_length 1)
				(best_width_ratio 0.9)
				(max_width 2)
				(curved_edges yes)
				(filter_ratio 0.9)
				(enabled yes)
				(allow_two_segments yes)
				(prefer_zone_connections yes)
			)
		)
		(pad "70" smd rect
			(at 8 1.31 270)
			(size 0.3 1.5)
			(layers "B.Cu" "B.Mask" "B.Paste")
			(net 969 "/M.2 key M #1/M2_3V3")
			(pinfunction "3V3")
			(pintype "passive")
			(teardrops
				(best_length_ratio 0.2)
				(max_length 1)
				(best_width_ratio 0.9)
				(max_width 2)
				(curved_edges yes)
				(filter_ratio 0.9)
				(enabled yes)
				(allow_two_segments yes)
				(prefer_zone_connections yes)
			)
		)
		(pad "71" smd rect
			(at 8.25 3.95 270)
			(size 0.3 1.5)
			(layers "B.Cu" "B.Mask" "B.Paste")
			(net 1 "GND")
			(pinfunction "GND")
			(pintype "passive")
			(teardrops
				(best_length_ratio 0.2)
				(max_length 1)
				(best_width_ratio 0.9)
				(max_width 2)
				(curved_edges yes)
				(filter_ratio 0.9)
				(enabled yes)
				(allow_two_segments yes)
				(prefer_zone_connections yes)
			)
		)
		(pad "72" smd rect
			(at 8.5 1.31 270)
			(size 0.3 1.5)
			(layers "B.Cu" "B.Mask" "B.Paste")
			(net 969 "/M.2 key M #1/M2_3V3")
			(pinfunction "3V3")
			(pintype "passive")
			(teardrops
				(best_length_ratio 0.2)
				(max_length 1)
				(best_width_ratio 0.9)
				(max_width 2)
				(curved_edges yes)
				(filter_ratio 0.9)
				(enabled yes)
				(allow_two_segments yes)
				(prefer_zone_connections yes)
			)
		)
		(pad "73" smd rect
			(at 8.75 3.95 270)
			(size 0.3 1.5)
			(layers "B.Cu" "B.Mask" "B.Paste")
			(net 1 "GND")
			(pinfunction "GND")
			(pintype "passive")
			(teardrops
				(best_length_ratio 0.2)
				(max_length 1)
				(best_width_ratio 0.9)
				(max_width 2)
				(curved_edges yes)
				(filter_ratio 0.9)
				(enabled yes)
				(allow_two_segments yes)
				(prefer_zone_connections yes)
			)
		)
		(pad "74" smd rect
			(at 9 1.31 270)
			(size 0.3 1.5)
			(layers "B.Cu" "B.Mask" "B.Paste")
			(net 969 "/M.2 key M #1/M2_3V3")
			(pinfunction "3V3")
			(pintype "passive")
			(teardrops
				(best_length_ratio 0.2)
				(max_length 1)
				(best_width_ratio 0.9)
				(max_width 2)
				(curved_edges yes)
				(filter_ratio 0.9)
				(enabled yes)
				(allow_two_segments yes)
				(prefer_zone_connections yes)
			)
		)
		(pad "75" smd rect
			(at 9.25 3.95 270)
			(size 0.3 1.5)
			(layers "B.Cu" "B.Mask" "B.Paste")
			(net 1 "GND")
			(pinfunction "GND")
			(pintype "passive")
			(teardrops
				(best_length_ratio 0.2)
				(max_length 1)
				(best_width_ratio 0.9)
				(max_width 2)
				(curved_edges yes)
				(filter_ratio 0.9)
				(enabled yes)
				(allow_two_segments yes)
				(prefer_zone_connections yes)
			)
		)
		(pad "SH" smd rect
			(at -11.585 -2.57 270)
			(size 1.2 2.6)
			(layers "B.Cu" "B.Mask" "B.Paste")
			(net 1 "GND")
			(pinfunction "SH")
			(pintype "passive")
			(solder_mask_margin 0.102)
			(teardrops
				(best_length_ratio 0.2)
				(max_length 1)
				(best_width_ratio 0.9)
				(max_width 2)
				(curved_edges yes)
				(filter_ratio 0.9)
				(enabled yes)
				(allow_two_segments yes)
				(prefer_zone_connections yes)
			)
		)
		(pad "SH" smd rect
			(at 11.585 -2.57 270)
			(size 1.2 2.6)
			(layers "B.Cu" "B.Mask" "B.Paste")
			(net 1 "GND")
			(pinfunction "SH")
			(pintype "passive")
			(solder_mask_margin 0.102)
			(teardrops
				(best_length_ratio 0.2)
				(max_length 1)
				(best_width_ratio 0.9)
				(max_width 2)
				(curved_edges yes)
				(filter_ratio 0.9)
				(enabled yes)
				(allow_two_segments yes)
				(prefer_zone_connections yes)
			)
		)
	)
	(footprint "antmicro-footprints:C_0402_1005Metric"
		(layer "B.Cu")
		(at 136.29 137.36 -90)
		(descr "Capacitor SMD 0402")
		(tags "capacitor SMD 0402")
		(property "Reference" "C191"
			(at -1.4 0.49 90)
			(layer "B.SilkS")
			(effects
				(font
					(size 0.7 0.7)
					(thickness 0.15)
				)
				(justify left bottom mirror)
			)
		)
		(property "Value" "C_100n_0402"
			(at -1.022927 -2.155213 90)
			(layer "B.Fab")
			(effects
				(font
					(size 0.7 0.7)
					(thickness 0.15)
				)
				(justify left bottom mirror)
			)
		)
		(property "Datasheet" "https://www.murata.com/products/productdetail?partno=GRM155R61H104KE14%23"
			(at 0 0 270)
			(layer "F.Fab")
			(hide yes)
			(effects
				(font
					(size 1.27 1.27)
					(thickness 0.15)
				)
			)
		)
		(property "Author" "Antmicro"
			(at -1.07 273.65 0)
			(layer "B.Fab")
			(hide yes)
			(effects
				(font
					(size 1 1)
					(thickness 0.15)
				)
				(justify mirror)
			)
		)
		(property "Dielectric" "X5R"
			(at -1.07 273.65 0)
			(layer "B.Fab")
			(hide yes)
			(effects
				(font
					(size 1 1)
					(thickness 0.15)
				)
				(justify mirror)
			)
		)
		(property "License" "Apache-2.0"
			(at -1.07 273.65 0)
			(layer "B.Fab")
			(hide yes)
			(effects
				(font
					(size 1 1)
					(thickness 0.15)
				)
				(justify mirror)
			)
		)
		(property "MPN" "GRM155R61H104KE14D"
			(at -1.07 273.65 0)
			(layer "B.Fab")
			(hide yes)
			(effects
				(font
					(size 1 1)
					(thickness 0.15)
				)
				(justify mirror)
			)
		)
		(property "Manufacturer" "Murata"
			(at -1.07 273.65 0)
			(layer "B.Fab")
			(hide yes)
			(effects
				(font
					(size 1 1)
					(thickness 0.15)
				)
				(justify mirror)
			)
		)
		(property "Public" "False"
			(at -1.07 273.65 0)
			(layer "B.Fab")
			(hide yes)
			(effects
				(font
					(size 1 1)
					(thickness 0.15)
				)
				(justify mirror)
			)
		)
		(property "Val" "100n"
			(at -1.07 273.65 0)
			(layer "B.Fab")
			(hide yes)
			(effects
				(font
					(size 1 1)
					(thickness 0.15)
				)
				(justify mirror)
			)
		)
		(property "Voltage" "50V"
			(at -1.07 273.65 0)
			(layer "B.Fab")
			(hide yes)
			(effects
				(font
					(size 1 1)
					(thickness 0.15)
				)
				(justify mirror)
			)
		)
		(sheetname "KR to SFI #2")
		(sheetfile "kr_sfi.kicad_sch")
		(attr smd)
		(fp_rect
			(start -0.925 0.47)
			(end 0.925 -0.47)
			(stroke
				(width 0.05)
				(type default)
			)
			(fill no)
			(layer "B.CrtYd")
		)
		(fp_line
			(start -0.494 0.25)
			(end -0.494 -0.248)
			(stroke
				(width 0.15)
				(type solid)
			)
			(layer "B.Fab")
		)
		(fp_line
			(start 0.504 0.25)
			(end -0.494 0.25)
			(stroke
				(width 0.15)
				(type solid)
			)
			(layer "B.Fab")
		)
		(fp_line
			(start -0.494 -0.248)
			(end 0.504 -0.248)
			(stroke
				(width 0.15)
				(type solid)
			)
			(layer "B.Fab")
		)
		(fp_line
			(start 0.504 -0.248)
			(end 0.504 0.25)
			(stroke
				(width 0.15)
				(type solid)
			)
			(layer "B.Fab")
		)
		(pad "1" smd roundrect
			(at -0.48 0 270)
			(size 0.59 0.64)
			(layers "B.Cu" "B.Mask" "B.Paste")
			(roundrect_rratio 0.25)
			(net 1 "GND")
			(pintype "passive")
			(teardrops
				(best_length_ratio 0.2)
				(max_length 1)
				(best_width_ratio 0.9)
				(max_width 2)
				(curved_edges yes)
				(filter_ratio 0.9)
				(enabled yes)
				(allow_two_segments yes)
				(prefer_zone_connections yes)
			)
		)
		(pad "2" smd roundrect
			(at 0.48 0 270)
			(size 0.59 0.64)
			(layers "B.Cu" "B.Mask" "B.Paste")
			(roundrect_rratio 0.25)
			(net 74 "+1V0")
			(pintype "passive")
			(teardrops
				(best_length_ratio 0.2)
				(max_length 1)
				(best_width_ratio 0.9)
				(max_width 2)
				(curved_edges yes)
				(filter_ratio 0.9)
				(enabled yes)
				(allow_two_segments yes)
				(prefer_zone_connections yes)
			)
		)
	)
	(footprint "antmicro-footprints:R_0402_1005Metric"
		(layer "B.Cu")
		(at 104.44 155.66)
		(descr "Resistor SMD 0402")
		(tags "resistor SMD 0402")
		(property "Reference" "R81"
			(at 0.89 0.44 0)
			(layer "B.SilkS")
			(effects
				(font
					(size 0.7 0.7)
					(thickness 0.15)
				)
				(justify right bottom mirror)
			)
		)
		(property "Value" "R_0R_0402"
			(at -1.011843 -1.772047 0)
			(layer "B.Fab")
			(effects
				(font
					(size 0.7 0.7)
					(thickness 0.15)
				)
				(justify right bottom mirror)
			)
		)
		(property "Datasheet" "https://industrial.panasonic.com/cdbs/www-data/pdf/RDA0000/AOA0000C301.pdf"
			(at 0 0 0)
			(layer "F.Fab")
			(hide yes)
			(effects
				(font
					(size 1.27 1.27)
					(thickness 0.15)
				)
			)
		)
		(property "Author" "Antmicro"
			(at 0 0 0)
			(layer "B.Fab")
			(hide yes)
			(effects
				(font
					(size 1 1)
					(thickness 0.15)
				)
				(justify mirror)
			)
		)
		(property "Current" "1A"
			(at 0 0 0)
			(layer "B.Fab")
			(hide yes)
			(effects
				(font
					(size 1 1)
					(thickness 0.15)
				)
				(justify mirror)
			)
		)
		(property "License" "Apache-2.0"
			(at 0 0 0)
			(layer "B.Fab")
			(hide yes)
			(effects
				(font
					(size 1 1)
					(thickness 0.15)
				)
				(justify mirror)
			)
		)
		(property "MPN" "ERJ2GE0R00X"
			(at 0 0 0)
			(layer "B.Fab")
			(hide yes)
			(effects
				(font
					(size 1 1)
					(thickness 0.15)
				)
				(justify mirror)
			)
		)
		(property "Manufacturer" "Panasonic"
			(at 0 0 0)
			(layer "B.Fab")
			(hide yes)
			(effects
				(font
					(size 1 1)
					(thickness 0.15)
				)
				(justify mirror)
			)
		)
		(property "Public" "False"
			(at 0 0 0)
			(layer "B.Fab")
			(hide yes)
			(effects
				(font
					(size 1 1)
					(thickness 0.15)
				)
				(justify mirror)
			)
		)
		(property "Tolerance" ""
			(at 0 0 0)
			(layer "B.Fab")
			(hide yes)
			(effects
				(font
					(size 1 1)
					(thickness 0.15)
				)
				(justify mirror)
			)
		)
		(property "Val" "0R"
			(at 0 0 0)
			(layer "B.Fab")
			(hide yes)
			(effects
				(font
					(size 1 1)
					(thickness 0.15)
				)
				(justify mirror)
			)
		)
		(sheetname "OCuLink")
		(sheetfile "oculink.kicad_sch")
		(attr smd)
		(fp_rect
			(start -0.925 0.47)
			(end 0.925 -0.47)
			(stroke
				(width 0.05)
				(type default)
			)
			(fill no)
			(layer "B.CrtYd")
		)
		(fp_rect
			(start -0.5 0.25)
			(end 0.5 -0.25)
			(stroke
				(width 0.15)
				(type solid)
			)
			(fill no)
			(layer "B.Fab")
		)
		(pad "1" smd roundrect
			(at -0.48 0)
			(size 0.59 0.64)
			(layers "B.Cu" "B.Mask" "B.Paste")
			(roundrect_rratio 0.25)
			(net 59 "/OCuLink/V_{ACT_TX}0")
			(pintype "passive")
			(teardrops
				(best_length_ratio 0.2)
				(max_length 1)
				(best_width_ratio 0.9)
				(max_width 2)
				(curved_edges yes)
				(filter_ratio 0.9)
				(enabled yes)
				(allow_two_segments yes)
				(prefer_zone_connections yes)
			)
		)
		(pad "2" smd roundrect
			(at 0.48 0)
			(size 0.59 0.64)
			(layers "B.Cu" "B.Mask" "B.Paste")
			(roundrect_rratio 0.25)
			(net 2 "+3V3")
			(pintype "passive")
			(teardrops
				(best_length_ratio 0.2)
				(max_length 1)
				(best_width_ratio 0.9)
				(max_width 2)
				(curved_edges yes)
				(filter_ratio 0.9)
				(enabled yes)
				(allow_two_segments yes)
				(prefer_zone_connections yes)
			)
		)
	)
	(footprint "antmicro-footprints:USON-10_2.5x1mm_P0.5mm"
		(layer "B.Cu")
		(at 104.767002 162.61)
		(descr "USON-10 2.5x1mm_ Pitch 0.5mm")
		(tags "USON-10 2.5x1mm Pitch 0.5mm")
		(property "Reference" "U35"
			(at 1.712998 1.07 90)
			(layer "B.SilkS")
			(effects
				(font
					(size 0.7 0.7)
					(thickness 0.15)
				)
				(justify right bottom mirror)
			)
		)
		(property "Value" "ESD204DQAR"
			(at 0.018 -2.499 0)
			(layer "B.Fab")
			(effects
				(font
					(size 0.7 0.7)
					(thickness 0.15)
				)
				(justify right bottom mirror)
			)
		)
		(property "Datasheet" "https://www.ti.com/lit/ds/symlink/esd204.pdf?ts=1706004844383&ref_url=https%253A%252F%252Fwww.ti.com%252Finterface%252Fdiodes%252Fesd-protection-diodes%252Fproducts.html"
			(at 0 0 0)
			(layer "F.Fab")
			(hide yes)
			(effects
				(font
					(size 1.27 1.27)
					(thickness 0.15)
				)
			)
		)
		(property "Author" "Antmicro"
			(at 0 0 0)
			(layer "B.Fab")
			(hide yes)
			(effects
				(font
					(size 1 1)
					(thickness 0.15)
				)
				(justify mirror)
			)
		)
		(property "License" "Apache-2.0"
			(at 0 0 0)
			(layer "B.Fab")
			(hide yes)
			(effects
				(font
					(size 1 1)
					(thickness 0.15)
				)
				(justify mirror)
			)
		)
		(property "MPN" "ESD204DQAR"
			(at 0 0 0)
			(layer "B.Fab")
			(hide yes)
			(effects
				(font
					(size 1 1)
					(thickness 0.15)
				)
				(justify mirror)
			)
		)
		(property "Manufacturer" "Texas Instruments"
			(at 0 0 0)
			(layer "B.Fab")
			(hide yes)
			(effects
				(font
					(size 1 1)
					(thickness 0.15)
				)
				(justify mirror)
			)
		)
		(sheetname "OCuLink")
		(sheetfile "oculink.kicad_sch")
		(attr smd)
		(fp_line
			(start -0.5 -1.398)
			(end 0.498 -1.398)
			(stroke
				(width 0.15)
				(type solid)
			)
			(layer "B.SilkS")
		)
		(fp_line
			(start -0.5 1.401)
			(end 0.498 1.401)
			(stroke
				(width 0.15)
				(type solid)
			)
			(layer "B.SilkS")
		)
		(fp_circle
			(center -0.68 1.27)
			(end -0.63 1.27)
			(stroke
				(width 0.15)
				(type solid)
			)
			(fill yes)
			(layer "B.SilkS")
		)
		(fp_rect
			(start -0.8 1.5)
			(end 0.8 -1.499)
			(stroke
				(width 0.05)
				(type solid)
			)
			(fill no)
			(layer "B.CrtYd")
		)
		(fp_line
			(start -0.5 -1.249)
			(end -0.5 1)
			(stroke
				(width 0.15)
				(type solid)
			)
			(layer "B.Fab")
		)
		(fp_line
			(start -0.5 1)
			(end -0.25 1.25)
			(stroke
				(width 0.15)
				(type solid)
			)
			(layer "B.Fab")
		)
		(fp_line
			(start -0.25 1.25)
			(end 0.498 1.25)
			(stroke
				(width 0.15)
				(type solid)
			)
			(layer "B.Fab")
		)
		(fp_line
			(start 0.498 -1.249)
			(end -0.5 -1.249)
			(stroke
				(width 0.15)
				(type solid)
			)
			(layer "B.Fab")
		)
		(fp_line
			(start 0.498 -1.249)
			(end 0.498 1.25)
			(stroke
				(width 0.15)
				(type solid)
			)
			(layer "B.Fab")
		)
		(pad "1" smd roundrect
			(at -0.387 1 90)
			(size 0.25 0.55)
			(layers "B.Cu" "B.Mask" "B.Paste")
			(roundrect_rratio 0.25)
			(net 198 "/OCuLink/SCL")
			(pintype "passive")
			(teardrops
				(best_length_ratio 0.2)
				(max_length 1)
				(best_width_ratio 0.9)
				(max_width 2)
				(curved_edges yes)
				(filter_ratio 0.9)
				(enabled yes)
				(allow_two_segments yes)
				(prefer_zone_connections yes)
			)
		)
		(pad "2" smd roundrect
			(at -0.387 0.5 90)
			(size 0.25 0.55)
			(layers "B.Cu" "B.Mask" "B.Paste")
			(roundrect_rratio 0.25)
			(net 199 "/OCuLink/SDA")
			(pintype "passive")
			(teardrops
				(best_length_ratio 0.2)
				(max_length 1)
				(best_width_ratio 0.9)
				(max_width 2)
				(curved_edges yes)
				(filter_ratio 0.9)
				(enabled yes)
				(allow_two_segments yes)
				(prefer_zone_connections yes)
			)
		)
		(pad "3" smd roundrect
			(at -0.387 0 90)
			(size 0.4 0.55)
			(layers "B.Cu" "B.Mask" "B.Paste")
			(roundrect_rratio 0.25)
			(net 1 "GND")
			(pintype "power_in")
			(teardrops
				(best_length_ratio 0.2)
				(max_length 1)
				(best_width_ratio 0.9)
				(max_width 2)
				(curved_edges yes)
				(filter_ratio 0.9)
				(enabled yes)
				(allow_two_segments yes)
				(prefer_zone_connections yes)
			)
		)
		(pad "4" smd roundrect
			(at -0.387 -0.498 90)
			(size 0.25 0.55)
			(layers "B.Cu" "B.Mask" "B.Paste")
			(roundrect_rratio 0.25)
			(net 200 "/OCuLink/~{PERST_D0}")
			(pintype "passive")
			(teardrops
				(best_length_ratio 0.2)
				(max_length 1)
				(best_width_ratio 0.9)
				(max_width 2)
				(curved_edges yes)
				(filter_ratio 0.9)
				(enabled yes)
				(allow_two_segments yes)
				(prefer_zone_connections yes)
			)
		)
		(pad "5" smd roundrect
			(at -0.387 -0.998 90)
			(size 0.25 0.55)
			(layers "B.Cu" "B.Mask" "B.Paste")
			(roundrect_rratio 0.25)
			(net 201 "/OCuLink/~{CPRSNT_D0}")
			(pintype "passive")
			(teardrops
				(best_length_ratio 0.2)
				(max_length 1)
				(best_width_ratio 0.9)
				(max_width 2)
				(curved_edges yes)
				(filter_ratio 0.9)
				(enabled yes)
				(allow_two_segments yes)
				(prefer_zone_connections yes)
			)
		)
		(pad "6" smd roundrect
			(at 0.385 -0.998 90)
			(size 0.25 0.55)
			(layers "B.Cu" "B.Mask" "B.Paste")
			(roundrect_rratio 0.25)
			(net 201 "/OCuLink/~{CPRSNT_D0}")
			(pintype "passive")
			(teardrops
				(best_length_ratio 0.2)
				(max_length 1)
				(best_width_ratio 0.9)
				(max_width 2)
				(curved_edges yes)
				(filter_ratio 0.9)
				(enabled yes)
				(allow_two_segments yes)
				(prefer_zone_connections yes)
			)
		)
		(pad "7" smd roundrect
			(at 0.385 -0.498 90)
			(size 0.25 0.55)
			(layers "B.Cu" "B.Mask" "B.Paste")
			(roundrect_rratio 0.25)
			(net 200 "/OCuLink/~{PERST_D0}")
			(pintype "passive")
			(teardrops
				(best_length_ratio 0.2)
				(max_length 1)
				(best_width_ratio 0.9)
				(max_width 2)
				(curved_edges yes)
				(filter_ratio 0.9)
				(enabled yes)
				(allow_two_segments yes)
				(prefer_zone_connections yes)
			)
		)
		(pad "8" smd roundrect
			(at 0.385 0 90)
			(size 0.4 0.55)
			(layers "B.Cu" "B.Mask" "B.Paste")
			(roundrect_rratio 0.25)
			(net 1 "GND")
			(pintype "passive")
			(teardrops
				(best_length_ratio 0.2)
				(max_length 1)
				(best_width_ratio 0.9)
				(max_width 2)
				(curved_edges yes)
				(filter_ratio 0.9)
				(enabled yes)
				(allow_two_segments yes)
				(prefer_zone_connections yes)
			)
		)
		(pad "9" smd roundrect
			(at 0.385 0.5 90)
			(size 0.25 0.55)
			(layers "B.Cu" "B.Mask" "B.Paste")
			(roundrect_rratio 0.25)
			(net 199 "/OCuLink/SDA")
			(pintype "passive")
			(teardrops
				(best_length_ratio 0.2)
				(max_length 1)
				(best_width_ratio 0.9)
				(max_width 2)
				(curved_edges yes)
				(filter_ratio 0.9)
				(enabled yes)
				(allow_two_segments yes)
				(prefer_zone_connections yes)
			)
		)
		(pad "10" smd roundrect
			(at 0.385 1 90)
			(size 0.25 0.55)
			(layers "B.Cu" "B.Mask" "B.Paste")
			(roundrect_rratio 0.25)
			(net 198 "/OCuLink/SCL")
			(pintype "passive")
			(teardrops
				(best_length_ratio 0.2)
				(max_length 1)
				(best_width_ratio 0.9)
				(max_width 2)
				(curved_edges yes)
				(filter_ratio 0.9)
				(enabled yes)
				(allow_two_segments yes)
				(prefer_zone_connections yes)
			)
		)
	)
	(footprint "antmicro-footprints:R_0402_1005Metric"
		(layer "B.Cu")
		(at 126.09 137.06 180)
		(descr "Resistor SMD 0402")
		(tags "resistor SMD 0402")
		(property "Reference" "R296"
			(at 0.79 -0.4 0)
			(layer "B.SilkS")
			(effects
				(font
					(size 0.7 0.7)
					(thickness 0.15)
				)
				(justify left bottom mirror)
			)
		)
		(property "Value" "R_10k_0402"
			(at -1.011843 -1.772047 0)
			(layer "B.Fab")
			(effects
				(font
					(size 0.7 0.7)
					(thickness 0.15)
				)
				(justify left bottom mirror)
			)
		)
		(property "Datasheet" "https://www.bourns.com/docs/product-datasheets/cr.pdf"
			(at 0 0 180)
			(layer "F.Fab")
			(hide yes)
			(effects
				(font
					(size 1.27 1.27)
					(thickness 0.15)
				)
			)
		)
		(property "Author" "Antmicro"
			(at 252.18 274.12 0)
			(layer "B.Fab")
			(hide yes)
			(effects
				(font
					(size 1 1)
					(thickness 0.15)
				)
				(justify mirror)
			)
		)
		(property "License" "Apache-2.0"
			(at 252.18 274.12 0)
			(layer "B.Fab")
			(hide yes)
			(effects
				(font
					(size 1 1)
					(thickness 0.15)
				)
				(justify mirror)
			)
		)
		(property "MPN" "CR0402-FX-1002GLF"
			(at 252.18 274.12 0)
			(layer "B.Fab")
			(hide yes)
			(effects
				(font
					(size 1 1)
					(thickness 0.15)
				)
				(justify mirror)
			)
		)
		(property "Manufacturer" "Bourns"
			(at 252.18 274.12 0)
			(layer "B.Fab")
			(hide yes)
			(effects
				(font
					(size 1 1)
					(thickness 0.15)
				)
				(justify mirror)
			)
		)
		(property "Public" "False"
			(at 252.18 274.12 0)
			(layer "B.Fab")
			(hide yes)
			(effects
				(font
					(size 1 1)
					(thickness 0.15)
				)
				(justify mirror)
			)
		)
		(property "Tolerance" "1%"
			(at 252.18 274.12 0)
			(layer "B.Fab")
			(hide yes)
			(effects
				(font
					(size 1 1)
					(thickness 0.15)
				)
				(justify mirror)
			)
		)
		(property "Val" "10k"
			(at 252.18 274.12 0)
			(layer "B.Fab")
			(hide yes)
			(effects
				(font
					(size 1 1)
					(thickness 0.15)
				)
				(justify mirror)
			)
		)
		(sheetname "KR to SFI #2")
		(sheetfile "kr_sfi.kicad_sch")
		(attr smd dnp)
		(fp_rect
			(start -0.925 0.47)
			(end 0.925 -0.47)
			(stroke
				(width 0.05)
				(type default)
			)
			(fill no)
			(layer "B.CrtYd")
		)
		(fp_rect
			(start -0.5 0.25)
			(end 0.5 -0.25)
			(stroke
				(width 0.15)
				(type solid)
			)
			(fill no)
			(layer "B.Fab")
		)
		(pad "1" smd roundrect
			(at -0.48 0 180)
			(size 0.59 0.64)
			(layers "B.Cu" "B.Mask" "B.Paste")
			(roundrect_rratio 0.25)
			(net 677 "Net-(U45C-PRTAD1)")
			(pintype "passive")
			(teardrops
				(best_length_ratio 0.2)
				(max_length 1)
				(best_width_ratio 0.9)
				(max_width 2)
				(curved_edges yes)
				(filter_ratio 0.9)
				(enabled yes)
				(allow_two_segments yes)
				(prefer_zone_connections yes)
			)
		)
		(pad "2" smd roundrect
			(at 0.48 0 180)
			(size 0.59 0.64)
			(layers "B.Cu" "B.Mask" "B.Paste")
			(roundrect_rratio 0.25)
			(net 78 "+1V8")
			(pintype "passive")
			(teardrops
				(best_length_ratio 0.2)
				(max_length 1)
				(best_width_ratio 0.9)
				(max_width 2)
				(curved_edges yes)
				(filter_ratio 0.9)
				(enabled yes)
				(allow_two_segments yes)
				(prefer_zone_connections yes)
			)
		)
	)
	(footprint "antmicro-footprints:C_0402_1005Metric"
		(layer "B.Cu")
		(at 109.811 160.847571 180)
		(descr "Capacitor SMD 0402")
		(tags "capacitor SMD 0402")
		(property "Reference" "C140"
			(at -3.689 -0.502429 0)
			(layer "B.SilkS")
			(effects
				(font
					(size 0.7 0.7)
					(thickness 0.15)
				)
				(justify left bottom mirror)
			)
		)
		(property "Value" "C_220n_0402"
			(at -1.022927 -2.155213 0)
			(layer "B.Fab")
			(effects
				(font
					(size 0.7 0.7)
					(thickness 0.15)
				)
				(justify left bottom mirror)
			)
		)
		(property "Datasheet" "https://www.yageo.com/en/Chart/Download/pdf/CC0402KRX5R6BB224"
			(at 0 0 180)
			(layer "F.Fab")
			(hide yes)
			(effects
				(font
					(size 1.27 1.27)
					(thickness 0.15)
				)
			)
		)
		(property "Author" "Antmicro"
			(at 219.622 321.695142 0)
			(layer "B.Fab")
			(hide yes)
			(effects
				(font
					(size 1 1)
					(thickness 0.15)
				)
				(justify mirror)
			)
		)
		(property "Dielectric" ""
			(at 219.622 321.695142 0)
			(layer "B.Fab")
			(hide yes)
			(effects
				(font
					(size 1 1)
					(thickness 0.15)
				)
				(justify mirror)
			)
		)
		(property "License" "Apache-2.0"
			(at 219.622 321.695142 0)
			(layer "B.Fab")
			(hide yes)
			(effects
				(font
					(size 1 1)
					(thickness 0.15)
				)
				(justify mirror)
			)
		)
		(property "MPN" "CC0402KRX5R6BB224"
			(at 219.622 321.695142 0)
			(layer "B.Fab")
			(hide yes)
			(effects
				(font
					(size 1 1)
					(thickness 0.15)
				)
				(justify mirror)
			)
		)
		(property "Manufacturer" "YAGEO"
			(at 219.622 321.695142 0)
			(layer "B.Fab")
			(hide yes)
			(effects
				(font
					(size 1 1)
					(thickness 0.15)
				)
				(justify mirror)
			)
		)
		(property "Public" "False"
			(at 219.622 321.695142 0)
			(layer "B.Fab")
			(hide yes)
			(effects
				(font
					(size 1 1)
					(thickness 0.15)
				)
				(justify mirror)
			)
		)
		(property "Val" "220n"
			(at 219.622 321.695142 0)
			(layer "B.Fab")
			(hide yes)
			(effects
				(font
					(size 1 1)
					(thickness 0.15)
				)
				(justify mirror)
			)
		)
		(property "Voltage" ""
			(at 219.622 321.695142 0)
			(layer "B.Fab")
			(hide yes)
			(effects
				(font
					(size 1 1)
					(thickness 0.15)
				)
				(justify mirror)
			)
		)
		(sheetname "PCIe redriver")
		(sheetfile "pcie_redriver.kicad_sch")
		(attr smd)
		(fp_rect
			(start -0.925 0.47)
			(end 0.925 -0.47)
			(stroke
				(width 0.05)
				(type default)
			)
			(fill no)
			(layer "B.CrtYd")
		)
		(fp_line
			(start 0.504 0.25)
			(end -0.494 0.25)
			(stroke
				(width 0.15)
				(type solid)
			)
			(layer "B.Fab")
		)
		(fp_line
			(start 0.504 -0.248)
			(end 0.504 0.25)
			(stroke
				(width 0.15)
				(type solid)
			)
			(layer "B.Fab")
		)
		(fp_line
			(start -0.494 0.25)
			(end -0.494 -0.248)
			(stroke
				(width 0.15)
				(type solid)
			)
			(layer "B.Fab")
		)
		(fp_line
			(start -0.494 -0.248)
			(end 0.504 -0.248)
			(stroke
				(width 0.15)
				(type solid)
			)
			(layer "B.Fab")
		)
		(pad "1" smd roundrect
			(at -0.48 0 180)
			(size 0.59 0.64)
			(layers "B.Cu" "B.Mask" "B.Paste")
			(roundrect_rratio 0.25)
			(net 961 "/PCIe redriver/PCIe_{O}_C.TX2+")
			(pintype "passive")
			(teardrops
				(best_length_ratio 0.2)
				(max_length 1)
				(best_width_ratio 0.9)
				(max_width 2)
				(curved_edges yes)
				(filter_ratio 0.9)
				(enabled yes)
				(allow_two_segments yes)
				(prefer_zone_connections yes)
			)
		)
		(pad "2" smd roundrect
			(at 0.48 0 180)
			(size 0.59 0.64)
			(layers "B.Cu" "B.Mask" "B.Paste")
			(roundrect_rratio 0.25)
			(net 104 "/OCuLink/PCIe_{x4}.TX2+")
			(pintype "passive")
			(teardrops
				(best_length_ratio 0.2)
				(max_length 1)
				(best_width_ratio 0.9)
				(max_width 2)
				(curved_edges yes)
				(filter_ratio 0.9)
				(enabled yes)
				(allow_two_segments yes)
				(prefer_zone_connections yes)
			)
		)
	)
	(footprint "antmicro-footprints:SC70-3"
		(layer "B.Cu")
		(at 100.75 121.96)
		(property "Reference" "D6"
			(at -1.45 0.75 90)
			(layer "B.SilkS")
			(effects
				(font
					(size 0.7 0.7)
					(thickness 0.15)
				)
				(justify right bottom mirror)
			)
		)
		(property "Value" "TPD2E2U06_SC70"
			(at 0 -2.3 0)
			(layer "B.Fab")
			(effects
				(font
					(size 0.7 0.7)
					(thickness 0.15)
				)
				(justify right bottom mirror)
			)
		)
		(property "Datasheet" "https://www.ti.com/lit/ds/symlink/tpd2e2u06.pdf?ts=1706006131823&ref_url=https%253A%252F%252Fwww.ti.com%252Finterface%252Fdiodes%252Fesd-protection-diodes%252Fproducts.html"
			(at 0 0 0)
			(layer "F.Fab")
			(hide yes)
			(effects
				(font
					(size 1.27 1.27)
					(thickness 0.15)
				)
			)
		)
		(property "Author" "Antmicro"
			(at 0 0 0)
			(layer "B.Fab")
			(hide yes)
			(effects
				(font
					(size 1 1)
					(thickness 0.15)
				)
				(justify mirror)
			)
		)
		(property "License" "Apache-2.0"
			(at 0 0 0)
			(layer "B.Fab")
			(hide yes)
			(effects
				(font
					(size 1 1)
					(thickness 0.15)
				)
				(justify mirror)
			)
		)
		(property "MPN" "TPD2E2U06DCKR"
			(at 0 0 0)
			(layer "B.Fab")
			(hide yes)
			(effects
				(font
					(size 1 1)
					(thickness 0.15)
				)
				(justify mirror)
			)
		)
		(property "Manufacturer" "Texas Instruments"
			(at 0 0 0)
			(layer "B.Fab")
			(hide yes)
			(effects
				(font
					(size 1 1)
					(thickness 0.15)
				)
				(justify mirror)
			)
		)
		(sheetname "Com Express 7 MGMT")
		(sheetfile "com_express_7_mgmt.kicad_sch")
		(attr smd)
		(fp_line
			(start 0.627 -1.001)
			(end -0.3 -1)
			(stroke
				(width 0.15)
				(type solid)
			)
			(layer "B.SilkS")
		)
		(fp_line
			(start 0.627 -1.001)
			(end 0.627 -0.6)
			(stroke
				(width 0.15)
				(type solid)
			)
			(layer "B.SilkS")
		)
		(fp_line
			(start 0.627 0.999)
			(end -0.3 1)
			(stroke
				(width 0.15)
				(type solid)
			)
			(layer "B.SilkS")
		)
		(fp_line
			(start 0.627 0.999)
			(end 0.627 0.6)
			(stroke
				(width 0.15)
				(type solid)
			)
			(layer "B.SilkS")
		)
		(fp_line
			(start -1.4 -1)
			(end -0.9 -1)
			(stroke
				(width 0.05)
				(type solid)
			)
			(layer "B.CrtYd")
		)
		(fp_line
			(start -1.4 1)
			(end -1.4 -1)
			(stroke
				(width 0.05)
				(type solid)
			)
			(layer "B.CrtYd")
		)
		(fp_line
			(start -1.4 1)
			(end -0.9 1)
			(stroke
				(width 0.05)
				(type solid)
			)
			(layer "B.CrtYd")
		)
		(fp_line
			(start -0.9 -1.3)
			(end 0.9 -1.3)
			(stroke
				(width 0.05)
				(type solid)
			)
			(layer "B.CrtYd")
		)
		(fp_line
			(start -0.9 -1)
			(end -0.9 -1.3)
			(stroke
				(width 0.05)
				(type solid)
			)
			(layer "B.CrtYd")
		)
		(fp_line
			(start -0.9 1)
			(end -0.9 1.3)
			(stroke
				(width 0.05)
				(type solid)
			)
			(layer "B.CrtYd")
		)
		(fp_line
			(start 0.9 -1.3)
			(end 0.9 -0.4)
			(stroke
				(width 0.05)
				(type solid)
			)
			(layer "B.CrtYd")
		)
		(fp_line
			(start 0.9 -0.4)
			(end 1.4 -0.4)
			(stroke
				(width 0.05)
				(type solid)
			)
			(layer "B.CrtYd")
		)
		(fp_line
			(start 0.9 0.4)
			(end 0.9 1.3)
			(stroke
				(width 0.05)
				(type solid)
			)
			(layer "B.CrtYd")
		)
		(fp_line
			(start 0.9 1.3)
			(end -0.9 1.3)
			(stroke
				(width 0.05)
				(type solid)
			)
			(layer "B.CrtYd")
		)
		(fp_line
			(start 1.4 -0.4)
			(end 1.4 0.4)
			(stroke
				(width 0.05)
				(type solid)
			)
			(layer "B.CrtYd")
		)
		(fp_line
			(start 1.4 0.4)
			(end 0.9 0.4)
			(stroke
				(width 0.05)
				(type solid)
			)
			(layer "B.CrtYd")
		)
		(fp_rect
			(start -0.623 0.999)
			(end 0.627 -1.001)
			(stroke
				(width 0.15)
				(type solid)
			)
			(fill no)
			(layer "B.Fab")
		)
		(pad "1" smd rect
			(at -1.051 0.65 270)
			(size 0.6 0.6)
			(layers "B.Cu" "B.Mask" "B.Paste")
			(net 928 "unconnected-(D6-Pad1)")
			(pinfunction "1")
			(pintype "passive+no_connect")
			(teardrops
				(best_length_ratio 0.2)
				(max_length 1)
				(best_width_ratio 0.9)
				(max_width 2)
				(curved_edges yes)
				(filter_ratio 0.9)
				(enabled yes)
				(allow_two_segments yes)
				(prefer_zone_connections yes)
			)
		)
		(pad "2" smd rect
			(at -1.051 -0.65 270)
			(size 0.6 0.6)
			(layers "B.Cu" "B.Mask" "B.Paste")
			(net 84 "/Com Express 7 MGMT/PWRBTN")
			(pinfunction "2")
			(pintype "passive")
			(teardrops
				(best_length_ratio 0.2)
				(max_length 1)
				(best_width_ratio 0.9)
				(max_width 2)
				(curved_edges yes)
				(filter_ratio 0.9)
				(enabled yes)
				(allow_two_segments yes)
				(prefer_zone_connections yes)
			)
		)
		(pad "3" smd rect
			(at 1.05 0 270)
			(size 0.6 0.6)
			(layers "B.Cu" "B.Mask" "B.Paste")
			(net 1 "GND")
			(pinfunction "3")
			(pintype "passive")
			(teardrops
				(best_length_ratio 0.2)
				(max_length 1)
				(best_width_ratio 0.9)
				(max_width 2)
				(curved_edges yes)
				(filter_ratio 0.9)
				(enabled yes)
				(allow_two_segments yes)
				(prefer_zone_connections yes)
			)
		)
	)
	(footprint "antmicro-footprints:TP_SMD_0.75mm"
		(layer "B.Cu")
		(at 189.1 164.25 -90)
		(property "Reference" "TP40"
			(at -0.35 3.3 0)
			(layer "B.SilkS")
			(effects
				(font
					(size 0.7 0.7)
					(thickness 0.15)
				)
				(justify right top mirror)
			)
		)
		(property "Value" "TP_0.75mm_SMD"
			(at 3.225 -53.865 90)
			(layer "B.Fab")
			(hide yes)
			(effects
				(font
					(size 0.7 0.7)
					(thickness 0.15)
				)
				(justify left bottom mirror)
			)
		)
		(property "Author" "Antmicro"
			(at 435.1 311.62 90)
			(layer "B.Fab")
			(hide yes)
			(effects
				(font
					(size 1 1)
					(thickness 0.15)
				)
				(justify mirror)
			)
		)
		(property "License" "Apache-2.0"
			(at 435.1 311.62 90)
			(layer "B.Fab")
			(hide yes)
			(effects
				(font
					(size 1 1)
					(thickness 0.15)
				)
				(justify mirror)
			)
		)
		(property "MPN" ""
			(at 435.1 311.62 90)
			(layer "B.Fab")
			(hide yes)
			(effects
				(font
					(size 1 1)
					(thickness 0.15)
				)
				(justify mirror)
			)
		)
		(property "Manufacturer" ""
			(at 435.1 311.62 90)
			(layer "B.Fab")
			(hide yes)
			(effects
				(font
					(size 1 1)
					(thickness 0.15)
				)
				(justify mirror)
			)
		)
		(property "Public" "False"
			(at 435.1 311.62 90)
			(layer "B.Fab")
			(hide yes)
			(effects
				(font
					(size 1 1)
					(thickness 0.15)
				)
				(justify mirror)
			)
		)
		(sheetname "Com Express 7 MGMT")
		(sheetfile "com_express_7_mgmt.kicad_sch")
		(attr exclude_from_pos_files exclude_from_bom)
		(fp_circle
			(center 0 0)
			(end 0.475 0)
			(stroke
				(width 0.05)
				(type default)
			)
			(fill no)
			(layer "B.CrtYd")
		)
		(pad "1" smd circle
			(at 0 0 270)
			(size 0.75 0.75)
			(layers "B.Cu" "B.Mask")
			(net 366 "Net-(J12D-WDT)")
			(pinfunction "1")
			(pintype "passive")
			(teardrops
				(best_length_ratio 0.4)
				(max_length 1)
				(best_width_ratio 0.9)
				(max_width 2)
				(curved_edges yes)
				(filter_ratio 0.9)
				(enabled yes)
				(allow_two_segments yes)
				(prefer_zone_connections yes)
			)
		)
	)
	(footprint "antmicro-footprints:C_0402_1005Metric"
		(layer "B.Cu")
		(at 196.425233 139.130616 135)
		(descr "Capacitor SMD 0402")
		(tags "capacitor SMD 0402")
		(property "Reference" "C124"
			(at -2.768935 -0.026347 135)
			(layer "B.SilkS")
			(effects
				(font
					(size 0.7 0.7)
					(thickness 0.15)
				)
				(justify right bottom mirror)
			)
		)
		(property "Value" "C_220n_0402"
			(at -1.022927 -2.155213 135)
			(layer "B.Fab")
			(effects
				(font
					(size 0.7 0.7)
					(thickness 0.15)
				)
				(justify right bottom mirror)
			)
		)
		(property "Datasheet" "https://www.yageo.com/en/Chart/Download/pdf/CC0402KRX5R6BB224"
			(at 0 0 135)
			(layer "F.Fab")
			(hide yes)
			(effects
				(font
					(size 1.27 1.27)
					(thickness 0.15)
				)
			)
		)
		(property "Author" "Antmicro"
			(at 339.710001 -39.09 45)
			(layer "B.Fab")
			(hide yes)
			(effects
				(font
					(size 1 1)
					(thickness 0.15)
				)
				(justify mirror)
			)
		)
		(property "Dielectric" ""
			(at 339.710001 -39.09 45)
			(layer "B.Fab")
			(hide yes)
			(effects
				(font
					(size 1 1)
					(thickness 0.15)
				)
				(justify mirror)
			)
		)
		(property "License" "Apache-2.0"
			(at 339.710001 -39.09 45)
			(layer "B.Fab")
			(hide yes)
			(effects
				(font
					(size 1 1)
					(thickness 0.15)
				)
				(justify mirror)
			)
		)
		(property "MPN" "CC0402KRX5R6BB224"
			(at 339.710001 -39.09 45)
			(layer "B.Fab")
			(hide yes)
			(effects
				(font
					(size 1 1)
					(thickness 0.15)
				)
				(justify mirror)
			)
		)
		(property "Manufacturer" "YAGEO"
			(at 339.710001 -39.09 45)
			(layer "B.Fab")
			(hide yes)
			(effects
				(font
					(size 1 1)
					(thickness 0.15)
				)
				(justify mirror)
			)
		)
		(property "Public" "False"
			(at 339.710001 -39.09 45)
			(layer "B.Fab")
			(hide yes)
			(effects
				(font
					(size 1 1)
					(thickness 0.15)
				)
				(justify mirror)
			)
		)
		(property "Val" "220n"
			(at 339.710001 -39.09 45)
			(layer "B.Fab")
			(hide yes)
			(effects
				(font
					(size 1 1)
					(thickness 0.15)
				)
				(justify mirror)
			)
		)
		(property "Voltage" ""
			(at 339.710001 -39.09 45)
			(layer "B.Fab")
			(hide yes)
			(effects
				(font
					(size 1 1)
					(thickness 0.15)
				)
				(justify mirror)
			)
		)
		(sheetname "PCIe redriver")
		(sheetfile "pcie_redriver.kicad_sch")
		(attr smd)
		(fp_poly
			(pts
				(xy -0.925 0.47) (xy 0.925 0.47) (xy 0.925 -0.47) (xy -0.925 -0.47)
			)
			(stroke
				(width 0.05)
				(type default)
			)
			(fill no)
			(layer "B.CrtYd")
		)
		(fp_line
			(start 0.504 -0.248)
			(end 0.504 0.25)
			(stroke
				(width 0.15)
				(type solid)
			)
			(layer "B.Fab")
		)
		(fp_line
			(start 0.504 0.25)
			(end -0.494 0.25)
			(stroke
				(width 0.15)
				(type solid)
			)
			(layer "B.Fab")
		)
		(fp_line
			(start -0.494 -0.248)
			(end 0.504 -0.248)
			(stroke
				(width 0.15)
				(type solid)
			)
			(layer "B.Fab")
		)
		(fp_line
			(start -0.494 0.25)
			(end -0.494 -0.248)
			(stroke
				(width 0.15)
				(type solid)
			)
			(layer "B.Fab")
		)
		(pad "1" smd roundrect
			(at -0.48 0 135)
			(size 0.59 0.64)
			(layers "B.Cu" "B.Mask" "B.Paste")
			(roundrect_rratio 0.25)
			(net 213 "/Com Express 7 Interfaces/PCIe_{B1x4}.RX2-")
			(pintype "passive")
			(teardrops
				(best_length_ratio 0.2)
				(max_length 1)
				(best_width_ratio 0.9)
				(max_width 2)
				(curved_edges yes)
				(filter_ratio 0.9)
				(enabled yes)
				(allow_two_segments yes)
				(prefer_zone_connections yes)
			)
		)
		(pad "2" smd roundrect
			(at 0.48 0 135)
			(size 0.59 0.64)
			(layers "B.Cu" "B.Mask" "B.Paste")
			(roundrect_rratio 0.25)
			(net 105 "/PCIe redriver/PCIe_{I}_C.RX2-")
			(pintype "passive")
			(teardrops
				(best_length_ratio 0.2)
				(max_length 1)
				(best_width_ratio 0.9)
				(max_width 2)
				(curved_edges yes)
				(filter_ratio 0.9)
				(enabled yes)
				(allow_two_segments yes)
				(prefer_zone_connections yes)
			)
		)
	)
	(footprint "antmicro-footprints:R_0402_1005Metric"
		(layer "B.Cu")
		(at 100.1 85.46 180)
		(descr "Resistor SMD 0402")
		(tags "resistor SMD 0402")
		(property "Reference" "R67"
			(at -1.05 -1.35 0)
			(layer "B.SilkS")
			(effects
				(font
					(size 0.7 0.7)
					(thickness 0.15)
				)
				(justify left bottom mirror)
			)
		)
		(property "Value" "R_5k1_0402"
			(at -1.011843 -1.772047 0)
			(layer "B.Fab")
			(effects
				(font
					(size 0.7 0.7)
					(thickness 0.15)
				)
				(justify left bottom mirror)
			)
		)
		(property "Datasheet" "https://www.bourns.com/docs/product-datasheets/cr.pdf"
			(at 0 0 180)
			(layer "F.Fab")
			(hide yes)
			(effects
				(font
					(size 1.27 1.27)
					(thickness 0.15)
				)
			)
		)
		(property "Author" "Antmicro"
			(at 200 170.92 0)
			(layer "B.Fab")
			(hide yes)
			(effects
				(font
					(size 1 1)
					(thickness 0.15)
				)
				(justify mirror)
			)
		)
		(property "License" "Apache-2.0"
			(at 200 170.92 0)
			(layer "B.Fab")
			(hide yes)
			(effects
				(font
					(size 1 1)
					(thickness 0.15)
				)
				(justify mirror)
			)
		)
		(property "MPN" "CR0402-FX-5101GLF"
			(at 200 170.92 0)
			(layer "B.Fab")
			(hide yes)
			(effects
				(font
					(size 1 1)
					(thickness 0.15)
				)
				(justify mirror)
			)
		)
		(property "Manufacturer" "Bourns"
			(at 200 170.92 0)
			(layer "B.Fab")
			(hide yes)
			(effects
				(font
					(size 1 1)
					(thickness 0.15)
				)
				(justify mirror)
			)
		)
		(property "Public" "False"
			(at 200 170.92 0)
			(layer "B.Fab")
			(hide yes)
			(effects
				(font
					(size 1 1)
					(thickness 0.15)
				)
				(justify mirror)
			)
		)
		(property "Tolerance" "1%"
			(at 200 170.92 0)
			(layer "B.Fab")
			(hide yes)
			(effects
				(font
					(size 1 1)
					(thickness 0.15)
				)
				(justify mirror)
			)
		)
		(property "Val" "5k1"
			(at 200 170.92 0)
			(layer "B.Fab")
			(hide yes)
			(effects
				(font
					(size 1 1)
					(thickness 0.15)
				)
				(justify mirror)
			)
		)
		(sheetname "USB-C console")
		(sheetfile "usb-c_console.kicad_sch")
		(attr smd)
		(fp_rect
			(start -0.925 0.47)
			(end 0.925 -0.47)
			(stroke
				(width 0.05)
				(type default)
			)
			(fill no)
			(layer "B.CrtYd")
		)
		(fp_rect
			(start -0.5 0.25)
			(end 0.5 -0.25)
			(stroke
				(width 0.15)
				(type solid)
			)
			(fill no)
			(layer "B.Fab")
		)
		(pad "1" smd roundrect
			(at -0.48 0 180)
			(size 0.59 0.64)
			(layers "B.Cu" "B.Mask" "B.Paste")
			(roundrect_rratio 0.25)
			(net 176 "Net-(J3-CC_{1})")
			(pintype "passive")
			(teardrops
				(best_length_ratio 0.2)
				(max_length 1)
				(best_width_ratio 0.9)
				(max_width 2)
				(curved_edges yes)
				(filter_ratio 0.9)
				(enabled yes)
				(allow_two_segments yes)
				(prefer_zone_connections yes)
			)
		)
		(pad "2" smd roundrect
			(at 0.48 0 180)
			(size 0.59 0.64)
			(layers "B.Cu" "B.Mask" "B.Paste")
			(roundrect_rratio 0.25)
			(net 1 "GND")
			(pintype "passive")
			(teardrops
				(best_length_ratio 0.2)
				(max_length 1)
				(best_width_ratio 0.9)
				(max_width 2)
				(curved_edges yes)
				(filter_ratio 0.9)
				(enabled yes)
				(allow_two_segments yes)
				(prefer_zone_connections yes)
			)
		)
	)
	(footprint "antmicro-footprints:R_0402_1005Metric"
		(layer "B.Cu")
		(at 121.7 162.56)
		(descr "Resistor SMD 0402")
		(tags "resistor SMD 0402")
		(property "Reference" "R78"
			(at 0.85 0.45 0)
			(layer "B.SilkS")
			(effects
				(font
					(size 0.7 0.7)
					(thickness 0.15)
				)
				(justify right bottom mirror)
			)
		)
		(property "Value" "R_10k_0402"
			(at -1.011843 -1.772047 0)
			(layer "B.Fab")
			(effects
				(font
					(size 0.7 0.7)
					(thickness 0.15)
				)
				(justify right bottom mirror)
			)
		)
		(property "Datasheet" "https://www.bourns.com/docs/product-datasheets/cr.pdf"
			(at 0 0 0)
			(layer "F.Fab")
			(hide yes)
			(effects
				(font
					(size 1.27 1.27)
					(thickness 0.15)
				)
			)
		)
		(property "Author" "Antmicro"
			(at 0 0 0)
			(layer "B.Fab")
			(hide yes)
			(effects
				(font
					(size 1 1)
					(thickness 0.15)
				)
				(justify mirror)
			)
		)
		(property "License" "Apache-2.0"
			(at 0 0 0)
			(layer "B.Fab")
			(hide yes)
			(effects
				(font
					(size 1 1)
					(thickness 0.15)
				)
				(justify mirror)
			)
		)
		(property "MPN" "CR0402-FX-1002GLF"
			(at 0 0 0)
			(layer "B.Fab")
			(hide yes)
			(effects
				(font
					(size 1 1)
					(thickness 0.15)
				)
				(justify mirror)
			)
		)
		(property "Manufacturer" "Bourns"
			(at 0 0 0)
			(layer "B.Fab")
			(hide yes)
			(effects
				(font
					(size 1 1)
					(thickness 0.15)
				)
				(justify mirror)
			)
		)
		(property "Public" "False"
			(at 0 0 0)
			(layer "B.Fab")
			(hide yes)
			(effects
				(font
					(size 1 1)
					(thickness 0.15)
				)
				(justify mirror)
			)
		)
		(property "Tolerance" "1%"
			(at 0 0 0)
			(layer "B.Fab")
			(hide yes)
			(effects
				(font
					(size 1 1)
					(thickness 0.15)
				)
				(justify mirror)
			)
		)
		(property "Val" "10k"
			(at 0 0 0)
			(layer "B.Fab")
			(hide yes)
			(effects
				(font
					(size 1 1)
					(thickness 0.15)
				)
				(justify mirror)
			)
		)
		(sheetname "OCuLink")
		(sheetfile "oculink.kicad_sch")
		(attr smd dnp)
		(fp_rect
			(start -0.925 0.47)
			(end 0.925 -0.47)
			(stroke
				(width 0.05)
				(type default)
			)
			(fill no)
			(layer "B.CrtYd")
		)
		(fp_rect
			(start -0.5 0.25)
			(end 0.5 -0.25)
			(stroke
				(width 0.15)
				(type solid)
			)
			(fill no)
			(layer "B.Fab")
		)
		(pad "1" smd roundrect
			(at -0.48 0)
			(size 0.59 0.64)
			(layers "B.Cu" "B.Mask" "B.Paste")
			(roundrect_rratio 0.25)
			(net 200 "/OCuLink/~{PERST_D0}")
			(pintype "passive")
			(teardrops
				(best_length_ratio 0.2)
				(max_length 1)
				(best_width_ratio 0.9)
				(max_width 2)
				(curved_edges yes)
				(filter_ratio 0.9)
				(enabled yes)
				(allow_two_segments yes)
				(prefer_zone_connections yes)
			)
		)
		(pad "2" smd roundrect
			(at 0.48 0)
			(size 0.59 0.64)
			(layers "B.Cu" "B.Mask" "B.Paste")
			(roundrect_rratio 0.25)
			(net 2 "+3V3")
			(pintype "passive")
			(teardrops
				(best_length_ratio 0.2)
				(max_length 1)
				(best_width_ratio 0.9)
				(max_width 2)
				(curved_edges yes)
				(filter_ratio 0.9)
				(enabled yes)
				(allow_two_segments yes)
				(prefer_zone_connections yes)
			)
		)
	)
	(footprint "antmicro-footprints:C_0402_1005Metric"
		(layer "B.Cu")
		(at 311.274999 121.96 -90)
		(descr "Capacitor SMD 0402")
		(tags "capacitor SMD 0402")
		(property "Reference" "C44"
			(at 0.8 -0.425001 90)
			(layer "B.SilkS")
			(effects
				(font
					(size 0.7 0.7)
					(thickness 0.15)
				)
				(justify left bottom mirror)
			)
		)
		(property "Value" "C_1u_0402"
			(at -1.022927 -2.155213 90)
			(layer "B.Fab")
			(effects
				(font
					(size 0.7 0.7)
					(thickness 0.15)
				)
				(justify left bottom mirror)
			)
		)
		(property "Datasheet" "https://product.tdk.com/en/search/capacitor/ceramic/mlcc/info?part_no=C1005X6S1A105K050BC"
			(at 0 0 270)
			(layer "F.Fab")
			(hide yes)
			(effects
				(font
					(size 1.27 1.27)
					(thickness 0.15)
				)
			)
		)
		(property "Author" "Antmicro"
			(at 189.314999 433.234999 0)
			(layer "B.Fab")
			(hide yes)
			(effects
				(font
					(size 1 1)
					(thickness 0.15)
				)
				(justify mirror)
			)
		)
		(property "Dielectric" ""
			(at 189.314999 433.234999 0)
			(layer "B.Fab")
			(hide yes)
			(effects
				(font
					(size 1 1)
					(thickness 0.15)
				)
				(justify mirror)
			)
		)
		(property "License" "Apache-2.0"
			(at 189.314999 433.234999 0)
			(layer "B.Fab")
			(hide yes)
			(effects
				(font
					(size 1 1)
					(thickness 0.15)
				)
				(justify mirror)
			)
		)
		(property "MPN" "C1005X6S1A105K050BC"
			(at 189.314999 433.234999 0)
			(layer "B.Fab")
			(hide yes)
			(effects
				(font
					(size 1 1)
					(thickness 0.15)
				)
				(justify mirror)
			)
		)
		(property "Manufacturer" "TDK"
			(at 189.314999 433.234999 0)
			(layer "B.Fab")
			(hide yes)
			(effects
				(font
					(size 1 1)
					(thickness 0.15)
				)
				(justify mirror)
			)
		)
		(property "Public" "False"
			(at 189.314999 433.234999 0)
			(layer "B.Fab")
			(hide yes)
			(effects
				(font
					(size 1 1)
					(thickness 0.15)
				)
				(justify mirror)
			)
		)
		(property "Val" "1u"
			(at 189.314999 433.234999 0)
			(layer "B.Fab")
			(hide yes)
			(effects
				(font
					(size 1 1)
					(thickness 0.15)
				)
				(justify mirror)
			)
		)
		(property "Voltage" ""
			(at 189.314999 433.234999 0)
			(layer "B.Fab")
			(hide yes)
			(effects
				(font
					(size 1 1)
					(thickness 0.15)
				)
				(justify mirror)
			)
		)
		(sheetname "Power")
		(sheetfile "power.kicad_sch")
		(attr smd)
		(fp_rect
			(start -0.925 0.47)
			(end 0.925 -0.47)
			(stroke
				(width 0.05)
				(type default)
			)
			(fill no)
			(layer "B.CrtYd")
		)
		(fp_line
			(start -0.494 0.25)
			(end -0.494 -0.248)
			(stroke
				(width 0.15)
				(type solid)
			)
			(layer "B.Fab")
		)
		(fp_line
			(start 0.504 0.25)
			(end -0.494 0.25)
			(stroke
				(width 0.15)
				(type solid)
			)
			(layer "B.Fab")
		)
		(fp_line
			(start -0.494 -0.248)
			(end 0.504 -0.248)
			(stroke
				(width 0.15)
				(type solid)
			)
			(layer "B.Fab")
		)
		(fp_line
			(start 0.504 -0.248)
			(end 0.504 0.25)
			(stroke
				(width 0.15)
				(type solid)
			)
			(layer "B.Fab")
		)
		(pad "1" smd roundrect
			(at -0.48 0 270)
			(size 0.59 0.64)
			(layers "B.Cu" "B.Mask" "B.Paste")
			(roundrect_rratio 0.25)
			(net 1 "GND")
			(pintype "passive")
			(teardrops
				(best_length_ratio 0.2)
				(max_length 1)
				(best_width_ratio 0.9)
				(max_width 2)
				(curved_edges yes)
				(filter_ratio 0.9)
				(enabled yes)
				(allow_two_segments yes)
				(prefer_zone_connections yes)
			)
		)
		(pad "2" smd roundrect
			(at 0.48 0 270)
			(size 0.59 0.64)
			(layers "B.Cu" "B.Mask" "B.Paste")
			(roundrect_rratio 0.25)
			(net 63 "Net-(U18-V_{CC})")
			(pintype "passive")
			(teardrops
				(best_length_ratio 0.2)
				(max_length 1)
				(best_width_ratio 0.9)
				(max_width 2)
				(curved_edges yes)
				(filter_ratio 0.9)
				(enabled yes)
				(allow_two_segments yes)
				(prefer_zone_connections yes)
			)
		)
	)
	(footprint "antmicro-footprints:R_0402_1005Metric"
		(layer "B.Cu")
		(at 144.25 142.06)
		(descr "Resistor SMD 0402")
		(tags "resistor SMD 0402")
		(property "Reference" "R269"
			(at -1.45 5.4 0)
			(layer "B.SilkS")
			(effects
				(font
					(size 0.7 0.7)
					(thickness 0.15)
				)
				(justify right bottom mirror)
			)
		)
		(property "Value" "R_10k_0402"
			(at -1.011843 -1.772047 0)
			(layer "B.Fab")
			(effects
				(font
					(size 0.7 0.7)
					(thickness 0.15)
				)
				(justify right bottom mirror)
			)
		)
		(property "Datasheet" "https://www.bourns.com/docs/product-datasheets/cr.pdf"
			(at 0 0 0)
			(layer "F.Fab")
			(hide yes)
			(effects
				(font
					(size 1.27 1.27)
					(thickness 0.15)
				)
			)
		)
		(property "Author" "Antmicro"
			(at 0 0 0)
			(layer "B.Fab")
			(hide yes)
			(effects
				(font
					(size 1 1)
					(thickness 0.15)
				)
				(justify mirror)
			)
		)
		(property "License" "Apache-2.0"
			(at 0 0 0)
			(layer "B.Fab")
			(hide yes)
			(effects
				(font
					(size 1 1)
					(thickness 0.15)
				)
				(justify mirror)
			)
		)
		(property "MPN" "CR0402-FX-1002GLF"
			(at 0 0 0)
			(layer "B.Fab")
			(hide yes)
			(effects
				(font
					(size 1 1)
					(thickness 0.15)
				)
				(justify mirror)
			)
		)
		(property "Manufacturer" "Bourns"
			(at 0 0 0)
			(layer "B.Fab")
			(hide yes)
			(effects
				(font
					(size 1 1)
					(thickness 0.15)
				)
				(justify mirror)
			)
		)
		(property "Public" "False"
			(at 0 0 0)
			(layer "B.Fab")
			(hide yes)
			(effects
				(font
					(size 1 1)
					(thickness 0.15)
				)
				(justify mirror)
			)
		)
		(property "Tolerance" "1%"
			(at 0 0 0)
			(layer "B.Fab")
			(hide yes)
			(effects
				(font
					(size 1 1)
					(thickness 0.15)
				)
				(justify mirror)
			)
		)
		(property "Val" "10k"
			(at 0 0 0)
			(layer "B.Fab")
			(hide yes)
			(effects
				(font
					(size 1 1)
					(thickness 0.15)
				)
				(justify mirror)
			)
		)
		(sheetname "KR to SFI #1")
		(sheetfile "kr_sfi.kicad_sch")
		(attr smd)
		(fp_rect
			(start -0.925 0.47)
			(end 0.925 -0.47)
			(stroke
				(width 0.05)
				(type default)
			)
			(fill no)
			(layer "B.CrtYd")
		)
		(fp_rect
			(start -0.5 0.25)
			(end 0.5 -0.25)
			(stroke
				(width 0.15)
				(type solid)
			)
			(fill no)
			(layer "B.Fab")
		)
		(pad "1" smd roundrect
			(at -0.48 0)
			(size 0.59 0.64)
			(layers "B.Cu" "B.Mask" "B.Paste")
			(roundrect_rratio 0.25)
			(net 1 "GND")
			(pintype "passive")
			(teardrops
				(best_length_ratio 0.2)
				(max_length 1)
				(best_width_ratio 0.9)
				(max_width 2)
				(curved_edges yes)
				(filter_ratio 0.9)
				(enabled yes)
				(allow_two_segments yes)
				(prefer_zone_connections yes)
			)
		)
		(pad "2" smd roundrect
			(at 0.48 0)
			(size 0.59 0.64)
			(layers "B.Cu" "B.Mask" "B.Paste")
			(roundrect_rratio 0.25)
			(net 662 "Net-(U43C-MODE_{SEL})")
			(pintype "passive")
			(teardrops
				(best_length_ratio 0.2)
				(max_length 1)
				(best_width_ratio 0.9)
				(max_width 2)
				(curved_edges yes)
				(filter_ratio 0.9)
				(enabled yes)
				(allow_two_segments yes)
				(prefer_zone_connections yes)
			)
		)
	)
	(footprint "antmicro-footprints:SOT-23-3"
		(layer "B.Cu")
		(at 306.525 101.76 -90)
		(property "Reference" "D36"
			(at -1.8 1.8 90)
			(layer "B.SilkS")
			(effects
				(font
					(size 0.7 0.7)
					(thickness 0.15)
				)
				(justify left bottom mirror)
			)
		)
		(property "Value" "BAT54C"
			(at -1.9 -2.7 90)
			(layer "B.Fab")
			(effects
				(font
					(size 0.7 0.7)
					(thickness 0.15)
				)
				(justify left bottom mirror)
			)
		)
		(property "Datasheet" "https://diotec.com/request/datasheet/bat54.pdf"
			(at 0 0 90)
			(layer "B.Fab")
			(hide yes)
			(effects
				(font
					(size 1.27 1.27)
					(thickness 0.15)
				)
				(justify mirror)
			)
		)
		(property "MPN" "BAT54C"
			(at 0 0 90)
			(unlocked yes)
			(layer "B.Fab")
			(hide yes)
			(effects
				(font
					(size 1 1)
					(thickness 0.15)
				)
				(justify mirror)
			)
		)
		(property "Manufacturer" "Diotec Semiconductor"
			(at 0 0 90)
			(unlocked yes)
			(layer "B.Fab")
			(hide yes)
			(effects
				(font
					(size 1 1)
					(thickness 0.15)
				)
				(justify mirror)
			)
		)
		(property "Author" "Antmicro"
			(at 0 0 90)
			(unlocked yes)
			(layer "B.Fab")
			(hide yes)
			(effects
				(font
					(size 1 1)
					(thickness 0.15)
				)
				(justify mirror)
			)
		)
		(property "License" "Apache-2.0"
			(at 0 0 90)
			(unlocked yes)
			(layer "B.Fab")
			(hide yes)
			(effects
				(font
					(size 1 1)
					(thickness 0.15)
				)
				(justify mirror)
			)
		)
		(sheetname "Power")
		(sheetfile "power.kicad_sch")
		(attr smd)
		(fp_line
			(start -0.7 1.5)
			(end 0.7 1.5)
			(stroke
				(width 0.15)
				(type solid)
			)
			(layer "B.SilkS")
		)
		(fp_line
			(start -0.7 1.5)
			(end -0.85 1.35)
			(stroke
				(width 0.15)
				(type solid)
			)
			(layer "B.SilkS")
		)
		(fp_line
			(start 0.7 1.5)
			(end 0.7 0.4)
			(stroke
				(width 0.15)
				(type solid)
			)
			(layer "B.SilkS")
		)
		(fp_line
			(start -0.85 1.35)
			(end -1.45 1.35)
			(stroke
				(width 0.15)
				(type solid)
			)
			(layer "B.SilkS")
		)
		(fp_line
			(start -0.7 -1.35)
			(end -0.7 -1.5)
			(stroke
				(width 0.15)
				(type solid)
			)
			(layer "B.SilkS")
		)
		(fp_line
			(start -0.7 -1.5)
			(end 0.7 -1.5)
			(stroke
				(width 0.15)
				(type solid)
			)
			(layer "B.SilkS")
		)
		(fp_line
			(start 0.7 -1.5)
			(end 0.7 -0.4)
			(stroke
				(width 0.15)
				(type solid)
			)
			(layer "B.SilkS")
		)
		(fp_line
			(start 0.825 1.6)
			(end -0.9 1.6)
			(stroke
				(width 0.05)
				(type solid)
			)
			(layer "B.CrtYd")
		)
		(fp_line
			(start -1.75 1.4)
			(end -0.9 1.4)
			(stroke
				(width 0.05)
				(type solid)
			)
			(layer "B.CrtYd")
		)
		(fp_line
			(start -1.75 1.4)
			(end -1.75 0.5)
			(stroke
				(width 0.05)
				(type solid)
			)
			(layer "B.CrtYd")
		)
		(fp_line
			(start -0.9 1.4)
			(end -0.9 1.6)
			(stroke
				(width 0.05)
				(type solid)
			)
			(layer "B.CrtYd")
		)
		(fp_line
			(start -1.75 0.5)
			(end -0.85 0.5)
			(stroke
				(width 0.05)
				(type solid)
			)
			(layer "B.CrtYd")
		)
		(fp_line
			(start -0.85 0.5)
			(end -0.85 -0.5)
			(stroke
				(width 0.05)
				(type solid)
			)
			(layer "B.CrtYd")
		)
		(fp_line
			(start 0.825 0.45)
			(end 0.825 1.6)
			(stroke
				(width 0.05)
				(type solid)
			)
			(layer "B.CrtYd")
		)
		(fp_line
			(start 1.75 0.45)
			(end 0.825 0.45)
			(stroke
				(width 0.05)
				(type solid)
			)
			(layer "B.CrtYd")
		)
		(fp_line
			(start 0.85 -0.45)
			(end 1.75 -0.45)
			(stroke
				(width 0.05)
				(type solid)
			)
			(layer "B.CrtYd")
		)
		(fp_line
			(start 1.75 -0.45)
			(end 1.75 0.45)
			(stroke
				(width 0.05)
				(type solid)
			)
			(layer "B.CrtYd")
		)
		(fp_line
			(start -1.75 -0.5)
			(end -1.75 -1.4)
			(stroke
				(width 0.05)
				(type solid)
			)
			(layer "B.CrtYd")
		)
		(fp_line
			(start -0.85 -0.5)
			(end -1.75 -0.5)
			(stroke
				(width 0.05)
				(type solid)
			)
			(layer "B.CrtYd")
		)
		(fp_line
			(start -1.75 -1.4)
			(end -0.85 -1.4)
			(stroke
				(width 0.05)
				(type solid)
			)
			(layer "B.CrtYd")
		)
		(fp_line
			(start -0.85 -1.4)
			(end -0.85 -1.65)
			(stroke
				(width 0.05)
				(type solid)
			)
			(layer "B.CrtYd")
		)
		(fp_line
			(start -0.85 -1.65)
			(end 0.85 -1.65)
			(stroke
				(width 0.05)
				(type solid)
			)
			(layer "B.CrtYd")
		)
		(fp_line
			(start 0.85 -1.65)
			(end 0.85 -0.45)
			(stroke
				(width 0.05)
				(type solid)
			)
			(layer "B.CrtYd")
		)
		(fp_line
			(start 0.688 1.526)
			(end -0.437 1.526)
			(stroke
				(width 0.15)
				(type solid)
			)
			(layer "B.Fab")
		)
		(fp_line
			(start 0.688 1.52)
			(end 0.688 -1.519)
			(stroke
				(width 0.15)
				(type solid)
			)
			(layer "B.Fab")
		)
		(fp_line
			(start -0.712 1.325)
			(end -0.437 1.526)
			(stroke
				(width 0.15)
				(type solid)
			)
			(layer "B.Fab")
		)
		(fp_line
			(start 0.688 -1.519)
			(end -0.712 -1.519)
			(stroke
				(width 0.15)
				(type solid)
			)
			(layer "B.Fab")
		)
		(fp_line
			(start -0.712 -1.523)
			(end -0.712 1.325)
			(stroke
				(width 0.15)
				(type solid)
			)
			(layer "B.Fab")
		)
		(pad "1" smd roundrect
			(at -1.1 0.951 270)
			(size 1 0.6)
			(layers "B.Cu" "B.Mask" "B.Paste")
			(roundrect_rratio 0.15)
			(net 574 "Net-(U19-EN)")
			(pinfunction "1")
			(pintype "passive")
			(teardrops
				(best_length_ratio 0.2)
				(max_length 1)
				(best_width_ratio 0.9)
				(max_width 2)
				(curved_edges yes)
				(filter_ratio 0.9)
				(enabled yes)
				(allow_two_segments yes)
				(prefer_zone_connections yes)
			)
		)
		(pad "2" smd roundrect
			(at -1.1 -0.949 270)
			(size 1 0.6)
			(layers "B.Cu" "B.Mask" "B.Paste")
			(roundrect_rratio 0.15)
			(net 574 "Net-(U19-EN)")
			(pinfunction "2")
			(pintype "passive")
			(teardrops
				(best_length_ratio 0.2)
				(max_length 1)
				(best_width_ratio 0.9)
				(max_width 2)
				(curved_edges yes)
				(filter_ratio 0.9)
				(enabled yes)
				(allow_two_segments yes)
				(prefer_zone_connections yes)
			)
		)
		(pad "3" smd roundrect
			(at 1.1 0.0005 270)
			(size 1 0.6)
			(layers "B.Cu" "B.Mask" "B.Paste")
			(roundrect_rratio 0.15)
			(net 533 "/Com Express 7 MGMT/PSON")
			(pinfunction "3")
			(pintype "passive")
			(teardrops
				(best_length_ratio 0.2)
				(max_length 1)
				(best_width_ratio 0.9)
				(max_width 2)
				(curved_edges yes)
				(filter_ratio 0.9)
				(enabled yes)
				(allow_two_segments yes)
				(prefer_zone_connections yes)
			)
		)
	)
	(footprint "antmicro-footprints:R_0402_1005Metric"
		(layer "B.Cu")
		(at 123.4 98.86 180)
		(descr "Resistor SMD 0402")
		(tags "resistor SMD 0402")
		(property "Reference" "R2"
			(at -2.4 -0.45 0)
			(layer "B.SilkS")
			(effects
				(font
					(size 0.7 0.7)
					(thickness 0.15)
				)
				(justify left bottom mirror)
			)
		)
		(property "Value" "R_0R_0402"
			(at -1.011843 -1.772047 0)
			(layer "B.Fab")
			(effects
				(font
					(size 0.7 0.7)
					(thickness 0.15)
				)
				(justify left bottom mirror)
			)
		)
		(property "Datasheet" "https://industrial.panasonic.com/cdbs/www-data/pdf/RDA0000/AOA0000C301.pdf"
			(at 0 0 180)
			(layer "F.Fab")
			(hide yes)
			(effects
				(font
					(size 1.27 1.27)
					(thickness 0.15)
				)
			)
		)
		(property "Author" "Antmicro"
			(at 246.8 197.72 0)
			(layer "B.Fab")
			(hide yes)
			(effects
				(font
					(size 1 1)
					(thickness 0.15)
				)
				(justify mirror)
			)
		)
		(property "Current" "1A"
			(at 246.8 197.72 0)
			(layer "B.Fab")
			(hide yes)
			(effects
				(font
					(size 1 1)
					(thickness 0.15)
				)
				(justify mirror)
			)
		)
		(property "License" "Apache-2.0"
			(at 246.8 197.72 0)
			(layer "B.Fab")
			(hide yes)
			(effects
				(font
					(size 1 1)
					(thickness 0.15)
				)
				(justify mirror)
			)
		)
		(property "MPN" "ERJ2GE0R00X"
			(at 246.8 197.72 0)
			(layer "B.Fab")
			(hide yes)
			(effects
				(font
					(size 1 1)
					(thickness 0.15)
				)
				(justify mirror)
			)
		)
		(property "Manufacturer" "Panasonic"
			(at 246.8 197.72 0)
			(layer "B.Fab")
			(hide yes)
			(effects
				(font
					(size 1 1)
					(thickness 0.15)
				)
				(justify mirror)
			)
		)
		(property "Public" "False"
			(at 246.8 197.72 0)
			(layer "B.Fab")
			(hide yes)
			(effects
				(font
					(size 1 1)
					(thickness 0.15)
				)
				(justify mirror)
			)
		)
		(property "Tolerance" ""
			(at 246.8 197.72 0)
			(layer "B.Fab")
			(hide yes)
			(effects
				(font
					(size 1 1)
					(thickness 0.15)
				)
				(justify mirror)
			)
		)
		(property "Val" "0R"
			(at 246.8 197.72 0)
			(layer "B.Fab")
			(hide yes)
			(effects
				(font
					(size 1 1)
					(thickness 0.15)
				)
				(justify mirror)
			)
		)
		(sheetname "2xUSB3.0+RJ45")
		(sheetfile "usb3+rj45.kicad_sch")
		(attr smd dnp)
		(fp_rect
			(start -0.925 0.47)
			(end 0.925 -0.47)
			(stroke
				(width 0.05)
				(type default)
			)
			(fill no)
			(layer "B.CrtYd")
		)
		(fp_rect
			(start -0.5 0.25)
			(end 0.5 -0.25)
			(stroke
				(width 0.15)
				(type solid)
			)
			(fill no)
			(layer "B.Fab")
		)
		(pad "1" smd roundrect
			(at -0.48 0 180)
			(size 0.59 0.64)
			(layers "B.Cu" "B.Mask" "B.Paste")
			(roundrect_rratio 0.25)
			(net 347 "/2xUSB3.0+RJ45/~{GBE0_ACT}")
			(pintype "passive")
			(teardrops
				(best_length_ratio 0.2)
				(max_length 1)
				(best_width_ratio 0.9)
				(max_width 2)
				(curved_edges yes)
				(filter_ratio 0.9)
				(enabled yes)
				(allow_two_segments yes)
				(prefer_zone_connections yes)
			)
		)
		(pad "2" smd roundrect
			(at 0.48 0 180)
			(size 0.59 0.64)
			(layers "B.Cu" "B.Mask" "B.Paste")
			(roundrect_rratio 0.25)
			(net 155 "Net-(J1A-LED_D2)")
			(pintype "passive")
			(teardrops
				(best_length_ratio 0.2)
				(max_length 1)
				(best_width_ratio 0.9)
				(max_width 2)
				(curved_edges yes)
				(filter_ratio 0.9)
				(enabled yes)
				(allow_two_segments yes)
				(prefer_zone_connections yes)
			)
		)
	)
	(footprint "antmicro-footprints:C_0402_1005Metric"
		(layer "B.Cu")
		(at 152.95 132.86)
		(descr "Capacitor SMD 0402")
		(tags "capacitor SMD 0402")
		(property "Reference" "C173"
			(at -1.8 1.4 0)
			(layer "B.SilkS")
			(effects
				(font
					(size 0.7 0.7)
					(thickness 0.15)
				)
				(justify right bottom mirror)
			)
		)
		(property "Value" "C_100n_0402"
			(at -1.022927 -2.155213 0)
			(layer "B.Fab")
			(effects
				(font
					(size 0.7 0.7)
					(thickness 0.15)
				)
				(justify right bottom mirror)
			)
		)
		(property "Datasheet" "https://www.murata.com/products/productdetail?partno=GRM155R61H104KE14%23"
			(at 0 0 0)
			(layer "F.Fab")
			(hide yes)
			(effects
				(font
					(size 1.27 1.27)
					(thickness 0.15)
				)
			)
		)
		(property "Author" "Antmicro"
			(at 0 0 0)
			(layer "B.Fab")
			(hide yes)
			(effects
				(font
					(size 1 1)
					(thickness 0.15)
				)
				(justify mirror)
			)
		)
		(property "Dielectric" "X5R"
			(at 0 0 0)
			(layer "B.Fab")
			(hide yes)
			(effects
				(font
					(size 1 1)
					(thickness 0.15)
				)
				(justify mirror)
			)
		)
		(property "License" "Apache-2.0"
			(at 0 0 0)
			(layer "B.Fab")
			(hide yes)
			(effects
				(font
					(size 1 1)
					(thickness 0.15)
				)
				(justify mirror)
			)
		)
		(property "MPN" "GRM155R61H104KE14D"
			(at 0 0 0)
			(layer "B.Fab")
			(hide yes)
			(effects
				(font
					(size 1 1)
					(thickness 0.15)
				)
				(justify mirror)
			)
		)
		(property "Manufacturer" "Murata"
			(at 0 0 0)
			(layer "B.Fab")
			(hide yes)
			(effects
				(font
					(size 1 1)
					(thickness 0.15)
				)
				(justify mirror)
			)
		)
		(property "Public" "False"
			(at 0 0 0)
			(layer "B.Fab")
			(hide yes)
			(effects
				(font
					(size 1 1)
					(thickness 0.15)
				)
				(justify mirror)
			)
		)
		(property "Val" "100n"
			(at 0 0 0)
			(layer "B.Fab")
			(hide yes)
			(effects
				(font
					(size 1 1)
					(thickness 0.15)
				)
				(justify mirror)
			)
		)
		(property "Voltage" "50V"
			(at 0 0 0)
			(layer "B.Fab")
			(hide yes)
			(effects
				(font
					(size 1 1)
					(thickness 0.15)
				)
				(justify mirror)
			)
		)
		(sheetname "KR to SFI #1")
		(sheetfile "kr_sfi.kicad_sch")
		(attr smd)
		(fp_rect
			(start -0.925 0.47)
			(end 0.925 -0.47)
			(stroke
				(width 0.05)
				(type default)
			)
			(fill no)
			(layer "B.CrtYd")
		)
		(fp_line
			(start -0.494 -0.248)
			(end 0.504 -0.248)
			(stroke
				(width 0.15)
				(type solid)
			)
			(layer "B.Fab")
		)
		(fp_line
			(start -0.494 0.25)
			(end -0.494 -0.248)
			(stroke
				(width 0.15)
				(type solid)
			)
			(layer "B.Fab")
		)
		(fp_line
			(start 0.504 -0.248)
			(end 0.504 0.25)
			(stroke
				(width 0.15)
				(type solid)
			)
			(layer "B.Fab")
		)
		(fp_line
			(start 0.504 0.25)
			(end -0.494 0.25)
			(stroke
				(width 0.15)
				(type solid)
			)
			(layer "B.Fab")
		)
		(pad "1" smd roundrect
			(at -0.48 0)
			(size 0.59 0.64)
			(layers "B.Cu" "B.Mask" "B.Paste")
			(roundrect_rratio 0.25)
			(net 1 "GND")
			(pintype "passive")
			(teardrops
				(best_length_ratio 0.2)
				(max_length 1)
				(best_width_ratio 0.9)
				(max_width 2)
				(curved_edges yes)
				(filter_ratio 0.9)
				(enabled yes)
				(allow_two_segments yes)
				(prefer_zone_connections yes)
			)
		)
		(pad "2" smd roundrect
			(at 0.48 0)
			(size 0.59 0.64)
			(layers "B.Cu" "B.Mask" "B.Paste")
			(roundrect_rratio 0.25)
			(net 74 "+1V0")
			(pintype "passive")
			(teardrops
				(best_length_ratio 0.2)
				(max_length 1)
				(best_width_ratio 0.9)
				(max_width 2)
				(curved_edges yes)
				(filter_ratio 0.9)
				(enabled yes)
				(allow_two_segments yes)
				(prefer_zone_connections yes)
			)
		)
	)
	(footprint "antmicro-footprints:C_0402_1005Metric"
		(layer "B.Cu")
		(at 134.79 141.86 180)
		(descr "Capacitor SMD 0402")
		(tags "capacitor SMD 0402")
		(property "Reference" "C196"
			(at -1.41 -1.35 0)
			(layer "B.SilkS")
			(effects
				(font
					(size 0.7 0.7)
					(thickness 0.15)
				)
				(justify left bottom mirror)
			)
		)
		(property "Value" "C_100n_0402"
			(at -1.022927 -2.155213 0)
			(layer "B.Fab")
			(effects
				(font
					(size 0.7 0.7)
					(thickness 0.15)
				)
				(justify left bottom mirror)
			)
		)
		(property "Datasheet" "https://www.murata.com/products/productdetail?partno=GRM155R61H104KE14%23"
			(at 0 0 180)
			(layer "F.Fab")
			(hide yes)
			(effects
				(font
					(size 1.27 1.27)
					(thickness 0.15)
				)
			)
		)
		(property "Author" "Antmicro"
			(at 269.58 283.72 0)
			(layer "B.Fab")
			(hide yes)
			(effects
				(font
					(size 1 1)
					(thickness 0.15)
				)
				(justify mirror)
			)
		)
		(property "Dielectric" "X5R"
			(at 269.58 283.72 0)
			(layer "B.Fab")
			(hide yes)
			(effects
				(font
					(size 1 1)
					(thickness 0.15)
				)
				(justify mirror)
			)
		)
		(property "License" "Apache-2.0"
			(at 269.58 283.72 0)
			(layer "B.Fab")
			(hide yes)
			(effects
				(font
					(size 1 1)
					(thickness 0.15)
				)
				(justify mirror)
			)
		)
		(property "MPN" "GRM155R61H104KE14D"
			(at 269.58 283.72 0)
			(layer "B.Fab")
			(hide yes)
			(effects
				(font
					(size 1 1)
					(thickness 0.15)
				)
				(justify mirror)
			)
		)
		(property "Manufacturer" "Murata"
			(at 269.58 283.72 0)
			(layer "B.Fab")
			(hide yes)
			(effects
				(font
					(size 1 1)
					(thickness 0.15)
				)
				(justify mirror)
			)
		)
		(property "Public" "False"
			(at 269.58 283.72 0)
			(layer "B.Fab")
			(hide yes)
			(effects
				(font
					(size 1 1)
					(thickness 0.15)
				)
				(justify mirror)
			)
		)
		(property "Val" "100n"
			(at 269.58 283.72 0)
			(layer "B.Fab")
			(hide yes)
			(effects
				(font
					(size 1 1)
					(thickness 0.15)
				)
				(justify mirror)
			)
		)
		(property "Voltage" "50V"
			(at 269.58 283.72 0)
			(layer "B.Fab")
			(hide yes)
			(effects
				(font
					(size 1 1)
					(thickness 0.15)
				)
				(justify mirror)
			)
		)
		(sheetname "KR to SFI #2")
		(sheetfile "kr_sfi.kicad_sch")
		(attr smd)
		(fp_rect
			(start -0.925 0.47)
			(end 0.925 -0.47)
			(stroke
				(width 0.05)
				(type default)
			)
			(fill no)
			(layer "B.CrtYd")
		)
		(fp_line
			(start 0.504 0.25)
			(end -0.494 0.25)
			(stroke
				(width 0.15)
				(type solid)
			)
			(layer "B.Fab")
		)
		(fp_line
			(start 0.504 -0.248)
			(end 0.504 0.25)
			(stroke
				(width 0.15)
				(type solid)
			)
			(layer "B.Fab")
		)
		(fp_line
			(start -0.494 0.25)
			(end -0.494 -0.248)
			(stroke
				(width 0.15)
				(type solid)
			)
			(layer "B.Fab")
		)
		(fp_line
			(start -0.494 -0.248)
			(end 0.504 -0.248)
			(stroke
				(width 0.15)
				(type solid)
			)
			(layer "B.Fab")
		)
		(pad "1" smd roundrect
			(at -0.48 0 180)
			(size 0.59 0.64)
			(layers "B.Cu" "B.Mask" "B.Paste")
			(roundrect_rratio 0.25)
			(net 1 "GND")
			(pintype "passive")
			(teardrops
				(best_length_ratio 0.2)
				(max_length 1)
				(best_width_ratio 0.9)
				(max_width 2)
				(curved_edges yes)
				(filter_ratio 0.9)
				(enabled yes)
				(allow_two_segments yes)
				(prefer_zone_connections yes)
			)
		)
		(pad "2" smd roundrect
			(at 0.48 0 180)
			(size 0.59 0.64)
			(layers "B.Cu" "B.Mask" "B.Paste")
			(roundrect_rratio 0.25)
			(net 78 "+1V8")
			(pintype "passive")
			(teardrops
				(best_length_ratio 0.2)
				(max_length 1)
				(best_width_ratio 0.9)
				(max_width 2)
				(curved_edges yes)
				(filter_ratio 0.9)
				(enabled yes)
				(allow_two_segments yes)
				(prefer_zone_connections yes)
			)
		)
	)
	(footprint "antmicro-footprints:SOD-523"
		(layer "B.Cu")
		(at 103.975 84.947)
		(property "Reference" "D10"
			(at -3.075 0.413 180)
			(layer "B.SilkS")
			(effects
				(font
					(size 0.7 0.7)
					(thickness 0.15)
				)
				(justify right bottom mirror)
			)
		)
		(property "Value" "PESD5Z5_0F"
			(at 0 -1.499 0)
			(layer "B.Fab")
			(effects
				(font
					(size 0.7 0.7)
					(thickness 0.15)
				)
				(justify right bottom mirror)
			)
		)
		(property "Datasheet" "https://assets.nexperia.com/documents/data-sheet/PESD5Z5_0.pdf"
			(at 0 0 0)
			(layer "F.Fab")
			(hide yes)
			(effects
				(font
					(size 1.27 1.27)
					(thickness 0.15)
				)
			)
		)
		(property "Author" "Antmicro"
			(at 0 0 0)
			(layer "B.Fab")
			(hide yes)
			(effects
				(font
					(size 1 1)
					(thickness 0.15)
				)
				(justify mirror)
			)
		)
		(property "License" "Apache-2.0"
			(at 0 0 0)
			(layer "B.Fab")
			(hide yes)
			(effects
				(font
					(size 1 1)
					(thickness 0.15)
				)
				(justify mirror)
			)
		)
		(property "MPN" "PESD5Z5.0F"
			(at 0 0 0)
			(layer "B.Fab")
			(hide yes)
			(effects
				(font
					(size 1 1)
					(thickness 0.15)
				)
				(justify mirror)
			)
		)
		(property "Manufacturer" "Nexperia"
			(at 0 0 0)
			(layer "B.Fab")
			(hide yes)
			(effects
				(font
					(size 1 1)
					(thickness 0.15)
				)
				(justify mirror)
			)
		)
		(property "Public" "False"
			(at 0 0 0)
			(layer "B.Fab")
			(hide yes)
			(effects
				(font
					(size 1 1)
					(thickness 0.15)
				)
				(justify mirror)
			)
		)
		(sheetname "USB-C console")
		(sheetfile "usb-c_console.kicad_sch")
		(attr smd)
		(fp_line
			(start -0.35 -0.5)
			(end -0.35 0.5)
			(stroke
				(width 0.15)
				(type solid)
			)
			(layer "B.SilkS")
		)
		(fp_rect
			(start -1 0.6)
			(end 1 -0.6)
			(stroke
				(width 0.05)
				(type solid)
			)
			(fill no)
			(layer "B.CrtYd")
		)
		(fp_line
			(start -0.652 0.425)
			(end -0.652 -0.423)
			(stroke
				(width 0.15)
				(type solid)
			)
			(layer "B.Fab")
		)
		(fp_line
			(start -0.35 -0.4)
			(end -0.35 0.4)
			(stroke
				(width 0.15)
				(type solid)
			)
			(layer "B.Fab")
		)
		(fp_line
			(start 0.65 -0.423)
			(end -0.652 -0.423)
			(stroke
				(width 0.15)
				(type solid)
			)
			(layer "B.Fab")
		)
		(fp_line
			(start 0.65 -0.423)
			(end 0.65 0.425)
			(stroke
				(width 0.15)
				(type solid)
			)
			(layer "B.Fab")
		)
		(fp_line
			(start 0.65 0.425)
			(end -0.652 0.425)
			(stroke
				(width 0.15)
				(type solid)
			)
			(layer "B.Fab")
		)
		(pad "1" smd roundrect
			(at -0.701 0)
			(size 0.5 0.6)
			(layers "B.Cu" "B.Mask" "B.Paste")
			(roundrect_rratio 0.25)
			(net 58 "/USB-C console/VBUS_FTDI")
			(pinfunction "C")
			(pintype "passive")
			(teardrops
				(best_length_ratio 0.2)
				(max_length 1)
				(best_width_ratio 0.9)
				(max_width 2)
				(curved_edges yes)
				(filter_ratio 0.9)
				(enabled yes)
				(allow_two_segments yes)
				(prefer_zone_connections yes)
			)
		)
		(pad "2" smd roundrect
			(at 0.699 0)
			(size 0.5 0.6)
			(layers "B.Cu" "B.Mask" "B.Paste")
			(roundrect_rratio 0.25)
			(net 1 "GND")
			(pinfunction "A")
			(pintype "passive")
			(teardrops
				(best_length_ratio 0.2)
				(max_length 1)
				(best_width_ratio 0.9)
				(max_width 2)
				(curved_edges yes)
				(filter_ratio 0.9)
				(enabled yes)
				(allow_two_segments yes)
				(prefer_zone_connections yes)
			)
		)
	)
	(footprint "antmicro-footprints:C_0402_1005Metric"
		(layer "B.Cu")
		(at 104.85 101.86)
		(descr "Capacitor SMD 0402")
		(tags "capacitor SMD 0402")
		(property "Reference" "C1"
			(at -2.35 0.45 0)
			(layer "B.SilkS")
			(effects
				(font
					(size 0.7 0.7)
					(thickness 0.15)
				)
				(justify right bottom mirror)
			)
		)
		(property "Value" "C_1u_0402"
			(at -1.022927 -2.155213 0)
			(layer "B.Fab")
			(effects
				(font
					(size 0.7 0.7)
					(thickness 0.15)
				)
				(justify right bottom mirror)
			)
		)
		(property "Datasheet" "https://product.tdk.com/en/search/capacitor/ceramic/mlcc/info?part_no=C1005X6S1A105K050BC"
			(at 0 0 0)
			(layer "F.Fab")
			(hide yes)
			(effects
				(font
					(size 1.27 1.27)
					(thickness 0.15)
				)
			)
		)
		(property "Author" "Antmicro"
			(at 0 0 0)
			(layer "B.Fab")
			(hide yes)
			(effects
				(font
					(size 1 1)
					(thickness 0.15)
				)
				(justify mirror)
			)
		)
		(property "Dielectric" ""
			(at 0 0 0)
			(layer "B.Fab")
			(hide yes)
			(effects
				(font
					(size 1 1)
					(thickness 0.15)
				)
				(justify mirror)
			)
		)
		(property "License" "Apache-2.0"
			(at 0 0 0)
			(layer "B.Fab")
			(hide yes)
			(effects
				(font
					(size 1 1)
					(thickness 0.15)
				)
				(justify mirror)
			)
		)
		(property "MPN" "C1005X6S1A105K050BC"
			(at 0 0 0)
			(layer "B.Fab")
			(hide yes)
			(effects
				(font
					(size 1 1)
					(thickness 0.15)
				)
				(justify mirror)
			)
		)
		(property "Manufacturer" "TDK"
			(at 0 0 0)
			(layer "B.Fab")
			(hide yes)
			(effects
				(font
					(size 1 1)
					(thickness 0.15)
				)
				(justify mirror)
			)
		)
		(property "Public" "False"
			(at 0 0 0)
			(layer "B.Fab")
			(hide yes)
			(effects
				(font
					(size 1 1)
					(thickness 0.15)
				)
				(justify mirror)
			)
		)
		(property "Val" "1u"
			(at 0 0 0)
			(layer "B.Fab")
			(hide yes)
			(effects
				(font
					(size 1 1)
					(thickness 0.15)
				)
				(justify mirror)
			)
		)
		(property "Voltage" ""
			(at 0 0 0)
			(layer "B.Fab")
			(hide yes)
			(effects
				(font
					(size 1 1)
					(thickness 0.15)
				)
				(justify mirror)
			)
		)
		(sheetname "2xUSB3.0+RJ45")
		(sheetfile "usb3+rj45.kicad_sch")
		(attr smd)
		(fp_rect
			(start -0.925 0.47)
			(end 0.925 -0.47)
			(stroke
				(width 0.05)
				(type default)
			)
			(fill no)
			(layer "B.CrtYd")
		)
		(fp_line
			(start -0.494 -0.248)
			(end 0.504 -0.248)
			(stroke
				(width 0.15)
				(type solid)
			)
			(layer "B.Fab")
		)
		(fp_line
			(start -0.494 0.25)
			(end -0.494 -0.248)
			(stroke
				(width 0.15)
				(type solid)
			)
			(layer "B.Fab")
		)
		(fp_line
			(start 0.504 -0.248)
			(end 0.504 0.25)
			(stroke
				(width 0.15)
				(type solid)
			)
			(layer "B.Fab")
		)
		(fp_line
			(start 0.504 0.25)
			(end -0.494 0.25)
			(stroke
				(width 0.15)
				(type solid)
			)
			(layer "B.Fab")
		)
		(pad "1" smd roundrect
			(at -0.48 0)
			(size 0.59 0.64)
			(layers "B.Cu" "B.Mask" "B.Paste")
			(roundrect_rratio 0.25)
			(net 1 "GND")
			(pintype "passive")
			(teardrops
				(best_length_ratio 0.2)
				(max_length 1)
				(best_width_ratio 0.9)
				(max_width 2)
				(curved_edges yes)
				(filter_ratio 0.9)
				(enabled yes)
				(allow_two_segments yes)
				(prefer_zone_connections yes)
			)
		)
		(pad "2" smd roundrect
			(at 0.48 0)
			(size 0.59 0.64)
			(layers "B.Cu" "B.Mask" "B.Paste")
			(roundrect_rratio 0.25)
			(net 42 "/2xUSB3.0+RJ45/P1_VBUS")
			(pintype "passive")
			(teardrops
				(best_length_ratio 0.2)
				(max_length 1)
				(best_width_ratio 0.9)
				(max_width 2)
				(curved_edges yes)
				(filter_ratio 0.9)
				(enabled yes)
				(allow_two_segments yes)
				(prefer_zone_connections yes)
			)
		)
	)
	(footprint "antmicro-footprints:TP_SMD_0.75mm"
		(layer "B.Cu")
		(at 123.4 145.71 180)
		(property "Reference" "TP49"
			(at -3.15 -0.47 0)
			(layer "B.SilkS")
			(effects
				(font
					(size 0.7 0.7)
					(thickness 0.15)
				)
				(justify left bottom mirror)
			)
		)
		(property "Value" "TP_0.75mm_SMD"
			(at 0 -1.2 0)
			(layer "B.Fab")
			(effects
				(font
					(size 0.7 0.7)
					(thickness 0.15)
				)
				(justify left bottom mirror)
			)
		)
		(property "Author" "Antmicro"
			(at 246.8 291.42 0)
			(layer "B.Fab")
			(hide yes)
			(effects
				(font
					(size 1 1)
					(thickness 0.15)
				)
				(justify mirror)
			)
		)
		(property "License" "Apache-2.0"
			(at 246.8 291.42 0)
			(layer "B.Fab")
			(hide yes)
			(effects
				(font
					(size 1 1)
					(thickness 0.15)
				)
				(justify mirror)
			)
		)
		(property "MPN" ""
			(at 246.8 291.42 0)
			(layer "B.Fab")
			(hide yes)
			(effects
				(font
					(size 1 1)
					(thickness 0.15)
				)
				(justify mirror)
			)
		)
		(property "Manufacturer" ""
			(at 246.8 291.42 0)
			(layer "B.Fab")
			(hide yes)
			(effects
				(font
					(size 1 1)
					(thickness 0.15)
				)
				(justify mirror)
			)
		)
		(property "Public" "False"
			(at 246.8 291.42 0)
			(layer "B.Fab")
			(hide yes)
			(effects
				(font
					(size 1 1)
					(thickness 0.15)
				)
				(justify mirror)
			)
		)
		(sheetname "PCIe redriver")
		(sheetfile "pcie_redriver.kicad_sch")
		(attr exclude_from_pos_files exclude_from_bom)
		(fp_circle
			(center 0 0)
			(end 0.475 0)
			(stroke
				(width 0.05)
				(type default)
			)
			(fill no)
			(layer "B.CrtYd")
		)
		(pad "1" smd circle
			(at 0 0 180)
			(size 0.75 0.75)
			(layers "B.Cu" "B.Mask")
			(net 712 "Net-(U39-SDA)")
			(pinfunction "1")
			(pintype "passive")
			(teardrops
				(best_length_ratio 0.4)
				(max_length 1)
				(best_width_ratio 0.9)
				(max_width 2)
				(curved_edges yes)
				(filter_ratio 0.9)
				(enabled yes)
				(allow_two_segments yes)
				(prefer_zone_connections yes)
			)
		)
	)
	(footprint "antmicro-footprints:R_0402_1005Metric"
		(layer "B.Cu")
		(at 157.9 138.36 180)
		(descr "Resistor SMD 0402")
		(tags "resistor SMD 0402")
		(property "Reference" "R253"
			(at -3.7 -0.45 0)
			(layer "B.SilkS")
			(effects
				(font
					(size 0.7 0.7)
					(thickness 0.15)
				)
				(justify left bottom mirror)
			)
		)
		(property "Value" "R_10k_0402"
			(at -1.011843 -1.772047 0)
			(layer "B.Fab")
			(effects
				(font
					(size 0.7 0.7)
					(thickness 0.15)
				)
				(justify left bottom mirror)
			)
		)
		(property "Datasheet" "https://www.bourns.com/docs/product-datasheets/cr.pdf"
			(at 0 0 180)
			(layer "F.Fab")
			(hide yes)
			(effects
				(font
					(size 1.27 1.27)
					(thickness 0.15)
				)
			)
		)
		(property "Author" "Antmicro"
			(at 315.8 276.72 0)
			(layer "B.Fab")
			(hide yes)
			(effects
				(font
					(size 1 1)
					(thickness 0.15)
				)
				(justify mirror)
			)
		)
		(property "License" "Apache-2.0"
			(at 315.8 276.72 0)
			(layer "B.Fab")
			(hide yes)
			(effects
				(font
					(size 1 1)
					(thickness 0.15)
				)
				(justify mirror)
			)
		)
		(property "MPN" "CR0402-FX-1002GLF"
			(at 315.8 276.72 0)
			(layer "B.Fab")
			(hide yes)
			(effects
				(font
					(size 1 1)
					(thickness 0.15)
				)
				(justify mirror)
			)
		)
		(property "Manufacturer" "Bourns"
			(at 315.8 276.72 0)
			(layer "B.Fab")
			(hide yes)
			(effects
				(font
					(size 1 1)
					(thickness 0.15)
				)
				(justify mirror)
			)
		)
		(property "Public" "False"
			(at 315.8 276.72 0)
			(layer "B.Fab")
			(hide yes)
			(effects
				(font
					(size 1 1)
					(thickness 0.15)
				)
				(justify mirror)
			)
		)
		(property "Tolerance" "1%"
			(at 315.8 276.72 0)
			(layer "B.Fab")
			(hide yes)
			(effects
				(font
					(size 1 1)
					(thickness 0.15)
				)
				(justify mirror)
			)
		)
		(property "Val" "10k"
			(at 315.8 276.72 0)
			(layer "B.Fab")
			(hide yes)
			(effects
				(font
					(size 1 1)
					(thickness 0.15)
				)
				(justify mirror)
			)
		)
		(sheetname "KR to SFI #1")
		(sheetfile "kr_sfi.kicad_sch")
		(attr smd)
		(fp_rect
			(start -0.925 0.47)
			(end 0.925 -0.47)
			(stroke
				(width 0.05)
				(type default)
			)
			(fill no)
			(layer "B.CrtYd")
		)
		(fp_rect
			(start -0.5 0.25)
			(end 0.5 -0.25)
			(stroke
				(width 0.15)
				(type solid)
			)
			(fill no)
			(layer "B.Fab")
		)
		(pad "1" smd roundrect
			(at -0.48 0 180)
			(size 0.59 0.64)
			(layers "B.Cu" "B.Mask" "B.Paste")
			(roundrect_rratio 0.25)
			(net 1 "GND")
			(pintype "passive")
			(teardrops
				(best_length_ratio 0.2)
				(max_length 1)
				(best_width_ratio 0.9)
				(max_width 2)
				(curved_edges yes)
				(filter_ratio 0.9)
				(enabled yes)
				(allow_two_segments yes)
				(prefer_zone_connections yes)
			)
		)
		(pad "2" smd roundrect
			(at 0.48 0 180)
			(size 0.59 0.64)
			(layers "B.Cu" "B.Mask" "B.Paste")
			(roundrect_rratio 0.25)
			(net 652 "/2xSFP+/KR to SFI #1/PRBSEN")
			(pintype "passive")
			(teardrops
				(best_length_ratio 0.2)
				(max_length 1)
				(best_width_ratio 0.9)
				(max_width 2)
				(curved_edges yes)
				(filter_ratio 0.9)
				(enabled yes)
				(allow_two_segments yes)
				(prefer_zone_connections yes)
			)
		)
	)
	(footprint "antmicro-footprints:TP_SMD_0.75mm"
		(layer "B.Cu")
		(at 180.8 160.15 180)
		(property "Reference" "TP20"
			(at -3.45 -0.6 0)
			(layer "B.SilkS")
			(effects
				(font
					(size 0.7 0.7)
					(thickness 0.15)
				)
				(justify left bottom mirror)
			)
		)
		(property "Value" "TP_0.75mm_SMD"
			(at 3.225 -53.865 0)
			(layer "B.Fab")
			(hide yes)
			(effects
				(font
					(size 0.7 0.7)
					(thickness 0.15)
				)
				(justify left bottom mirror)
			)
		)
		(property "Author" "Antmicro"
			(at 444.9 323.42 0)
			(layer "B.Fab")
			(hide yes)
			(effects
				(font
					(size 1 1)
					(thickness 0.15)
				)
				(justify mirror)
			)
		)
		(property "License" "Apache-2.0"
			(at 444.9 323.42 0)
			(layer "B.Fab")
			(hide yes)
			(effects
				(font
					(size 1 1)
					(thickness 0.15)
				)
				(justify mirror)
			)
		)
		(property "MPN" ""
			(at 444.9 323.42 0)
			(layer "B.Fab")
			(hide yes)
			(effects
				(font
					(size 1 1)
					(thickness 0.15)
				)
				(justify mirror)
			)
		)
		(property "Manufacturer" ""
			(at 444.9 323.42 0)
			(layer "B.Fab")
			(hide yes)
			(effects
				(font
					(size 1 1)
					(thickness 0.15)
				)
				(justify mirror)
			)
		)
		(property "Public" "False"
			(at 444.9 323.42 0)
			(layer "B.Fab")
			(hide yes)
			(effects
				(font
					(size 1 1)
					(thickness 0.15)
				)
				(justify mirror)
			)
		)
		(sheetname "Com Express 7 Interfaces")
		(sheetfile "com_express_7_interfaces.kicad_sch")
		(attr exclude_from_pos_files exclude_from_bom)
		(fp_circle
			(center 0 0)
			(end 0.475 0)
			(stroke
				(width 0.05)
				(type default)
			)
			(fill no)
			(layer "B.CrtYd")
		)
		(pad "1" smd circle
			(at 0 0 180)
			(size 0.75 0.75)
			(layers "B.Cu" "B.Mask")
			(net 409 "Net-(J12K-10G_SDP2)")
			(pinfunction "1")
			(pintype "passive")
			(teardrops
				(best_length_ratio 0.4)
				(max_length 1)
				(best_width_ratio 0.9)
				(max_width 2)
				(curved_edges yes)
				(filter_ratio 0.9)
				(enabled yes)
				(allow_two_segments yes)
				(prefer_zone_connections yes)
			)
		)
	)
	(footprint "antmicro-footprints:TP_SMD_0.75mm"
		(layer "B.Cu")
		(at 221.18 128.2)
		(property "Reference" "TP47"
			(at 0.37 0.46 0)
			(layer "B.SilkS")
			(effects
				(font
					(size 0.7 0.7)
					(thickness 0.15)
				)
				(justify right bottom mirror)
			)
		)
		(property "Value" "TP_0.75mm_SMD"
			(at 0 -1.2 0)
			(layer "B.Fab")
			(effects
				(font
					(size 0.7 0.7)
					(thickness 0.15)
				)
				(justify right bottom mirror)
			)
		)
		(property "Author" "Antmicro"
			(at 0 0 0)
			(layer "B.Fab")
			(hide yes)
			(effects
				(font
					(size 1 1)
					(thickness 0.15)
				)
				(justify mirror)
			)
		)
		(property "License" "Apache-2.0"
			(at 0 0 0)
			(layer "B.Fab")
			(hide yes)
			(effects
				(font
					(size 1 1)
					(thickness 0.15)
				)
				(justify mirror)
			)
		)
		(property "MPN" ""
			(at 0 0 0)
			(layer "B.Fab")
			(hide yes)
			(effects
				(font
					(size 1 1)
					(thickness 0.15)
				)
				(justify mirror)
			)
		)
		(property "Manufacturer" ""
			(at 0 0 0)
			(layer "B.Fab")
			(hide yes)
			(effects
				(font
					(size 1 1)
					(thickness 0.15)
				)
				(justify mirror)
			)
		)
		(property "Public" "False"
			(at 0 0 0)
			(layer "B.Fab")
			(hide yes)
			(effects
				(font
					(size 1 1)
					(thickness 0.15)
				)
				(justify mirror)
			)
		)
		(sheetname "PCIe misc")
		(sheetfile "pcie_misc.kicad_sch")
		(attr exclude_from_pos_files exclude_from_bom)
		(fp_circle
			(center 0 0)
			(end 0.475 0)
			(stroke
				(width 0.05)
				(type default)
			)
			(fill no)
			(layer "B.CrtYd")
		)
		(pad "1" smd circle
			(at 0 0)
			(size 0.75 0.75)
			(layers "B.Cu" "B.Mask")
			(net 621 "/PCIe misc/DIF5+")
			(pinfunction "1")
			(pintype "passive")
			(teardrops
				(best_length_ratio 0.4)
				(max_length 1)
				(best_width_ratio 0.9)
				(max_width 2)
				(curved_edges yes)
				(filter_ratio 0.9)
				(enabled yes)
				(allow_two_segments yes)
				(prefer_zone_connections yes)
			)
		)
	)
	(footprint "antmicro-footprints:C_0402_1005Metric"
		(layer "B.Cu")
		(at 133.29 139.36 -90)
		(descr "Capacitor SMD 0402")
		(tags "capacitor SMD 0402")
		(property "Reference" "C190"
			(at -0.95 -1.41 90)
			(layer "B.SilkS")
			(effects
				(font
					(size 0.7 0.7)
					(thickness 0.15)
				)
				(justify left bottom mirror)
			)
		)
		(property "Value" "C_100n_0402"
			(at -1.022927 -2.155213 90)
			(layer "B.Fab")
			(effects
				(font
					(size 0.7 0.7)
					(thickness 0.15)
				)
				(justify left bottom mirror)
			)
		)
		(property "Datasheet" "https://www.murata.com/products/productdetail?partno=GRM155R61H104KE14%23"
			(at 0 0 270)
			(layer "F.Fab")
			(hide yes)
			(effects
				(font
					(size 1.27 1.27)
					(thickness 0.15)
				)
			)
		)
		(property "Author" "Antmicro"
			(at -6.07 272.65 0)
			(layer "B.Fab")
			(hide yes)
			(effects
				(font
					(size 1 1)
					(thickness 0.15)
				)
				(justify mirror)
			)
		)
		(property "Dielectric" "X5R"
			(at -6.07 272.65 0)
			(layer "B.Fab")
			(hide yes)
			(effects
				(font
					(size 1 1)
					(thickness 0.15)
				)
				(justify mirror)
			)
		)
		(property "License" "Apache-2.0"
			(at -6.07 272.65 0)
			(layer "B.Fab")
			(hide yes)
			(effects
				(font
					(size 1 1)
					(thickness 0.15)
				)
				(justify mirror)
			)
		)
		(property "MPN" "GRM155R61H104KE14D"
			(at -6.07 272.65 0)
			(layer "B.Fab")
			(hide yes)
			(effects
				(font
					(size 1 1)
					(thickness 0.15)
				)
				(justify mirror)
			)
		)
		(property "Manufacturer" "Murata"
			(at -6.07 272.65 0)
			(layer "B.Fab")
			(hide yes)
			(effects
				(font
					(size 1 1)
					(thickness 0.15)
				)
				(justify mirror)
			)
		)
		(property "Public" "False"
			(at -6.07 272.65 0)
			(layer "B.Fab")
			(hide yes)
			(effects
				(font
					(size 1 1)
					(thickness 0.15)
				)
				(justify mirror)
			)
		)
		(property "Val" "100n"
			(at -6.07 272.65 0)
			(layer "B.Fab")
			(hide yes)
			(effects
				(font
					(size 1 1)
					(thickness 0.15)
				)
				(justify mirror)
			)
		)
		(property "Voltage" "50V"
			(at -6.07 272.65 0)
			(layer "B.Fab")
			(hide yes)
			(effects
				(font
					(size 1 1)
					(thickness 0.15)
				)
				(justify mirror)
			)
		)
		(sheetname "KR to SFI #2")
		(sheetfile "kr_sfi.kicad_sch")
		(attr smd)
		(fp_rect
			(start -0.925 0.47)
			(end 0.925 -0.47)
			(stroke
				(width 0.05)
				(type default)
			)
			(fill no)
			(layer "B.CrtYd")
		)
		(fp_line
			(start -0.494 0.25)
			(end -0.494 -0.248)
			(stroke
				(width 0.15)
				(type solid)
			)
			(layer "B.Fab")
		)
		(fp_line
			(start 0.504 0.25)
			(end -0.494 0.25)
			(stroke
				(width 0.15)
				(type solid)
			)
			(layer "B.Fab")
		)
		(fp_line
			(start -0.494 -0.248)
			(end 0.504 -0.248)
			(stroke
				(width 0.15)
				(type solid)
			)
			(layer "B.Fab")
		)
		(fp_line
			(start 0.504 -0.248)
			(end 0.504 0.25)
			(stroke
				(width 0.15)
				(type solid)
			)
			(layer "B.Fab")
		)
		(pad "1" smd roundrect
			(at -0.48 0 270)
			(size 0.59 0.64)
			(layers "B.Cu" "B.Mask" "B.Paste")
			(roundrect_rratio 0.25)
			(net 1 "GND")
			(pintype "passive")
			(teardrops
				(best_length_ratio 0.2)
				(max_length 1)
				(best_width_ratio 0.9)
				(max_width 2)
				(curved_edges yes)
				(filter_ratio 0.9)
				(enabled yes)
				(allow_two_segments yes)
				(prefer_zone_connections yes)
			)
		)
		(pad "2" smd roundrect
			(at 0.48 0 270)
			(size 0.59 0.64)
			(layers "B.Cu" "B.Mask" "B.Paste")
			(roundrect_rratio 0.25)
			(net 74 "+1V0")
			(pintype "passive")
			(teardrops
				(best_length_ratio 0.2)
				(max_length 1)
				(best_width_ratio 0.9)
				(max_width 2)
				(curved_edges yes)
				(filter_ratio 0.9)
				(enabled yes)
				(allow_two_segments yes)
				(prefer_zone_connections yes)
			)
		)
	)
	(footprint "antmicro-footprints:C_0402_1005Metric"
		(layer "B.Cu")
		(at 107.893 158.377 180)
		(descr "Capacitor SMD 0402")
		(tags "capacitor SMD 0402")
		(property "Reference" "C143"
			(at -3.707 0.067 0)
			(layer "B.SilkS")
			(effects
				(font
					(size 0.7 0.7)
					(thickness 0.15)
				)
				(justify left bottom mirror)
			)
		)
		(property "Value" "C_220n_0402"
			(at -1.022927 -2.155213 0)
			(layer "B.Fab")
			(effects
				(font
					(size 0.7 0.7)
					(thickness 0.15)
				)
				(justify left bottom mirror)
			)
		)
		(property "Datasheet" "https://www.yageo.com/en/Chart/Download/pdf/CC0402KRX5R6BB224"
			(at 0 0 180)
			(layer "F.Fab")
			(hide yes)
			(effects
				(font
					(size 1.27 1.27)
					(thickness 0.15)
				)
			)
		)
		(property "Author" "Antmicro"
			(at 215.786 316.754 0)
			(layer "B.Fab")
			(hide yes)
			(effects
				(font
					(size 1 1)
					(thickness 0.15)
				)
				(justify mirror)
			)
		)
		(property "Dielectric" ""
			(at 215.786 316.754 0)
			(layer "B.Fab")
			(hide yes)
			(effects
				(font
					(size 1 1)
					(thickness 0.15)
				)
				(justify mirror)
			)
		)
		(property "License" "Apache-2.0"
			(at 215.786 316.754 0)
			(layer "B.Fab")
			(hide yes)
			(effects
				(font
					(size 1 1)
					(thickness 0.15)
				)
				(justify mirror)
			)
		)
		(property "MPN" "CC0402KRX5R6BB224"
			(at 215.786 316.754 0)
			(layer "B.Fab")
			(hide yes)
			(effects
				(font
					(size 1 1)
					(thickness 0.15)
				)
				(justify mirror)
			)
		)
		(property "Manufacturer" "YAGEO"
			(at 215.786 316.754 0)
			(layer "B.Fab")
			(hide yes)
			(effects
				(font
					(size 1 1)
					(thickness 0.15)
				)
				(justify mirror)
			)
		)
		(property "Public" "False"
			(at 215.786 316.754 0)
			(layer "B.Fab")
			(hide yes)
			(effects
				(font
					(size 1 1)
					(thickness 0.15)
				)
				(justify mirror)
			)
		)
		(property "Val" "220n"
			(at 215.786 316.754 0)
			(layer "B.Fab")
			(hide yes)
			(effects
				(font
					(size 1 1)
					(thickness 0.15)
				)
				(justify mirror)
			)
		)
		(property "Voltage" ""
			(at 215.786 316.754 0)
			(layer "B.Fab")
			(hide yes)
			(effects
				(font
					(size 1 1)
					(thickness 0.15)
				)
				(justify mirror)
			)
		)
		(sheetname "PCIe redriver")
		(sheetfile "pcie_redriver.kicad_sch")
		(attr smd)
		(fp_rect
			(start -0.925 0.47)
			(end 0.925 -0.47)
			(stroke
				(width 0.05)
				(type default)
			)
			(fill no)
			(layer "B.CrtYd")
		)
		(fp_line
			(start 0.504 0.25)
			(end -0.494 0.25)
			(stroke
				(width 0.15)
				(type solid)
			)
			(layer "B.Fab")
		)
		(fp_line
			(start 0.504 -0.248)
			(end 0.504 0.25)
			(stroke
				(width 0.15)
				(type solid)
			)
			(layer "B.Fab")
		)
		(fp_line
			(start -0.494 0.25)
			(end -0.494 -0.248)
			(stroke
				(width 0.15)
				(type solid)
			)
			(layer "B.Fab")
		)
		(fp_line
			(start -0.494 -0.248)
			(end 0.504 -0.248)
			(stroke
				(width 0.15)
				(type solid)
			)
			(layer "B.Fab")
		)
		(pad "1" smd roundrect
			(at -0.48 0 180)
			(size 0.59 0.64)
			(layers "B.Cu" "B.Mask" "B.Paste")
			(roundrect_rratio 0.25)
			(net 99 "/PCIe redriver/PCIe_{O}_C.TX3-")
			(pintype "passive")
			(teardrops
				(best_length_ratio 0.2)
				(max_length 1)
				(best_width_ratio 0.9)
				(max_width 2)
				(curved_edges yes)
				(filter_ratio 0.9)
				(enabled yes)
				(allow_two_segments yes)
				(prefer_zone_connections yes)
			)
		)
		(pad "2" smd roundrect
			(at 0.48 0 180)
			(size 0.59 0.64)
			(layers "B.Cu" "B.Mask" "B.Paste")
			(roundrect_rratio 0.25)
			(net 98 "/OCuLink/PCIe_{x4}.TX3-")
			(pintype "passive")
			(teardrops
				(best_length_ratio 0.2)
				(max_length 1)
				(best_width_ratio 0.9)
				(max_width 2)
				(curved_edges yes)
				(filter_ratio 0.9)
				(enabled yes)
				(allow_two_segments yes)
				(prefer_zone_connections yes)
			)
		)
	)
	(footprint "antmicro-footprints:R_0402_1005Metric"
		(layer "B.Cu")
		(at 144.25 139.06)
		(descr "Resistor SMD 0402")
		(tags "resistor SMD 0402")
		(property "Reference" "R265"
			(at -1.45 5.4 0)
			(layer "B.SilkS")
			(effects
				(font
					(size 0.7 0.7)
					(thickness 0.15)
				)
				(justify right bottom mirror)
			)
		)
		(property "Value" "R_10k_0402"
			(at -1.011843 -1.772047 0)
			(layer "B.Fab")
			(effects
				(font
					(size 0.7 0.7)
					(thickness 0.15)
				)
				(justify right bottom mirror)
			)
		)
		(property "Datasheet" "https://www.bourns.com/docs/product-datasheets/cr.pdf"
			(at 0 0 0)
			(layer "F.Fab")
			(hide yes)
			(effects
				(font
					(size 1.27 1.27)
					(thickness 0.15)
				)
			)
		)
		(property "Author" "Antmicro"
			(at 0 0 0)
			(layer "B.Fab")
			(hide yes)
			(effects
				(font
					(size 1 1)
					(thickness 0.15)
				)
				(justify mirror)
			)
		)
		(property "License" "Apache-2.0"
			(at 0 0 0)
			(layer "B.Fab")
			(hide yes)
			(effects
				(font
					(size 1 1)
					(thickness 0.15)
				)
				(justify mirror)
			)
		)
		(property "MPN" "CR0402-FX-1002GLF"
			(at 0 0 0)
			(layer "B.Fab")
			(hide yes)
			(effects
				(font
					(size 1 1)
					(thickness 0.15)
				)
				(justify mirror)
			)
		)
		(property "Manufacturer" "Bourns"
			(at 0 0 0)
			(layer "B.Fab")
			(hide yes)
			(effects
				(font
					(size 1 1)
					(thickness 0.15)
				)
				(justify mirror)
			)
		)
		(property "Public" "False"
			(at 0 0 0)
			(layer "B.Fab")
			(hide yes)
			(effects
				(font
					(size 1 1)
					(thickness 0.15)
				)
				(justify mirror)
			)
		)
		(property "Tolerance" "1%"
			(at 0 0 0)
			(layer "B.Fab")
			(hide yes)
			(effects
				(font
					(size 1 1)
					(thickness 0.15)
				)
				(justify mirror)
			)
		)
		(property "Val" "10k"
			(at 0 0 0)
			(layer "B.Fab")
			(hide yes)
			(effects
				(font
					(size 1 1)
					(thickness 0.15)
				)
				(justify mirror)
			)
		)
		(sheetname "KR to SFI #1")
		(sheetfile "kr_sfi.kicad_sch")
		(attr smd)
		(fp_rect
			(start -0.925 0.47)
			(end 0.925 -0.47)
			(stroke
				(width 0.05)
				(type default)
			)
			(fill no)
			(layer "B.CrtYd")
		)
		(fp_rect
			(start -0.5 0.25)
			(end 0.5 -0.25)
			(stroke
				(width 0.15)
				(type solid)
			)
			(fill no)
			(layer "B.Fab")
		)
		(pad "1" smd roundrect
			(at -0.48 0)
			(size 0.59 0.64)
			(layers "B.Cu" "B.Mask" "B.Paste")
			(roundrect_rratio 0.25)
			(net 1 "GND")
			(pintype "passive")
			(teardrops
				(best_length_ratio 0.2)
				(max_length 1)
				(best_width_ratio 0.9)
				(max_width 2)
				(curved_edges yes)
				(filter_ratio 0.9)
				(enabled yes)
				(allow_two_segments yes)
				(prefer_zone_connections yes)
			)
		)
		(pad "2" smd roundrect
			(at 0.48 0)
			(size 0.59 0.64)
			(layers "B.Cu" "B.Mask" "B.Paste")
			(roundrect_rratio 0.25)
			(net 658 "Net-(U43C-PRTAD2)")
			(pintype "passive")
			(teardrops
				(best_length_ratio 0.2)
				(max_length 1)
				(best_width_ratio 0.9)
				(max_width 2)
				(curved_edges yes)
				(filter_ratio 0.9)
				(enabled yes)
				(allow_two_segments yes)
				(prefer_zone_connections yes)
			)
		)
	)
	(footprint "antmicro-footprints:C_0402_1005Metric"
		(layer "B.Cu")
		(at 152.25 160.23 -90)
		(descr "Capacitor SMD 0402")
		(tags "capacitor SMD 0402")
		(property "Reference" "C214"
			(at -1.12 -2.45 90)
			(layer "B.SilkS")
			(effects
				(font
					(size 0.7 0.7)
					(thickness 0.15)
				)
				(justify left bottom mirror)
			)
		)
		(property "Value" "C_100n_0402"
			(at -1.022927 -2.155213 90)
			(layer "B.Fab")
			(effects
				(font
					(size 0.7 0.7)
					(thickness 0.15)
				)
				(justify left bottom mirror)
			)
		)
		(property "Datasheet" "https://www.murata.com/products/productdetail?partno=GRM155R61H104KE14%23"
			(at 0 0 270)
			(layer "F.Fab")
			(hide yes)
			(effects
				(font
					(size 1.27 1.27)
					(thickness 0.15)
				)
			)
		)
		(property "Author" "Antmicro"
			(at -7.98 312.48 0)
			(layer "B.Fab")
			(hide yes)
			(effects
				(font
					(size 1 1)
					(thickness 0.15)
				)
				(justify mirror)
			)
		)
		(property "Dielectric" "X5R"
			(at -7.98 312.48 0)
			(layer "B.Fab")
			(hide yes)
			(effects
				(font
					(size 1 1)
					(thickness 0.15)
				)
				(justify mirror)
			)
		)
		(property "License" "Apache-2.0"
			(at -7.98 312.48 0)
			(layer "B.Fab")
			(hide yes)
			(effects
				(font
					(size 1 1)
					(thickness 0.15)
				)
				(justify mirror)
			)
		)
		(property "MPN" "GRM155R61H104KE14D"
			(at -7.98 312.48 0)
			(layer "B.Fab")
			(hide yes)
			(effects
				(font
					(size 1 1)
					(thickness 0.15)
				)
				(justify mirror)
			)
		)
		(property "Manufacturer" "Murata"
			(at -7.98 312.48 0)
			(layer "B.Fab")
			(hide yes)
			(effects
				(font
					(size 1 1)
					(thickness 0.15)
				)
				(justify mirror)
			)
		)
		(property "Public" "False"
			(at -7.98 312.48 0)
			(layer "B.Fab")
			(hide yes)
			(effects
				(font
					(size 1 1)
					(thickness 0.15)
				)
				(justify mirror)
			)
		)
		(property "Val" "100n"
			(at -7.98 312.48 0)
			(layer "B.Fab")
			(hide yes)
			(effects
				(font
					(size 1 1)
					(thickness 0.15)
				)
				(justify mirror)
			)
		)
		(property "Voltage" "50V"
			(at -7.98 312.48 0)
			(layer "B.Fab")
			(hide yes)
			(effects
				(font
					(size 1 1)
					(thickness 0.15)
				)
				(justify mirror)
			)
		)
		(sheetname "2xSFP+")
		(sheetfile "2xSFP+.kicad_sch")
		(attr smd)
		(fp_rect
			(start -0.925 0.47)
			(end 0.925 -0.47)
			(stroke
				(width 0.05)
				(type default)
			)
			(fill no)
			(layer "B.CrtYd")
		)
		(fp_line
			(start -0.494 0.25)
			(end -0.494 -0.248)
			(stroke
				(width 0.15)
				(type solid)
			)
			(layer "B.Fab")
		)
		(fp_line
			(start 0.504 0.25)
			(end -0.494 0.25)
			(stroke
				(width 0.15)
				(type solid)
			)
			(layer "B.Fab")
		)
		(fp_line
			(start -0.494 -0.248)
			(end 0.504 -0.248)
			(stroke
				(width 0.15)
				(type solid)
			)
			(layer "B.Fab")
		)
		(fp_line
			(start 0.504 -0.248)
			(end 0.504 0.25)
			(stroke
				(width 0.15)
				(type solid)
			)
			(layer "B.Fab")
		)
		(pad "1" smd roundrect
			(at -0.48 0 270)
			(size 0.59 0.64)
			(layers "B.Cu" "B.Mask" "B.Paste")
			(roundrect_rratio 0.25)
			(net 53 "/2xSFP+/SH")
			(pintype "passive")
			(teardrops
				(best_length_ratio 0.2)
				(max_length 1)
				(best_width_ratio 0.9)
				(max_width 2)
				(curved_edges yes)
				(filter_ratio 0.9)
				(enabled yes)
				(allow_two_segments yes)
				(prefer_zone_connections yes)
			)
		)
		(pad "2" smd roundrect
			(at 0.48 0 270)
			(size 0.59 0.64)
			(layers "B.Cu" "B.Mask" "B.Paste")
			(roundrect_rratio 0.25)
			(net 1 "GND")
			(pintype "passive")
			(teardrops
				(best_length_ratio 0.2)
				(max_length 1)
				(best_width_ratio 0.9)
				(max_width 2)
				(curved_edges yes)
				(filter_ratio 0.9)
				(enabled yes)
				(allow_two_segments yes)
				(prefer_zone_connections yes)
			)
		)
	)
	(footprint "antmicro-footprints:C_0402_1005Metric"
		(layer "B.Cu")
		(at 110.35 169.435)
		(descr "Capacitor SMD 0402")
		(tags "capacitor SMD 0402")
		(property "Reference" "C208"
			(at -1.35 -0.525 0)
			(layer "B.SilkS")
			(effects
				(font
					(size 0.7 0.7)
					(thickness 0.15)
				)
				(justify right bottom mirror)
			)
		)
		(property "Value" "C_100n_0402"
			(at -1.022927 -2.155213 0)
			(layer "B.Fab")
			(effects
				(font
					(size 0.7 0.7)
					(thickness 0.15)
				)
				(justify right bottom mirror)
			)
		)
		(property "Datasheet" "https://www.murata.com/products/productdetail?partno=GRM155R61H104KE14%23"
			(at 0 0 0)
			(layer "F.Fab")
			(hide yes)
			(effects
				(font
					(size 1.27 1.27)
					(thickness 0.15)
				)
			)
		)
		(property "Author" "Antmicro"
			(at 0 0 0)
			(layer "B.Fab")
			(hide yes)
			(effects
				(font
					(size 1 1)
					(thickness 0.15)
				)
				(justify mirror)
			)
		)
		(property "Dielectric" "X5R"
			(at 0 0 0)
			(layer "B.Fab")
			(hide yes)
			(effects
				(font
					(size 1 1)
					(thickness 0.15)
				)
				(justify mirror)
			)
		)
		(property "License" "Apache-2.0"
			(at 0 0 0)
			(layer "B.Fab")
			(hide yes)
			(effects
				(font
					(size 1 1)
					(thickness 0.15)
				)
				(justify mirror)
			)
		)
		(property "MPN" "GRM155R61H104KE14D"
			(at 0 0 0)
			(layer "B.Fab")
			(hide yes)
			(effects
				(font
					(size 1 1)
					(thickness 0.15)
				)
				(justify mirror)
			)
		)
		(property "Manufacturer" "Murata"
			(at 0 0 0)
			(layer "B.Fab")
			(hide yes)
			(effects
				(font
					(size 1 1)
					(thickness 0.15)
				)
				(justify mirror)
			)
		)
		(property "Public" "False"
			(at 0 0 0)
			(layer "B.Fab")
			(hide yes)
			(effects
				(font
					(size 1 1)
					(thickness 0.15)
				)
				(justify mirror)
			)
		)
		(property "Val" "100n"
			(at 0 0 0)
			(layer "B.Fab")
			(hide yes)
			(effects
				(font
					(size 1 1)
					(thickness 0.15)
				)
				(justify mirror)
			)
		)
		(property "Voltage" "50V"
			(at 0 0 0)
			(layer "B.Fab")
			(hide yes)
			(effects
				(font
					(size 1 1)
					(thickness 0.15)
				)
				(justify mirror)
			)
		)
		(sheetname "2xSFP+")
		(sheetfile "2xSFP+.kicad_sch")
		(attr smd)
		(fp_rect
			(start -0.925 0.47)
			(end 0.925 -0.47)
			(stroke
				(width 0.05)
				(type default)
			)
			(fill no)
			(layer "B.CrtYd")
		)
		(fp_line
			(start -0.494 -0.248)
			(end 0.504 -0.248)
			(stroke
				(width 0.15)
				(type solid)
			)
			(layer "B.Fab")
		)
		(fp_line
			(start -0.494 0.25)
			(end -0.494 -0.248)
			(stroke
				(width 0.15)
				(type solid)
			)
			(layer "B.Fab")
		)
		(fp_line
			(start 0.504 -0.248)
			(end 0.504 0.25)
			(stroke
				(width 0.15)
				(type solid)
			)
			(layer "B.Fab")
		)
		(fp_line
			(start 0.504 0.25)
			(end -0.494 0.25)
			(stroke
				(width 0.15)
				(type solid)
			)
			(layer "B.Fab")
		)
		(pad "1" smd roundrect
			(at -0.48 0)
			(size 0.59 0.64)
			(layers "B.Cu" "B.Mask" "B.Paste")
			(roundrect_rratio 0.25)
			(net 53 "/2xSFP+/SH")
			(pintype "passive")
			(teardrops
				(best_length_ratio 0.2)
				(max_length 1)
				(best_width_ratio 0.9)
				(max_width 2)
				(curved_edges yes)
				(filter_ratio 0.9)
				(enabled yes)
				(allow_two_segments yes)
				(prefer_zone_connections yes)
			)
		)
		(pad "2" smd roundrect
			(at 0.48 0)
			(size 0.59 0.64)
			(layers "B.Cu" "B.Mask" "B.Paste")
			(roundrect_rratio 0.25)
			(net 1 "GND")
			(pintype "passive")
			(teardrops
				(best_length_ratio 0.2)
				(max_length 1)
				(best_width_ratio 0.9)
				(max_width 2)
				(curved_edges yes)
				(filter_ratio 0.9)
				(enabled yes)
				(allow_two_segments yes)
				(prefer_zone_connections yes)
			)
		)
	)
	(footprint "antmicro-footprints:R_0402_1005Metric"
		(layer "B.Cu")
		(at 99.3 76.81)
		(descr "Resistor SMD 0402")
		(tags "resistor SMD 0402")
		(property "Reference" "R141"
			(at -3.65 0.4 0)
			(layer "B.SilkS")
			(effects
				(font
					(size 0.7 0.7)
					(thickness 0.15)
				)
				(justify right bottom mirror)
			)
		)
		(property "Value" "R_10k_0402"
			(at -1.011843 -1.772047 0)
			(layer "B.Fab")
			(effects
				(font
					(size 0.7 0.7)
					(thickness 0.15)
				)
				(justify right bottom mirror)
			)
		)
		(property "Datasheet" "https://www.bourns.com/docs/product-datasheets/cr.pdf"
			(at 0 0 0)
			(layer "F.Fab")
			(hide yes)
			(effects
				(font
					(size 1.27 1.27)
					(thickness 0.15)
				)
			)
		)
		(property "Description" "SMD Chip Resistor, 10 kohm, ± 1%, 62.5 mW, 0402 [1005 Metric], Thick Film, General Purpose"
			(at 0 0 0)
			(layer "F.Fab")
			(hide yes)
			(effects
				(font
					(size 1.27 1.27)
					(thickness 0.15)
				)
			)
		)
		(property "Author" "Antmicro"
			(at 0 0 0)
			(layer "B.Fab")
			(hide yes)
			(effects
				(font
					(size 1 1)
					(thickness 0.15)
				)
				(justify mirror)
			)
		)
		(property "License" "Apache-2.0"
			(at 0 0 0)
			(layer "B.Fab")
			(hide yes)
			(effects
				(font
					(size 1 1)
					(thickness 0.15)
				)
				(justify mirror)
			)
		)
		(property "MPN" "CR0402-FX-1002GLF"
			(at 0 0 0)
			(layer "B.Fab")
			(hide yes)
			(effects
				(font
					(size 1 1)
					(thickness 0.15)
				)
				(justify mirror)
			)
		)
		(property "Manufacturer" "Bourns"
			(at 0 0 0)
			(layer "B.Fab")
			(hide yes)
			(effects
				(font
					(size 1 1)
					(thickness 0.15)
				)
				(justify mirror)
			)
		)
		(property "Tolerance" "1%"
			(at 0 0 0)
			(layer "B.Fab")
			(hide yes)
			(effects
				(font
					(size 1 1)
					(thickness 0.15)
				)
				(justify mirror)
			)
		)
		(property "Val" "10k"
			(at 0 0 0)
			(layer "B.Fab")
			(hide yes)
			(effects
				(font
					(size 1 1)
					(thickness 0.15)
				)
				(justify mirror)
			)
		)
		(sheetname "Misc")
		(sheetfile "misc.kicad_sch")
		(attr smd)
		(fp_rect
			(start -0.925 0.47)
			(end 0.925 -0.47)
			(stroke
				(width 0.05)
				(type default)
			)
			(fill no)
			(layer "B.CrtYd")
		)
		(fp_rect
			(start -0.5 0.25)
			(end 0.5 -0.25)
			(stroke
				(width 0.15)
				(type solid)
			)
			(fill no)
			(layer "B.Fab")
		)
		(pad "1" smd roundrect
			(at -0.48 0)
			(size 0.59 0.64)
			(layers "B.Cu" "B.Mask" "B.Paste")
			(roundrect_rratio 0.25)
			(net 573 "/GPIO expander/GPIOEX0")
			(pintype "passive")
			(teardrops
				(best_length_ratio 0.2)
				(max_length 1)
				(best_width_ratio 0.9)
				(max_width 2)
				(curved_edges yes)
				(filter_ratio 0.9)
				(enabled yes)
				(allow_two_segments yes)
				(prefer_zone_connections yes)
			)
		)
		(pad "2" smd roundrect
			(at 0.48 0)
			(size 0.59 0.64)
			(layers "B.Cu" "B.Mask" "B.Paste")
			(roundrect_rratio 0.25)
			(net 130 "Net-(D17-C_{G})")
			(pintype "passive")
			(teardrops
				(best_length_ratio 0.2)
				(max_length 1)
				(best_width_ratio 0.9)
				(max_width 2)
				(curved_edges yes)
				(filter_ratio 0.9)
				(enabled yes)
				(allow_two_segments yes)
				(prefer_zone_connections yes)
			)
		)
	)
	(footprint "antmicro-footprints:C_0402_1005Metric"
		(layer "B.Cu")
		(at 128.79 137.86)
		(descr "Capacitor SMD 0402")
		(tags "capacitor SMD 0402")
		(property "Reference" "C187"
			(at -1.39 1.4 0)
			(layer "B.SilkS")
			(effects
				(font
					(size 0.7 0.7)
					(thickness 0.15)
				)
				(justify right bottom mirror)
			)
		)
		(property "Value" "C_100n_0402"
			(at -1.022927 -2.155213 0)
			(layer "B.Fab")
			(effects
				(font
					(size 0.7 0.7)
					(thickness 0.15)
				)
				(justify right bottom mirror)
			)
		)
		(property "Datasheet" "https://www.murata.com/products/productdetail?partno=GRM155R61H104KE14%23"
			(at 0 0 0)
			(layer "F.Fab")
			(hide yes)
			(effects
				(font
					(size 1.27 1.27)
					(thickness 0.15)
				)
			)
		)
		(property "Author" "Antmicro"
			(at 0 0 0)
			(layer "B.Fab")
			(hide yes)
			(effects
				(font
					(size 1 1)
					(thickness 0.15)
				)
				(justify mirror)
			)
		)
		(property "Dielectric" "X5R"
			(at 0 0 0)
			(layer "B.Fab")
			(hide yes)
			(effects
				(font
					(size 1 1)
					(thickness 0.15)
				)
				(justify mirror)
			)
		)
		(property "License" "Apache-2.0"
			(at 0 0 0)
			(layer "B.Fab")
			(hide yes)
			(effects
				(font
					(size 1 1)
					(thickness 0.15)
				)
				(justify mirror)
			)
		)
		(property "MPN" "GRM155R61H104KE14D"
			(at 0 0 0)
			(layer "B.Fab")
			(hide yes)
			(effects
				(font
					(size 1 1)
					(thickness 0.15)
				)
				(justify mirror)
			)
		)
		(property "Manufacturer" "Murata"
			(at 0 0 0)
			(layer "B.Fab")
			(hide yes)
			(effects
				(font
					(size 1 1)
					(thickness 0.15)
				)
				(justify mirror)
			)
		)
		(property "Public" "False"
			(at 0 0 0)
			(layer "B.Fab")
			(hide yes)
			(effects
				(font
					(size 1 1)
					(thickness 0.15)
				)
				(justify mirror)
			)
		)
		(property "Val" "100n"
			(at 0 0 0)
			(layer "B.Fab")
			(hide yes)
			(effects
				(font
					(size 1 1)
					(thickness 0.15)
				)
				(justify mirror)
			)
		)
		(property "Voltage" "50V"
			(at 0 0 0)
			(layer "B.Fab")
			(hide yes)
			(effects
				(font
					(size 1 1)
					(thickness 0.15)
				)
				(justify mirror)
			)
		)
		(sheetname "KR to SFI #2")
		(sheetfile "kr_sfi.kicad_sch")
		(attr smd)
		(fp_rect
			(start -0.925 0.47)
			(end 0.925 -0.47)
			(stroke
				(width 0.05)
				(type default)
			)
			(fill no)
			(layer "B.CrtYd")
		)
		(fp_line
			(start -0.494 -0.248)
			(end 0.504 -0.248)
			(stroke
				(width 0.15)
				(type solid)
			)
			(layer "B.Fab")
		)
		(fp_line
			(start -0.494 0.25)
			(end -0.494 -0.248)
			(stroke
				(width 0.15)
				(type solid)
			)
			(layer "B.Fab")
		)
		(fp_line
			(start 0.504 -0.248)
			(end 0.504 0.25)
			(stroke
				(width 0.15)
				(type solid)
			)
			(layer "B.Fab")
		)
		(fp_line
			(start 0.504 0.25)
			(end -0.494 0.25)
			(stroke
				(width 0.15)
				(type solid)
			)
			(layer "B.Fab")
		)
		(pad "1" smd roundrect
			(at -0.48 0)
			(size 0.59 0.64)
			(layers "B.Cu" "B.Mask" "B.Paste")
			(roundrect_rratio 0.25)
			(net 1 "GND")
			(pintype "passive")
			(teardrops
				(best_length_ratio 0.2)
				(max_length 1)
				(best_width_ratio 0.9)
				(max_width 2)
				(curved_edges yes)
				(filter_ratio 0.9)
				(enabled yes)
				(allow_two_segments yes)
				(prefer_zone_connections yes)
			)
		)
		(pad "2" smd roundrect
			(at 0.48 0)
			(size 0.59 0.64)
			(layers "B.Cu" "B.Mask" "B.Paste")
			(roundrect_rratio 0.25)
			(net 74 "+1V0")
			(pintype "passive")
			(teardrops
				(best_length_ratio 0.2)
				(max_length 1)
				(best_width_ratio 0.9)
				(max_width 2)
				(curved_edges yes)
				(filter_ratio 0.9)
				(enabled yes)
				(allow_two_segments yes)
				(prefer_zone_connections yes)
			)
		)
	)
	(footprint "antmicro-footprints:C_0402_1005Metric"
		(layer "B.Cu")
		(at 121.5 73.61 -90)
		(descr "Capacitor SMD 0402")
		(tags "capacitor SMD 0402")
		(property "Reference" "C35"
			(at -1.1 -1.35 90)
			(layer "B.SilkS")
			(effects
				(font
					(size 0.7 0.7)
					(thickness 0.15)
				)
				(justify left bottom mirror)
			)
		)
		(property "Value" "C_100n_0402"
			(at -1.022927 -2.155213 90)
			(layer "B.Fab")
			(effects
				(font
					(size 0.7 0.7)
					(thickness 0.15)
				)
				(justify left bottom mirror)
			)
		)
		(property "Datasheet" "https://www.murata.com/products/productdetail?partno=GRM155R61H104KE14%23"
			(at 0 0 270)
			(layer "F.Fab")
			(hide yes)
			(effects
				(font
					(size 1.27 1.27)
					(thickness 0.15)
				)
			)
		)
		(property "Author" "Antmicro"
			(at 47.89 195.11 0)
			(layer "B.Fab")
			(hide yes)
			(effects
				(font
					(size 1 1)
					(thickness 0.15)
				)
				(justify mirror)
			)
		)
		(property "Dielectric" "X5R"
			(at 47.89 195.11 0)
			(layer "B.Fab")
			(hide yes)
			(effects
				(font
					(size 1 1)
					(thickness 0.15)
				)
				(justify mirror)
			)
		)
		(property "License" "Apache-2.0"
			(at 47.89 195.11 0)
			(layer "B.Fab")
			(hide yes)
			(effects
				(font
					(size 1 1)
					(thickness 0.15)
				)
				(justify mirror)
			)
		)
		(property "MPN" "GRM155R61H104KE14D"
			(at 47.89 195.11 0)
			(layer "B.Fab")
			(hide yes)
			(effects
				(font
					(size 1 1)
					(thickness 0.15)
				)
				(justify mirror)
			)
		)
		(property "Manufacturer" "Murata"
			(at 47.89 195.11 0)
			(layer "B.Fab")
			(hide yes)
			(effects
				(font
					(size 1 1)
					(thickness 0.15)
				)
				(justify mirror)
			)
		)
		(property "Public" "False"
			(at 47.89 195.11 0)
			(layer "B.Fab")
			(hide yes)
			(effects
				(font
					(size 1 1)
					(thickness 0.15)
				)
				(justify mirror)
			)
		)
		(property "Val" "100n"
			(at 47.89 195.11 0)
			(layer "B.Fab")
			(hide yes)
			(effects
				(font
					(size 1 1)
					(thickness 0.15)
				)
				(justify mirror)
			)
		)
		(property "Voltage" "50V"
			(at 47.89 195.11 0)
			(layer "B.Fab")
			(hide yes)
			(effects
				(font
					(size 1 1)
					(thickness 0.15)
				)
				(justify mirror)
			)
		)
		(sheetname "USB-C console")
		(sheetfile "usb-c_console.kicad_sch")
		(attr smd)
		(fp_rect
			(start -0.925 0.47)
			(end 0.925 -0.47)
			(stroke
				(width 0.05)
				(type default)
			)
			(fill no)
			(layer "B.CrtYd")
		)
		(fp_line
			(start -0.494 0.25)
			(end -0.494 -0.248)
			(stroke
				(width 0.15)
				(type solid)
			)
			(layer "B.Fab")
		)
		(fp_line
			(start 0.504 0.25)
			(end -0.494 0.25)
			(stroke
				(width 0.15)
				(type solid)
			)
			(layer "B.Fab")
		)
		(fp_line
			(start -0.494 -0.248)
			(end 0.504 -0.248)
			(stroke
				(width 0.15)
				(type solid)
			)
			(layer "B.Fab")
		)
		(fp_line
			(start 0.504 -0.248)
			(end 0.504 0.25)
			(stroke
				(width 0.15)
				(type solid)
			)
			(layer "B.Fab")
		)
		(pad "1" smd roundrect
			(at -0.48 0 270)
			(size 0.59 0.64)
			(layers "B.Cu" "B.Mask" "B.Paste")
			(roundrect_rratio 0.25)
			(net 1 "GND")
			(pintype "passive")
			(teardrops
				(best_length_ratio 0.2)
				(max_length 1)
				(best_width_ratio 0.9)
				(max_width 2)
				(curved_edges yes)
				(filter_ratio 0.9)
				(enabled yes)
				(allow_two_segments yes)
				(prefer_zone_connections yes)
			)
		)
		(pad "2" smd roundrect
			(at 0.48 0 270)
			(size 0.59 0.64)
			(layers "B.Cu" "B.Mask" "B.Paste")
			(roundrect_rratio 0.25)
			(net 2 "+3V3")
			(pintype "passive")
			(teardrops
				(best_length_ratio 0.2)
				(max_length 1)
				(best_width_ratio 0.9)
				(max_width 2)
				(curved_edges yes)
				(filter_ratio 0.9)
				(enabled yes)
				(allow_two_segments yes)
				(prefer_zone_connections yes)
			)
		)
	)
	(footprint "antmicro-footprints:R_0402_1005Metric"
		(layer "B.Cu")
		(at 126.09 141.06)
		(descr "Resistor SMD 0402")
		(tags "resistor SMD 0402")
		(property "Reference" "R292"
			(at -3.64 1.1 0)
			(layer "B.SilkS")
			(effects
				(font
					(size 0.7 0.7)
					(thickness 0.15)
				)
				(justify right bottom mirror)
			)
		)
		(property "Value" "R_10k_0402"
			(at -1.011843 -1.772047 0)
			(layer "B.Fab")
			(effects
				(font
					(size 0.7 0.7)
					(thickness 0.15)
				)
				(justify right bottom mirror)
			)
		)
		(property "Datasheet" "https://www.bourns.com/docs/product-datasheets/cr.pdf"
			(at 0 0 0)
			(layer "F.Fab")
			(hide yes)
			(effects
				(font
					(size 1.27 1.27)
					(thickness 0.15)
				)
			)
		)
		(property "Author" "Antmicro"
			(at 0 0 0)
			(layer "B.Fab")
			(hide yes)
			(effects
				(font
					(size 1 1)
					(thickness 0.15)
				)
				(justify mirror)
			)
		)
		(property "License" "Apache-2.0"
			(at 0 0 0)
			(layer "B.Fab")
			(hide yes)
			(effects
				(font
					(size 1 1)
					(thickness 0.15)
				)
				(justify mirror)
			)
		)
		(property "MPN" "CR0402-FX-1002GLF"
			(at 0 0 0)
			(layer "B.Fab")
			(hide yes)
			(effects
				(font
					(size 1 1)
					(thickness 0.15)
				)
				(justify mirror)
			)
		)
		(property "Manufacturer" "Bourns"
			(at 0 0 0)
			(layer "B.Fab")
			(hide yes)
			(effects
				(font
					(size 1 1)
					(thickness 0.15)
				)
				(justify mirror)
			)
		)
		(property "Public" "False"
			(at 0 0 0)
			(layer "B.Fab")
			(hide yes)
			(effects
				(font
					(size 1 1)
					(thickness 0.15)
				)
				(justify mirror)
			)
		)
		(property "Tolerance" "1%"
			(at 0 0 0)
			(layer "B.Fab")
			(hide yes)
			(effects
				(font
					(size 1 1)
					(thickness 0.15)
				)
				(justify mirror)
			)
		)
		(property "Val" "10k"
			(at 0 0 0)
			(layer "B.Fab")
			(hide yes)
			(effects
				(font
					(size 1 1)
					(thickness 0.15)
				)
				(justify mirror)
			)
		)
		(sheetname "KR to SFI #2")
		(sheetfile "kr_sfi.kicad_sch")
		(attr smd)
		(fp_rect
			(start -0.925 0.47)
			(end 0.925 -0.47)
			(stroke
				(width 0.05)
				(type default)
			)
			(fill no)
			(layer "B.CrtYd")
		)
		(fp_rect
			(start -0.5 0.25)
			(end 0.5 -0.25)
			(stroke
				(width 0.15)
				(type solid)
			)
			(fill no)
			(layer "B.Fab")
		)
		(pad "1" smd roundrect
			(at -0.48 0)
			(size 0.59 0.64)
			(layers "B.Cu" "B.Mask" "B.Paste")
			(roundrect_rratio 0.25)
			(net 1 "GND")
			(pintype "passive")
			(teardrops
				(best_length_ratio 0.2)
				(max_length 1)
				(best_width_ratio 0.9)
				(max_width 2)
				(curved_edges yes)
				(filter_ratio 0.9)
				(enabled yes)
				(allow_two_segments yes)
				(prefer_zone_connections yes)
			)
		)
		(pad "2" smd roundrect
			(at 0.48 0)
			(size 0.59 0.64)
			(layers "B.Cu" "B.Mask" "B.Paste")
			(roundrect_rratio 0.25)
			(net 675 "Net-(U45C-GPI0)")
			(pintype "passive")
			(teardrops
				(best_length_ratio 0.2)
				(max_length 1)
				(best_width_ratio 0.9)
				(max_width 2)
				(curved_edges yes)
				(filter_ratio 0.9)
				(enabled yes)
				(allow_two_segments yes)
				(prefer_zone_connections yes)
			)
		)
	)
	(footprint "antmicro-footprints:R_0402_1005Metric"
		(layer "B.Cu")
		(at 99.3 75.81)
		(descr "Resistor SMD 0402")
		(tags "resistor SMD 0402")
		(property "Reference" "R153"
			(at -3.65 0.4 0)
			(layer "B.SilkS")
			(effects
				(font
					(size 0.7 0.7)
					(thickness 0.15)
				)
				(justify right bottom mirror)
			)
		)
		(property "Value" "R_10k_0402"
			(at -1.011843 -1.772047 0)
			(layer "B.Fab")
			(effects
				(font
					(size 0.7 0.7)
					(thickness 0.15)
				)
				(justify right bottom mirror)
			)
		)
		(property "Datasheet" "https://www.bourns.com/docs/product-datasheets/cr.pdf"
			(at 0 0 0)
			(layer "F.Fab")
			(hide yes)
			(effects
				(font
					(size 1.27 1.27)
					(thickness 0.15)
				)
			)
		)
		(property "Description" "SMD Chip Resistor, 10 kohm, ± 1%, 62.5 mW, 0402 [1005 Metric], Thick Film, General Purpose"
			(at 0 0 0)
			(layer "F.Fab")
			(hide yes)
			(effects
				(font
					(size 1.27 1.27)
					(thickness 0.15)
				)
			)
		)
		(property "Author" "Antmicro"
			(at 0 0 0)
			(layer "B.Fab")
			(hide yes)
			(effects
				(font
					(size 1 1)
					(thickness 0.15)
				)
				(justify mirror)
			)
		)
		(property "License" "Apache-2.0"
			(at 0 0 0)
			(layer "B.Fab")
			(hide yes)
			(effects
				(font
					(size 1 1)
					(thickness 0.15)
				)
				(justify mirror)
			)
		)
		(property "MPN" "CR0402-FX-1002GLF"
			(at 0 0 0)
			(layer "B.Fab")
			(hide yes)
			(effects
				(font
					(size 1 1)
					(thickness 0.15)
				)
				(justify mirror)
			)
		)
		(property "Manufacturer" "Bourns"
			(at 0 0 0)
			(layer "B.Fab")
			(hide yes)
			(effects
				(font
					(size 1 1)
					(thickness 0.15)
				)
				(justify mirror)
			)
		)
		(property "Tolerance" "1%"
			(at 0 0 0)
			(layer "B.Fab")
			(hide yes)
			(effects
				(font
					(size 1 1)
					(thickness 0.15)
				)
				(justify mirror)
			)
		)
		(property "Val" "10k"
			(at 0 0 0)
			(layer "B.Fab")
			(hide yes)
			(effects
				(font
					(size 1 1)
					(thickness 0.15)
				)
				(justify mirror)
			)
		)
		(sheetname "Misc")
		(sheetfile "misc.kicad_sch")
		(attr smd)
		(fp_rect
			(start -0.925 0.47)
			(end 0.925 -0.47)
			(stroke
				(width 0.05)
				(type default)
			)
			(fill no)
			(layer "B.CrtYd")
		)
		(fp_rect
			(start -0.5 0.25)
			(end 0.5 -0.25)
			(stroke
				(width 0.15)
				(type solid)
			)
			(fill no)
			(layer "B.Fab")
		)
		(pad "1" smd roundrect
			(at -0.48 0)
			(size 0.59 0.64)
			(layers "B.Cu" "B.Mask" "B.Paste")
			(roundrect_rratio 0.25)
			(net 540 "Net-(Q8-D)")
			(pintype "passive")
			(teardrops
				(best_length_ratio 0.2)
				(max_length 1)
				(best_width_ratio 0.9)
				(max_width 2)
				(curved_edges yes)
				(filter_ratio 0.9)
				(enabled yes)
				(allow_two_segments yes)
				(prefer_zone_connections yes)
			)
		)
		(pad "2" smd roundrect
			(at 0.48 0)
			(size 0.59 0.64)
			(layers "B.Cu" "B.Mask" "B.Paste")
			(roundrect_rratio 0.25)
			(net 132 "Net-(D18-C_{R})")
			(pintype "passive")
			(teardrops
				(best_length_ratio 0.2)
				(max_length 1)
				(best_width_ratio 0.9)
				(max_width 2)
				(curved_edges yes)
				(filter_ratio 0.9)
				(enabled yes)
				(allow_two_segments yes)
				(prefer_zone_connections yes)
			)
		)
	)
	(footprint "antmicro-footprints:R_0402_1005Metric"
		(layer "B.Cu")
		(at 123.4 100.86 180)
		(descr "Resistor SMD 0402")
		(tags "resistor SMD 0402")
		(property "Reference" "R330"
			(at -3.74 -0.44 0)
			(layer "B.SilkS")
			(effects
				(font
					(size 0.7 0.7)
					(thickness 0.15)
				)
				(justify left bottom mirror)
			)
		)
		(property "Value" "R_470R_0402"
			(at -1.011843 -1.772047 0)
			(layer "B.Fab")
			(effects
				(font
					(size 0.7 0.7)
					(thickness 0.15)
				)
				(justify left bottom mirror)
			)
		)
		(property "Datasheet" "https://www.bourns.com/docs/product-datasheets/cr.pdf"
			(at 0 0 0)
			(layer "B.Fab")
			(hide yes)
			(effects
				(font
					(size 1.27 1.27)
					(thickness 0.15)
				)
				(justify mirror)
			)
		)
		(property "MPN" "CR0402-FX-4700GLF"
			(at 0 0 0)
			(unlocked yes)
			(layer "B.Fab")
			(hide yes)
			(effects
				(font
					(size 1 1)
					(thickness 0.15)
				)
				(justify mirror)
			)
		)
		(property "Manufacturer" "Bourns"
			(at 0 0 0)
			(unlocked yes)
			(layer "B.Fab")
			(hide yes)
			(effects
				(font
					(size 1 1)
					(thickness 0.15)
				)
				(justify mirror)
			)
		)
		(property "License" "Apache-2.0"
			(at 0 0 0)
			(unlocked yes)
			(layer "B.Fab")
			(hide yes)
			(effects
				(font
					(size 1 1)
					(thickness 0.15)
				)
				(justify mirror)
			)
		)
		(property "Author" "Antmicro"
			(at 0 0 0)
			(unlocked yes)
			(layer "B.Fab")
			(hide yes)
			(effects
				(font
					(size 1 1)
					(thickness 0.15)
				)
				(justify mirror)
			)
		)
		(property "Val" "470R"
			(at 0 0 0)
			(unlocked yes)
			(layer "B.Fab")
			(hide yes)
			(effects
				(font
					(size 1 1)
					(thickness 0.15)
				)
				(justify mirror)
			)
		)
		(property "Tolerance" "1%"
			(at 0 0 0)
			(unlocked yes)
			(layer "B.Fab")
			(hide yes)
			(effects
				(font
					(size 1 1)
					(thickness 0.15)
				)
				(justify mirror)
			)
		)
		(property "Public" "False"
			(at 0 0 0)
			(unlocked yes)
			(layer "B.Fab")
			(hide yes)
			(effects
				(font
					(size 1 1)
					(thickness 0.15)
				)
				(justify mirror)
			)
		)
		(sheetname "2xUSB3.0+RJ45")
		(sheetfile "usb3+rj45.kicad_sch")
		(attr smd)
		(fp_rect
			(start -0.925 0.47)
			(end 0.925 -0.47)
			(stroke
				(width 0.05)
				(type default)
			)
			(fill no)
			(layer "B.CrtYd")
		)
		(fp_rect
			(start -0.5 0.25)
			(end 0.5 -0.25)
			(stroke
				(width 0.15)
				(type solid)
			)
			(fill no)
			(layer "B.Fab")
		)
		(pad "1" smd roundrect
			(at -0.48 0 180)
			(size 0.59 0.64)
			(layers "B.Cu" "B.Mask" "B.Paste")
			(roundrect_rratio 0.25)
			(net 1 "GND")
			(pintype "passive")
			(teardrops
				(best_length_ratio 0.2)
				(max_length 1)
				(best_width_ratio 0.9)
				(max_width 2)
				(curved_edges yes)
				(filter_ratio 0.9)
				(enabled yes)
				(allow_two_segments yes)
				(prefer_zone_connections yes)
			)
		)
		(pad "2" smd roundrect
			(at 0.48 0 180)
			(size 0.59 0.64)
			(layers "B.Cu" "B.Mask" "B.Paste")
			(roundrect_rratio 0.25)
			(net 155 "Net-(J1A-LED_D2)")
			(pintype "passive")
			(teardrops
				(best_length_ratio 0.2)
				(max_length 1)
				(best_width_ratio 0.9)
				(max_width 2)
				(curved_edges yes)
				(filter_ratio 0.9)
				(enabled yes)
				(allow_two_segments yes)
				(prefer_zone_connections yes)
			)
		)
	)
	(footprint "antmicro-footprints:R_0402_1005Metric"
		(layer "B.Cu")
		(at 123.4 96.86)
		(descr "Resistor SMD 0402")
		(tags "resistor SMD 0402")
		(property "Reference" "R7"
			(at 0.9 0.45 0)
			(layer "B.SilkS")
			(effects
				(font
					(size 0.7 0.7)
					(thickness 0.15)
				)
				(justify right bottom mirror)
			)
		)
		(property "Value" "R_470R_0402"
			(at -1.011843 -1.772047 0)
			(layer "B.Fab")
			(effects
				(font
					(size 0.7 0.7)
					(thickness 0.15)
				)
				(justify right bottom mirror)
			)
		)
		(property "Datasheet" "https://www.bourns.com/docs/product-datasheets/cr.pdf"
			(at 0 0 0)
			(layer "F.Fab")
			(hide yes)
			(effects
				(font
					(size 1.27 1.27)
					(thickness 0.15)
				)
			)
		)
		(property "Author" "Antmicro"
			(at 0 0 0)
			(layer "B.Fab")
			(hide yes)
			(effects
				(font
					(size 1 1)
					(thickness 0.15)
				)
				(justify mirror)
			)
		)
		(property "License" "Apache-2.0"
			(at 0 0 0)
			(layer "B.Fab")
			(hide yes)
			(effects
				(font
					(size 1 1)
					(thickness 0.15)
				)
				(justify mirror)
			)
		)
		(property "MPN" "CR0402-FX-4700GLF"
			(at 0 0 0)
			(layer "B.Fab")
			(hide yes)
			(effects
				(font
					(size 1 1)
					(thickness 0.15)
				)
				(justify mirror)
			)
		)
		(property "Manufacturer" "Bourns"
			(at 0 0 0)
			(layer "B.Fab")
			(hide yes)
			(effects
				(font
					(size 1 1)
					(thickness 0.15)
				)
				(justify mirror)
			)
		)
		(property "Public" "False"
			(at 0 0 0)
			(layer "B.Fab")
			(hide yes)
			(effects
				(font
					(size 1 1)
					(thickness 0.15)
				)
				(justify mirror)
			)
		)
		(property "Tolerance" "1%"
			(at 0 0 0)
			(layer "B.Fab")
			(hide yes)
			(effects
				(font
					(size 1 1)
					(thickness 0.15)
				)
				(justify mirror)
			)
		)
		(property "Val" "470R"
			(at 0 0 0)
			(layer "B.Fab")
			(hide yes)
			(effects
				(font
					(size 1 1)
					(thickness 0.15)
				)
				(justify mirror)
			)
		)
		(sheetname "2xUSB3.0+RJ45")
		(sheetfile "usb3+rj45.kicad_sch")
		(attr smd dnp)
		(fp_rect
			(start -0.925 0.47)
			(end 0.925 -0.47)
			(stroke
				(width 0.05)
				(type default)
			)
			(fill no)
			(layer "B.CrtYd")
		)
		(fp_rect
			(start -0.5 0.25)
			(end 0.5 -0.25)
			(stroke
				(width 0.15)
				(type solid)
			)
			(fill no)
			(layer "B.Fab")
		)
		(pad "1" smd roundrect
			(at -0.48 0)
			(size 0.59 0.64)
			(layers "B.Cu" "B.Mask" "B.Paste")
			(roundrect_rratio 0.25)
			(net 154 "Net-(J1A-LED_D1)")
			(pintype "passive")
			(teardrops
				(best_length_ratio 0.2)
				(max_length 1)
				(best_width_ratio 0.9)
				(max_width 2)
				(curved_edges yes)
				(filter_ratio 0.9)
				(enabled yes)
				(allow_two_segments yes)
				(prefer_zone_connections yes)
			)
		)
		(pad "2" smd roundrect
			(at 0.48 0)
			(size 0.59 0.64)
			(layers "B.Cu" "B.Mask" "B.Paste")
			(roundrect_rratio 0.25)
			(net 2 "+3V3")
			(pintype "passive")
			(teardrops
				(best_length_ratio 0.2)
				(max_length 1)
				(best_width_ratio 0.9)
				(max_width 2)
				(curved_edges yes)
				(filter_ratio 0.9)
				(enabled yes)
				(allow_two_segments yes)
				(prefer_zone_connections yes)
			)
		)
	)
	(footprint "antmicro-footprints:C_0402_1005Metric"
		(layer "B.Cu")
		(at 154.95 133.86 180)
		(descr "Capacitor SMD 0402")
		(tags "capacitor SMD 0402")
		(property "Reference" "C158"
			(at -3.7 -0.45 180)
			(layer "B.SilkS")
			(effects
				(font
					(size 0.7 0.7)
					(thickness 0.15)
				)
				(justify left bottom mirror)
			)
		)
		(property "Value" "C_100n_0402"
			(at -1.022927 -2.155213 0)
			(layer "B.Fab")
			(effects
				(font
					(size 0.7 0.7)
					(thickness 0.15)
				)
				(justify left bottom mirror)
			)
		)
		(property "Datasheet" "https://www.murata.com/products/productdetail?partno=GRM155R61H104KE14%23"
			(at 0 0 180)
			(layer "F.Fab")
			(hide yes)
			(effects
				(font
					(size 1.27 1.27)
					(thickness 0.15)
				)
			)
		)
		(property "Author" "Antmicro"
			(at 309.9 267.72 0)
			(layer "B.Fab")
			(hide yes)
			(effects
				(font
					(size 1 1)
					(thickness 0.15)
				)
				(justify mirror)
			)
		)
		(property "Dielectric" "X5R"
			(at 309.9 267.72 0)
			(layer "B.Fab")
			(hide yes)
			(effects
				(font
					(size 1 1)
					(thickness 0.15)
				)
				(justify mirror)
			)
		)
		(property "License" "Apache-2.0"
			(at 309.9 267.72 0)
			(layer "B.Fab")
			(hide yes)
			(effects
				(font
					(size 1 1)
					(thickness 0.15)
				)
				(justify mirror)
			)
		)
		(property "MPN" "GRM155R61H104KE14D"
			(at 309.9 267.72 0)
			(layer "B.Fab")
			(hide yes)
			(effects
				(font
					(size 1 1)
					(thickness 0.15)
				)
				(justify mirror)
			)
		)
		(property "Manufacturer" "Murata"
			(at 309.9 267.72 0)
			(layer "B.Fab")
			(hide yes)
			(effects
				(font
					(size 1 1)
					(thickness 0.15)
				)
				(justify mirror)
			)
		)
		(property "Public" "False"
			(at 309.9 267.72 0)
			(layer "B.Fab")
			(hide yes)
			(effects
				(font
					(size 1 1)
					(thickness 0.15)
				)
				(justify mirror)
			)
		)
		(property "Val" "100n"
			(at 309.9 267.72 0)
			(layer "B.Fab")
			(hide yes)
			(effects
				(font
					(size 1 1)
					(thickness 0.15)
				)
				(justify mirror)
			)
		)
		(property "Voltage" "50V"
			(at 309.9 267.72 0)
			(layer "B.Fab")
			(hide yes)
			(effects
				(font
					(size 1 1)
					(thickness 0.15)
				)
				(justify mirror)
			)
		)
		(sheetname "KR to SFI #1")
		(sheetfile "kr_sfi.kicad_sch")
		(attr smd)
		(fp_rect
			(start -0.925 0.47)
			(end 0.925 -0.47)
			(stroke
				(width 0.05)
				(type default)
			)
			(fill no)
			(layer "B.CrtYd")
		)
		(fp_line
			(start 0.504 0.25)
			(end -0.494 0.25)
			(stroke
				(width 0.15)
				(type solid)
			)
			(layer "B.Fab")
		)
		(fp_line
			(start 0.504 -0.248)
			(end 0.504 0.25)
			(stroke
				(width 0.15)
				(type solid)
			)
			(layer "B.Fab")
		)
		(fp_line
			(start -0.494 0.25)
			(end -0.494 -0.248)
			(stroke
				(width 0.15)
				(type solid)
			)
			(layer "B.Fab")
		)
		(fp_line
			(start -0.494 -0.248)
			(end 0.504 -0.248)
			(stroke
				(width 0.15)
				(type solid)
			)
			(layer "B.Fab")
		)
		(pad "1" smd roundrect
			(at -0.48 0 180)
			(size 0.59 0.64)
			(layers "B.Cu" "B.Mask" "B.Paste")
			(roundrect_rratio 0.25)
			(net 1 "GND")
			(pintype "passive")
			(teardrops
				(best_length_ratio 0.2)
				(max_length 1)
				(best_width_ratio 0.9)
				(max_width 2)
				(curved_edges yes)
				(filter_ratio 0.9)
				(enabled yes)
				(allow_two_segments yes)
				(prefer_zone_connections yes)
			)
		)
		(pad "2" smd roundrect
			(at 0.48 0 180)
			(size 0.59 0.64)
			(layers "B.Cu" "B.Mask" "B.Paste")
			(roundrect_rratio 0.25)
			(net 78 "+1V8")
			(pintype "passive")
			(teardrops
				(best_length_ratio 0.2)
				(max_length 1)
				(best_width_ratio 0.9)
				(max_width 2)
				(curved_edges yes)
				(filter_ratio 0.9)
				(enabled yes)
				(allow_two_segments yes)
				(prefer_zone_connections yes)
			)
		)
	)
	(footprint "antmicro-footprints:C_0402_1005Metric"
		(layer "B.Cu")
		(at 132.29 141.36 90)
		(descr "Capacitor SMD 0402")
		(tags "capacitor SMD 0402")
		(property "Reference" "C188"
			(at -3.65 0.11 90)
			(layer "B.SilkS")
			(effects
				(font
					(size 0.7 0.7)
					(thickness 0.15)
				)
				(justify right bottom mirror)
			)
		)
		(property "Value" "C_100n_0402"
			(at -1.022927 -2.155213 90)
			(layer "B.Fab")
			(effects
				(font
					(size 0.7 0.7)
					(thickness 0.15)
				)
				(justify right bottom mirror)
			)
		)
		(property "Datasheet" "https://www.murata.com/products/productdetail?partno=GRM155R61H104KE14%23"
			(at 0 0 90)
			(layer "F.Fab")
			(hide yes)
			(effects
				(font
					(size 1.27 1.27)
					(thickness 0.15)
				)
			)
		)
		(property "Author" "Antmicro"
			(at 273.65 9.07 0)
			(layer "B.Fab")
			(hide yes)
			(effects
				(font
					(size 1 1)
					(thickness 0.15)
				)
				(justify mirror)
			)
		)
		(property "Dielectric" "X5R"
			(at 273.65 9.07 0)
			(layer "B.Fab")
			(hide yes)
			(effects
				(font
					(size 1 1)
					(thickness 0.15)
				)
				(justify mirror)
			)
		)
		(property "License" "Apache-2.0"
			(at 273.65 9.07 0)
			(layer "B.Fab")
			(hide yes)
			(effects
				(font
					(size 1 1)
					(thickness 0.15)
				)
				(justify mirror)
			)
		)
		(property "MPN" "GRM155R61H104KE14D"
			(at 273.65 9.07 0)
			(layer "B.Fab")
			(hide yes)
			(effects
				(font
					(size 1 1)
					(thickness 0.15)
				)
				(justify mirror)
			)
		)
		(property "Manufacturer" "Murata"
			(at 273.65 9.07 0)
			(layer "B.Fab")
			(hide yes)
			(effects
				(font
					(size 1 1)
					(thickness 0.15)
				)
				(justify mirror)
			)
		)
		(property "Public" "False"
			(at 273.65 9.07 0)
			(layer "B.Fab")
			(hide yes)
			(effects
				(font
					(size 1 1)
					(thickness 0.15)
				)
				(justify mirror)
			)
		)
		(property "Val" "100n"
			(at 273.65 9.07 0)
			(layer "B.Fab")
			(hide yes)
			(effects
				(font
					(size 1 1)
					(thickness 0.15)
				)
				(justify mirror)
			)
		)
		(property "Voltage" "50V"
			(at 273.65 9.07 0)
			(layer "B.Fab")
			(hide yes)
			(effects
				(font
					(size 1 1)
					(thickness 0.15)
				)
				(justify mirror)
			)
		)
		(sheetname "KR to SFI #2")
		(sheetfile "kr_sfi.kicad_sch")
		(attr smd)
		(fp_rect
			(start -0.925 0.47)
			(end 0.925 -0.47)
			(stroke
				(width 0.05)
				(type default)
			)
			(fill no)
			(layer "B.CrtYd")
		)
		(fp_line
			(start 0.504 -0.248)
			(end 0.504 0.25)
			(stroke
				(width 0.15)
				(type solid)
			)
			(layer "B.Fab")
		)
		(fp_line
			(start -0.494 -0.248)
			(end 0.504 -0.248)
			(stroke
				(width 0.15)
				(type solid)
			)
			(layer "B.Fab")
		)
		(fp_line
			(start 0.504 0.25)
			(end -0.494 0.25)
			(stroke
				(width 0.15)
				(type solid)
			)
			(layer "B.Fab")
		)
		(fp_line
			(start -0.494 0.25)
			(end -0.494 -0.248)
			(stroke
				(width 0.15)
				(type solid)
			)
			(layer "B.Fab")
		)
		(pad "1" smd roundrect
			(at -0.48 0 90)
			(size 0.59 0.64)
			(layers "B.Cu" "B.Mask" "B.Paste")
			(roundrect_rratio 0.25)
			(net 1 "GND")
			(pintype "passive")
			(teardrops
				(best_length_ratio 0.2)
				(max_length 1)
				(best_width_ratio 0.9)
				(max_width 2)
				(curved_edges yes)
				(filter_ratio 0.9)
				(enabled yes)
				(allow_two_segments yes)
				(prefer_zone_connections yes)
			)
		)
		(pad "2" smd roundrect
			(at 0.48 0 90)
			(size 0.59 0.64)
			(layers "B.Cu" "B.Mask" "B.Paste")
			(roundrect_rratio 0.25)
			(net 74 "+1V0")
			(pintype "passive")
			(teardrops
				(best_length_ratio 0.2)
				(max_length 1)
				(best_width_ratio 0.9)
				(max_width 2)
				(curved_edges yes)
				(filter_ratio 0.9)
				(enabled yes)
				(allow_two_segments yes)
				(prefer_zone_connections yes)
			)
		)
	)
	(footprint "antmicro-footprints:LED_0603_1608Metric_G"
		(layer "B.Cu")
		(at 177.3 88.76)
		(descr "LED SMD 0603 Green")
		(tags "LED SMD 0603 Green")
		(property "Reference" "D13"
			(at -1.05 -0.7 0)
			(layer "B.SilkS")
			(effects
				(font
					(size 0.7 0.7)
					(thickness 0.15)
				)
				(justify right bottom mirror)
			)
		)
		(property "Value" "LED_G_0603_LTST-C190GKT"
			(at -0.001 -1.599 0)
			(layer "B.Fab")
			(effects
				(font
					(size 0.7 0.7)
					(thickness 0.15)
				)
				(justify right bottom mirror)
			)
		)
		(property "Datasheet" "https://media.digikey.com/pdf/Data%20Sheets/Lite-On%20PDFs/LTST-C190GKT.pdf"
			(at 0 0 0)
			(layer "F.Fab")
			(hide yes)
			(effects
				(font
					(size 1.27 1.27)
					(thickness 0.15)
				)
			)
		)
		(property "Author" "Antmicro"
			(at 0 0 0)
			(layer "B.Fab")
			(hide yes)
			(effects
				(font
					(size 1 1)
					(thickness 0.15)
				)
				(justify mirror)
			)
		)
		(property "Color" "Green"
			(at 0 0 0)
			(layer "B.Fab")
			(hide yes)
			(effects
				(font
					(size 1 1)
					(thickness 0.15)
				)
				(justify mirror)
			)
		)
		(property "License" "Apache-2.0"
			(at 0 0 0)
			(layer "B.Fab")
			(hide yes)
			(effects
				(font
					(size 1 1)
					(thickness 0.15)
				)
				(justify mirror)
			)
		)
		(property "MPN" "LTST-C190GKT"
			(at 0 0 0)
			(layer "B.Fab")
			(hide yes)
			(effects
				(font
					(size 1 1)
					(thickness 0.15)
				)
				(justify mirror)
			)
		)
		(property "Manufacturer" "Lite-On"
			(at 0 0 0)
			(layer "B.Fab")
			(hide yes)
			(effects
				(font
					(size 1 1)
					(thickness 0.15)
				)
				(justify mirror)
			)
		)
		(property "Public" "False"
			(at 0 0 0)
			(layer "B.Fab")
			(hide yes)
			(effects
				(font
					(size 1 1)
					(thickness 0.15)
				)
				(justify mirror)
			)
		)
		(sheetname "M.2 key M #1")
		(sheetfile "m2keym_low.kicad_sch")
		(attr smd)
		(fp_line
			(start -1.18 -0.321)
			(end -1.18 0.319)
			(stroke
				(width 0.15)
				(type solid)
			)
			(layer "B.SilkS")
		)
		(fp_line
			(start -0.24 -0.001008)
			(end -0.094672 -0.001008)
			(stroke
				(width 0.1)
				(type solid)
			)
			(layer "B.SilkS")
		)
		(fp_line
			(start -0.22 -0.35)
			(end 0.22 -0.35)
			(stroke
				(width 0.15)
				(type solid)
			)
			(layer "B.SilkS")
		)
		(fp_line
			(start -0.22 0.35)
			(end 0.22 0.35)
			(stroke
				(width 0.15)
				(type solid)
			)
			(layer "B.SilkS")
		)
		(fp_line
			(start -0.094672 -0.001008)
			(end 0.105328 -0.201008)
			(stroke
				(width 0.1)
				(type solid)
			)
			(layer "B.SilkS")
		)
		(fp_line
			(start -0.094672 0.198992)
			(end -0.094672 -0.201008)
			(stroke
				(width 0.1)
				(type solid)
			)
			(layer "B.SilkS")
		)
		(fp_line
			(start 0.105328 0.198992)
			(end -0.094672 -0.001008)
			(stroke
				(width 0.1)
				(type solid)
			)
			(layer "B.SilkS")
		)
		(fp_line
			(start 0.105328 0.198992)
			(end 0.105328 -0.201008)
			(stroke
				(width 0.1)
				(type solid)
			)
			(layer "B.SilkS")
		)
		(fp_line
			(start 0.24 -0.001)
			(end 0.105328 -0.001008)
			(stroke
				(width 0.1)
				(type solid)
			)
			(layer "B.SilkS")
		)
		(fp_rect
			(start 1.25 -0.65)
			(end -1.25 0.65)
			(stroke
				(width 0.05)
				(type solid)
			)
			(fill no)
			(layer "B.CrtYd")
		)
		(fp_line
			(start -0.597 0)
			(end -0.199 0)
			(stroke
				(width 0.15)
				(type solid)
			)
			(layer "B.Fab")
		)
		(fp_line
			(start -0.199 -0.1)
			(end -0.199 -0.2)
			(stroke
				(width 0.15)
				(type solid)
			)
			(layer "B.Fab")
		)
		(fp_line
			(start -0.199 -0.1)
			(end -0.199 0.202)
			(stroke
				(width 0.15)
				(type solid)
			)
			(layer "B.Fab")
		)
		(fp_line
			(start -0.101 0)
			(end 0.201 0.202)
			(stroke
				(width 0.15)
				(type solid)
			)
			(layer "B.Fab")
		)
		(fp_line
			(start 0.201 -0.2)
			(end -0.101 0)
			(stroke
				(width 0.15)
				(type solid)
			)
			(layer "B.Fab")
		)
		(fp_line
			(start 0.201 0)
			(end 0.201 -0.2)
			(stroke
				(width 0.15)
				(type solid)
			)
			(layer "B.Fab")
		)
		(fp_line
			(start 0.201 0)
			(end 0.599 0)
			(stroke
				(width 0.15)
				(type solid)
			)
			(layer "B.Fab")
		)
		(fp_line
			(start 0.201 0.202)
			(end 0.201 0)
			(stroke
				(width 0.15)
				(type solid)
			)
			(layer "B.Fab")
		)
		(fp_rect
			(start 0.848 -0.4)
			(end -0.85 0.402)
			(stroke
				(width 0.15)
				(type solid)
			)
			(fill no)
			(layer "B.Fab")
		)
		(pad "1" smd roundrect
			(at -0.7 0 180)
			(size 0.8 1)
			(layers "B.Cu" "B.Mask" "B.Paste")
			(roundrect_rratio 0.2)
			(net 935 "Net-(D13-C)")
			(pinfunction "C")
			(pintype "passive")
			(teardrops
				(best_length_ratio 0.2)
				(max_length 1)
				(best_width_ratio 0.9)
				(max_width 2)
				(curved_edges yes)
				(filter_ratio 0.9)
				(enabled yes)
				(allow_two_segments yes)
				(prefer_zone_connections yes)
			)
		)
		(pad "2" smd roundrect
			(at 0.7 0 180)
			(size 0.8 1)
			(layers "B.Cu" "B.Mask" "B.Paste")
			(roundrect_rratio 0.2)
			(net 891 "Net-(D13-A)")
			(pinfunction "A")
			(pintype "passive")
			(teardrops
				(best_length_ratio 0.2)
				(max_length 1)
				(best_width_ratio 0.9)
				(max_width 2)
				(curved_edges yes)
				(filter_ratio 0.9)
				(enabled yes)
				(allow_two_segments yes)
				(prefer_zone_connections yes)
			)
		)
	)
	(footprint "antmicro-footprints:R_0402_1005Metric"
		(layer "B.Cu")
		(at 179.890001 88.76)
		(descr "Resistor SMD 0402")
		(tags "resistor SMD 0402")
		(property "Reference" "R123"
			(at -1.390001 -0.5 0)
			(layer "B.SilkS")
			(effects
				(font
					(size 0.7 0.7)
					(thickness 0.15)
				)
				(justify right bottom mirror)
			)
		)
		(property "Value" "R_220R_0402"
			(at -1.011843 -1.772047 0)
			(layer "B.Fab")
			(effects
				(font
					(size 0.7 0.7)
					(thickness 0.15)
				)
				(justify right bottom mirror)
			)
		)
		(property "Datasheet" "https://www.bourns.com/docs/product-datasheets/cr.pdf"
			(at 0 0 0)
			(layer "F.Fab")
			(hide yes)
			(effects
				(font
					(size 1.27 1.27)
					(thickness 0.15)
				)
			)
		)
		(property "Author" "Antmicro"
			(at 0 0 0)
			(layer "B.Fab")
			(hide yes)
			(effects
				(font
					(size 1 1)
					(thickness 0.15)
				)
				(justify mirror)
			)
		)
		(property "License" "Apache-2.0"
			(at 0 0 0)
			(layer "B.Fab")
			(hide yes)
			(effects
				(font
					(size 1 1)
					(thickness 0.15)
				)
				(justify mirror)
			)
		)
		(property "MPN" "CR0402-FX-2200GLF"
			(at 0 0 0)
			(layer "B.Fab")
			(hide yes)
			(effects
				(font
					(size 1 1)
					(thickness 0.15)
				)
				(justify mirror)
			)
		)
		(property "Manufacturer" "Bourns"
			(at 0 0 0)
			(layer "B.Fab")
			(hide yes)
			(effects
				(font
					(size 1 1)
					(thickness 0.15)
				)
				(justify mirror)
			)
		)
		(property "Public" "False"
			(at 0 0 0)
			(layer "B.Fab")
			(hide yes)
			(effects
				(font
					(size 1 1)
					(thickness 0.15)
				)
				(justify mirror)
			)
		)
		(property "Tolerance" "1%"
			(at 0 0 0)
			(layer "B.Fab")
			(hide yes)
			(effects
				(font
					(size 1 1)
					(thickness 0.15)
				)
				(justify mirror)
			)
		)
		(property "Val" "220R"
			(at 0 0 0)
			(layer "B.Fab")
			(hide yes)
			(effects
				(font
					(size 1 1)
					(thickness 0.15)
				)
				(justify mirror)
			)
		)
		(sheetname "M.2 key M #1")
		(sheetfile "m2keym_low.kicad_sch")
		(attr smd)
		(fp_rect
			(start -0.925 0.47)
			(end 0.925 -0.47)
			(stroke
				(width 0.05)
				(type default)
			)
			(fill no)
			(layer "B.CrtYd")
		)
		(fp_rect
			(start -0.5 0.25)
			(end 0.5 -0.25)
			(stroke
				(width 0.15)
				(type solid)
			)
			(fill no)
			(layer "B.Fab")
		)
		(pad "1" smd roundrect
			(at -0.48 0)
			(size 0.59 0.64)
			(layers "B.Cu" "B.Mask" "B.Paste")
			(roundrect_rratio 0.25)
			(net 891 "Net-(D13-A)")
			(pintype "passive")
			(teardrops
				(best_length_ratio 0.2)
				(max_length 1)
				(best_width_ratio 0.9)
				(max_width 2)
				(curved_edges yes)
				(filter_ratio 0.9)
				(enabled yes)
				(allow_two_segments yes)
				(prefer_zone_connections yes)
			)
		)
		(pad "2" smd roundrect
			(at 0.48 0)
			(size 0.59 0.64)
			(layers "B.Cu" "B.Mask" "B.Paste")
			(roundrect_rratio 0.25)
			(net 2 "+3V3")
			(pintype "passive")
			(teardrops
				(best_length_ratio 0.2)
				(max_length 1)
				(best_width_ratio 0.9)
				(max_width 2)
				(curved_edges yes)
				(filter_ratio 0.9)
				(enabled yes)
				(allow_two_segments yes)
				(prefer_zone_connections yes)
			)
		)
	)
	(footprint "antmicro-footprints:R_0402_1005Metric"
		(layer "B.Cu")
		(at 148.86 133.87 180)
		(descr "Resistor SMD 0402")
		(tags "resistor SMD 0402")
		(property "Reference" "R267"
			(at 0.36 4.91 0)
			(layer "B.SilkS")
			(effects
				(font
					(size 0.7 0.7)
					(thickness 0.15)
				)
				(justify left bottom mirror)
			)
		)
		(property "Value" "R_10k_0402"
			(at -1.011843 -1.772047 0)
			(layer "B.Fab")
			(effects
				(font
					(size 0.7 0.7)
					(thickness 0.15)
				)
				(justify left bottom mirror)
			)
		)
		(property "Datasheet" "https://www.bourns.com/docs/product-datasheets/cr.pdf"
			(at 0 0 180)
			(layer "F.Fab")
			(hide yes)
			(effects
				(font
					(size 1.27 1.27)
					(thickness 0.15)
				)
			)
		)
		(property "Author" "Antmicro"
			(at 297.72 267.74 0)
			(layer "B.Fab")
			(hide yes)
			(effects
				(font
					(size 1 1)
					(thickness 0.15)
				)
				(justify mirror)
			)
		)
		(property "License" "Apache-2.0"
			(at 297.72 267.74 0)
			(layer "B.Fab")
			(hide yes)
			(effects
				(font
					(size 1 1)
					(thickness 0.15)
				)
				(justify mirror)
			)
		)
		(property "MPN" "CR0402-FX-1002GLF"
			(at 297.72 267.74 0)
			(layer "B.Fab")
			(hide yes)
			(effects
				(font
					(size 1 1)
					(thickness 0.15)
				)
				(justify mirror)
			)
		)
		(property "Manufacturer" "Bourns"
			(at 297.72 267.74 0)
			(layer "B.Fab")
			(hide yes)
			(effects
				(font
					(size 1 1)
					(thickness 0.15)
				)
				(justify mirror)
			)
		)
		(property "Public" "False"
			(at 297.72 267.74 0)
			(layer "B.Fab")
			(hide yes)
			(effects
				(font
					(size 1 1)
					(thickness 0.15)
				)
				(justify mirror)
			)
		)
		(property "Tolerance" "1%"
			(at 297.72 267.74 0)
			(layer "B.Fab")
			(hide yes)
			(effects
				(font
					(size 1 1)
					(thickness 0.15)
				)
				(justify mirror)
			)
		)
		(property "Val" "10k"
			(at 297.72 267.74 0)
			(layer "B.Fab")
			(hide yes)
			(effects
				(font
					(size 1 1)
					(thickness 0.15)
				)
				(justify mirror)
			)
		)
		(sheetname "KR to SFI #1")
		(sheetfile "kr_sfi.kicad_sch")
		(attr smd)
		(fp_rect
			(start -0.925 0.47)
			(end 0.925 -0.47)
			(stroke
				(width 0.05)
				(type default)
			)
			(fill no)
			(layer "B.CrtYd")
		)
		(fp_rect
			(start -0.5 0.25)
			(end 0.5 -0.25)
			(stroke
				(width 0.15)
				(type solid)
			)
			(fill no)
			(layer "B.Fab")
		)
		(pad "1" smd roundrect
			(at -0.48 0 180)
			(size 0.59 0.64)
			(layers "B.Cu" "B.Mask" "B.Paste")
			(roundrect_rratio 0.25)
			(net 660 "Net-(U43B-~{PDTRXB})")
			(pintype "passive")
			(teardrops
				(best_length_ratio 0.2)
				(max_length 1)
				(best_width_ratio 0.9)
				(max_width 2)
				(curved_edges yes)
				(filter_ratio 0.9)
				(enabled yes)
				(allow_two_segments yes)
				(prefer_zone_connections yes)
			)
		)
		(pad "2" smd roundrect
			(at 0.48 0 180)
			(size 0.59 0.64)
			(layers "B.Cu" "B.Mask" "B.Paste")
			(roundrect_rratio 0.25)
			(net 78 "+1V8")
			(pintype "passive")
			(teardrops
				(best_length_ratio 0.2)
				(max_length 1)
				(best_width_ratio 0.9)
				(max_width 2)
				(curved_edges yes)
				(filter_ratio 0.9)
				(enabled yes)
				(allow_two_segments yes)
				(prefer_zone_connections yes)
			)
		)
	)
	(footprint "antmicro-footprints:C_0402_1005Metric"
		(layer "B.Cu")
		(at 132.29 132.36 -90)
		(descr "Capacitor SMD 0402")
		(tags "capacitor SMD 0402")
		(property "Reference" "C198"
			(at -3.7 -0.41 90)
			(layer "B.SilkS")
			(effects
				(font
					(size 0.7 0.7)
					(thickness 0.15)
				)
				(justify left bottom mirror)
			)
		)
		(property "Value" "C_100n_0402"
			(at -1.022927 -2.155213 90)
			(layer "B.Fab")
			(effects
				(font
					(size 0.7 0.7)
					(thickness 0.15)
				)
				(justify left bottom mirror)
			)
		)
		(property "Datasheet" "https://www.murata.com/products/productdetail?partno=GRM155R61H104KE14%23"
			(at 0 0 270)
			(layer "F.Fab")
			(hide yes)
			(effects
				(font
					(size 1.27 1.27)
					(thickness 0.15)
				)
			)
		)
		(property "Author" "Antmicro"
			(at -0.07 264.65 0)
			(layer "B.Fab")
			(hide yes)
			(effects
				(font
					(size 1 1)
					(thickness 0.15)
				)
				(justify mirror)
			)
		)
		(property "Dielectric" "X5R"
			(at -0.07 264.65 0)
			(layer "B.Fab")
			(hide yes)
			(effects
				(font
					(size 1 1)
					(thickness 0.15)
				)
				(justify mirror)
			)
		)
		(property "License" "Apache-2.0"
			(at -0.07 264.65 0)
			(layer "B.Fab")
			(hide yes)
			(effects
				(font
					(size 1 1)
					(thickness 0.15)
				)
				(justify mirror)
			)
		)
		(property "MPN" "GRM155R61H104KE14D"
			(at -0.07 264.65 0)
			(layer "B.Fab")
			(hide yes)
			(effects
				(font
					(size 1 1)
					(thickness 0.15)
				)
				(justify mirror)
			)
		)
		(property "Manufacturer" "Murata"
			(at -0.07 264.65 0)
			(layer "B.Fab")
			(hide yes)
			(effects
				(font
					(size 1 1)
					(thickness 0.15)
				)
				(justify mirror)
			)
		)
		(property "Public" "False"
			(at -0.07 264.65 0)
			(layer "B.Fab")
			(hide yes)
			(effects
				(font
					(size 1 1)
					(thickness 0.15)
				)
				(justify mirror)
			)
		)
		(property "Val" "100n"
			(at -0.07 264.65 0)
			(layer "B.Fab")
			(hide yes)
			(effects
				(font
					(size 1 1)
					(thickness 0.15)
				)
				(justify mirror)
			)
		)
		(property "Voltage" "50V"
			(at -0.07 264.65 0)
			(layer "B.Fab")
			(hide yes)
			(effects
				(font
					(size 1 1)
					(thickness 0.15)
				)
				(justify mirror)
			)
		)
		(sheetname "KR to SFI #2")
		(sheetfile "kr_sfi.kicad_sch")
		(attr smd)
		(fp_rect
			(start -0.925 0.47)
			(end 0.925 -0.47)
			(stroke
				(width 0.05)
				(type default)
			)
			(fill no)
			(layer "B.CrtYd")
		)
		(fp_line
			(start -0.494 0.25)
			(end -0.494 -0.248)
			(stroke
				(width 0.15)
				(type solid)
			)
			(layer "B.Fab")
		)
		(fp_line
			(start 0.504 0.25)
			(end -0.494 0.25)
			(stroke
				(width 0.15)
				(type solid)
			)
			(layer "B.Fab")
		)
		(fp_line
			(start -0.494 -0.248)
			(end 0.504 -0.248)
			(stroke
				(width 0.15)
				(type solid)
			)
			(layer "B.Fab")
		)
		(fp_line
			(start 0.504 -0.248)
			(end 0.504 0.25)
			(stroke
				(width 0.15)
				(type solid)
			)
			(layer "B.Fab")
		)
		(pad "1" smd roundrect
			(at -0.48 0 270)
			(size 0.59 0.64)
			(layers "B.Cu" "B.Mask" "B.Paste")
			(roundrect_rratio 0.25)
			(net 1 "GND")
			(pintype "passive")
			(teardrops
				(best_length_ratio 0.2)
				(max_length 1)
				(best_width_ratio 0.9)
				(max_width 2)
				(curved_edges yes)
				(filter_ratio 0.9)
				(enabled yes)
				(allow_two_segments yes)
				(prefer_zone_connections yes)
			)
		)
		(pad "2" smd roundrect
			(at 0.48 0 270)
			(size 0.59 0.64)
			(layers "B.Cu" "B.Mask" "B.Paste")
			(roundrect_rratio 0.25)
			(net 74 "+1V0")
			(pintype "passive")
			(teardrops
				(best_length_ratio 0.2)
				(max_length 1)
				(best_width_ratio 0.9)
				(max_width 2)
				(curved_edges yes)
				(filter_ratio 0.9)
				(enabled yes)
				(allow_two_segments yes)
				(prefer_zone_connections yes)
			)
		)
	)
	(footprint "antmicro-footprints:C_0402_1005Metric"
		(layer "B.Cu")
		(at 256.350707 78.135)
		(descr "Capacitor SMD 0402")
		(tags "capacitor SMD 0402")
		(property "Reference" "C84"
			(at -1.079999 1.375 0)
			(layer "B.SilkS")
			(effects
				(font
					(size 0.7 0.7)
					(thickness 0.15)
				)
				(justify right bottom mirror)
			)
		)
		(property "Value" "C_100n_0402"
			(at -1.022927 -2.155213 0)
			(layer "B.Fab")
			(effects
				(font
					(size 0.7 0.7)
					(thickness 0.15)
				)
				(justify right bottom mirror)
			)
		)
		(property "Datasheet" "https://www.murata.com/products/productdetail?partno=GRM155R61H104KE14%23"
			(at 0 0 0)
			(layer "F.Fab")
			(hide yes)
			(effects
				(font
					(size 1.27 1.27)
					(thickness 0.15)
				)
			)
		)
		(property "Author" "Antmicro"
			(at 0 0 0)
			(layer "B.Fab")
			(hide yes)
			(effects
				(font
					(size 1 1)
					(thickness 0.15)
				)
				(justify mirror)
			)
		)
		(property "Dielectric" "X5R"
			(at 0 0 0)
			(layer "B.Fab")
			(hide yes)
			(effects
				(font
					(size 1 1)
					(thickness 0.15)
				)
				(justify mirror)
			)
		)
		(property "License" "Apache-2.0"
			(at 0 0 0)
			(layer "B.Fab")
			(hide yes)
			(effects
				(font
					(size 1 1)
					(thickness 0.15)
				)
				(justify mirror)
			)
		)
		(property "MPN" "GRM155R61H104KE14D"
			(at 0 0 0)
			(layer "B.Fab")
			(hide yes)
			(effects
				(font
					(size 1 1)
					(thickness 0.15)
				)
				(justify mirror)
			)
		)
		(property "Manufacturer" "Murata"
			(at 0 0 0)
			(layer "B.Fab")
			(hide yes)
			(effects
				(font
					(size 1 1)
					(thickness 0.15)
				)
				(justify mirror)
			)
		)
		(property "Public" "False"
			(at 0 0 0)
			(layer "B.Fab")
			(hide yes)
			(effects
				(font
					(size 1 1)
					(thickness 0.15)
				)
				(justify mirror)
			)
		)
		(property "Val" "100n"
			(at 0 0 0)
			(layer "B.Fab")
			(hide yes)
			(effects
				(font
					(size 1 1)
					(thickness 0.15)
				)
				(justify mirror)
			)
		)
		(property "Voltage" "50V"
			(at 0 0 0)
			(layer "B.Fab")
			(hide yes)
			(effects
				(font
					(size 1 1)
					(thickness 0.15)
				)
				(justify mirror)
			)
		)
		(sheetname "Misc")
		(sheetfile "misc.kicad_sch")
		(attr smd)
		(fp_rect
			(start -0.925 0.47)
			(end 0.925 -0.47)
			(stroke
				(width 0.05)
				(type default)
			)
			(fill no)
			(layer "B.CrtYd")
		)
		(fp_line
			(start -0.494 -0.248)
			(end 0.504 -0.248)
			(stroke
				(width 0.15)
				(type solid)
			)
			(layer "B.Fab")
		)
		(fp_line
			(start -0.494 0.25)
			(end -0.494 -0.248)
			(stroke
				(width 0.15)
				(type solid)
			)
			(layer "B.Fab")
		)
		(fp_line
			(start 0.504 -0.248)
			(end 0.504 0.25)
			(stroke
				(width 0.15)
				(type solid)
			)
			(layer "B.Fab")
		)
		(fp_line
			(start 0.504 0.25)
			(end -0.494 0.25)
			(stroke
				(width 0.15)
				(type solid)
			)
			(layer "B.Fab")
		)
		(pad "1" smd roundrect
			(at -0.48 0)
			(size 0.59 0.64)
			(layers "B.Cu" "B.Mask" "B.Paste")
			(roundrect_rratio 0.25)
			(net 1 "GND")
			(pintype "passive")
			(teardrops
				(best_length_ratio 0.2)
				(max_length 1)
				(best_width_ratio 0.9)
				(max_width 2)
				(curved_edges yes)
				(filter_ratio 0.9)
				(enabled yes)
				(allow_two_segments yes)
				(prefer_zone_connections yes)
			)
		)
		(pad "2" smd roundrect
			(at 0.48 0)
			(size 0.59 0.64)
			(layers "B.Cu" "B.Mask" "B.Paste")
			(roundrect_rratio 0.25)
			(net 2 "+3V3")
			(pintype "passive")
			(teardrops
				(best_length_ratio 0.2)
				(max_length 1)
				(best_width_ratio 0.9)
				(max_width 2)
				(curved_edges yes)
				(filter_ratio 0.9)
				(enabled yes)
				(allow_two_segments yes)
				(prefer_zone_connections yes)
			)
		)
	)
	(footprint "antmicro-footprints:R_0402_1005Metric"
		(layer "B.Cu")
		(at 139.74 141.36)
		(descr "Resistor SMD 0402")
		(tags "resistor SMD 0402")
		(property "Reference" "R294"
			(at -3.64 0.75 0)
			(layer "B.SilkS")
			(effects
				(font
					(size 0.7 0.7)
					(thickness 0.15)
				)
				(justify right bottom mirror)
			)
		)
		(property "Value" "R_10k_0402"
			(at -1.011843 -1.772047 0)
			(layer "B.Fab")
			(effects
				(font
					(size 0.7 0.7)
					(thickness 0.15)
				)
				(justify right bottom mirror)
			)
		)
		(property "Datasheet" "https://www.bourns.com/docs/product-datasheets/cr.pdf"
			(at 0 0 0)
			(layer "F.Fab")
			(hide yes)
			(effects
				(font
					(size 1.27 1.27)
					(thickness 0.15)
				)
			)
		)
		(property "Author" "Antmicro"
			(at 0 0 0)
			(layer "B.Fab")
			(hide yes)
			(effects
				(font
					(size 1 1)
					(thickness 0.15)
				)
				(justify mirror)
			)
		)
		(property "License" "Apache-2.0"
			(at 0 0 0)
			(layer "B.Fab")
			(hide yes)
			(effects
				(font
					(size 1 1)
					(thickness 0.15)
				)
				(justify mirror)
			)
		)
		(property "MPN" "CR0402-FX-1002GLF"
			(at 0 0 0)
			(layer "B.Fab")
			(hide yes)
			(effects
				(font
					(size 1 1)
					(thickness 0.15)
				)
				(justify mirror)
			)
		)
		(property "Manufacturer" "Bourns"
			(at 0 0 0)
			(layer "B.Fab")
			(hide yes)
			(effects
				(font
					(size 1 1)
					(thickness 0.15)
				)
				(justify mirror)
			)
		)
		(property "Public" "False"
			(at 0 0 0)
			(layer "B.Fab")
			(hide yes)
			(effects
				(font
					(size 1 1)
					(thickness 0.15)
				)
				(justify mirror)
			)
		)
		(property "Tolerance" "1%"
			(at 0 0 0)
			(layer "B.Fab")
			(hide yes)
			(effects
				(font
					(size 1 1)
					(thickness 0.15)
				)
				(justify mirror)
			)
		)
		(property "Val" "10k"
			(at 0 0 0)
			(layer "B.Fab")
			(hide yes)
			(effects
				(font
					(size 1 1)
					(thickness 0.15)
				)
				(justify mirror)
			)
		)
		(sheetname "KR to SFI #2")
		(sheetfile "kr_sfi.kicad_sch")
		(attr smd dnp)
		(fp_rect
			(start -0.925 0.47)
			(end 0.925 -0.47)
			(stroke
				(width 0.05)
				(type default)
			)
			(fill no)
			(layer "B.CrtYd")
		)
		(fp_rect
			(start -0.5 0.25)
			(end 0.5 -0.25)
			(stroke
				(width 0.15)
				(type solid)
			)
			(fill no)
			(layer "B.Fab")
		)
		(pad "1" smd roundrect
			(at -0.48 0)
			(size 0.59 0.64)
			(layers "B.Cu" "B.Mask" "B.Paste")
			(roundrect_rratio 0.25)
			(net 676 "Net-(U45C-PRTAD0)")
			(pintype "passive")
			(teardrops
				(best_length_ratio 0.2)
				(max_length 1)
				(best_width_ratio 0.9)
				(max_width 2)
				(curved_edges yes)
				(filter_ratio 0.9)
				(enabled yes)
				(allow_two_segments yes)
				(prefer_zone_connections yes)
			)
		)
		(pad "2" smd roundrect
			(at 0.48 0)
			(size 0.59 0.64)
			(layers "B.Cu" "B.Mask" "B.Paste")
			(roundrect_rratio 0.25)
			(net 78 "+1V8")
			(pintype "passive")
			(teardrops
				(best_length_ratio 0.2)
				(max_length 1)
				(best_width_ratio 0.9)
				(max_width 2)
				(curved_edges yes)
				(filter_ratio 0.9)
				(enabled yes)
				(allow_two_segments yes)
				(prefer_zone_connections yes)
			)
		)
	)
	(footprint "antmicro-footprints:R_0402_1005Metric"
		(layer "B.Cu")
		(at 116.45 69.86 -90)
		(descr "Resistor SMD 0402")
		(tags "resistor SMD 0402")
		(property "Reference" "R138"
			(at 0.8 -0.45 90)
			(layer "B.SilkS")
			(effects
				(font
					(size 0.7 0.7)
					(thickness 0.15)
				)
				(justify left bottom mirror)
			)
		)
		(property "Value" "R_220R_0402"
			(at -1.011843 -1.772047 90)
			(layer "B.Fab")
			(effects
				(font
					(size 0.7 0.7)
					(thickness 0.15)
				)
				(justify left bottom mirror)
			)
		)
		(property "Datasheet" "https://www.bourns.com/docs/product-datasheets/cr.pdf"
			(at 0 0 270)
			(layer "F.Fab")
			(hide yes)
			(effects
				(font
					(size 1.27 1.27)
					(thickness 0.15)
				)
			)
		)
		(property "Author" "Antmicro"
			(at 46.59 186.31 0)
			(layer "B.Fab")
			(hide yes)
			(effects
				(font
					(size 1 1)
					(thickness 0.15)
				)
				(justify mirror)
			)
		)
		(property "License" "Apache-2.0"
			(at 46.59 186.31 0)
			(layer "B.Fab")
			(hide yes)
			(effects
				(font
					(size 1 1)
					(thickness 0.15)
				)
				(justify mirror)
			)
		)
		(property "MPN" "CR0402-FX-2200GLF"
			(at 46.59 186.31 0)
			(layer "B.Fab")
			(hide yes)
			(effects
				(font
					(size 1 1)
					(thickness 0.15)
				)
				(justify mirror)
			)
		)
		(property "Manufacturer" "Bourns"
			(at 46.59 186.31 0)
			(layer "B.Fab")
			(hide yes)
			(effects
				(font
					(size 1 1)
					(thickness 0.15)
				)
				(justify mirror)
			)
		)
		(property "Public" "False"
			(at 46.59 186.31 0)
			(layer "B.Fab")
			(hide yes)
			(effects
				(font
					(size 1 1)
					(thickness 0.15)
				)
				(justify mirror)
			)
		)
		(property "Tolerance" "1%"
			(at 46.59 186.31 0)
			(layer "B.Fab")
			(hide yes)
			(effects
				(font
					(size 1 1)
					(thickness 0.15)
				)
				(justify mirror)
			)
		)
		(property "Val" "220R"
			(at 46.59 186.31 0)
			(layer "B.Fab")
			(hide yes)
			(effects
				(font
					(size 1 1)
					(thickness 0.15)
				)
				(justify mirror)
			)
		)
		(sheetname "M.2 key E")
		(sheetfile "m2keye.kicad_sch")
		(attr smd)
		(fp_rect
			(start -0.925 0.47)
			(end 0.925 -0.47)
			(stroke
				(width 0.05)
				(type default)
			)
			(fill no)
			(layer "B.CrtYd")
		)
		(fp_rect
			(start -0.5 0.25)
			(end 0.5 -0.25)
			(stroke
				(width 0.15)
				(type solid)
			)
			(fill no)
			(layer "B.Fab")
		)
		(pad "1" smd roundrect
			(at -0.48 0 270)
			(size 0.59 0.64)
			(layers "B.Cu" "B.Mask" "B.Paste")
			(roundrect_rratio 0.25)
			(net 937 "Net-(D15-A)")
			(pintype "passive")
			(teardrops
				(best_length_ratio 0.2)
				(max_length 1)
				(best_width_ratio 0.9)
				(max_width 2)
				(curved_edges yes)
				(filter_ratio 0.9)
				(enabled yes)
				(allow_two_segments yes)
				(prefer_zone_connections yes)
			)
		)
		(pad "2" smd roundrect
			(at 0.48 0 270)
			(size 0.59 0.64)
			(layers "B.Cu" "B.Mask" "B.Paste")
			(roundrect_rratio 0.25)
			(net 2 "+3V3")
			(pintype "passive")
			(teardrops
				(best_length_ratio 0.2)
				(max_length 1)
				(best_width_ratio 0.9)
				(max_width 2)
				(curved_edges yes)
				(filter_ratio 0.9)
				(enabled yes)
				(allow_two_segments yes)
				(prefer_zone_connections yes)
			)
		)
	)
	(footprint "antmicro-footprints:R_0402_1005Metric"
		(layer "B.Cu")
		(at 157.9 139.36)
		(descr "Resistor SMD 0402")
		(tags "resistor SMD 0402")
		(property "Reference" "R264"
			(at 0.85 0.45 0)
			(layer "B.SilkS")
			(effects
				(font
					(size 0.7 0.7)
					(thickness 0.15)
				)
				(justify right bottom mirror)
			)
		)
		(property "Value" "R_10k_0402"
			(at -1.011843 -1.772047 0)
			(layer "B.Fab")
			(effects
				(font
					(size 0.7 0.7)
					(thickness 0.15)
				)
				(justify right bottom mirror)
			)
		)
		(property "Datasheet" "https://www.bourns.com/docs/product-datasheets/cr.pdf"
			(at 0 0 0)
			(layer "F.Fab")
			(hide yes)
			(effects
				(font
					(size 1.27 1.27)
					(thickness 0.15)
				)
			)
		)
		(property "Author" "Antmicro"
			(at 0 0 0)
			(layer "B.Fab")
			(hide yes)
			(effects
				(font
					(size 1 1)
					(thickness 0.15)
				)
				(justify mirror)
			)
		)
		(property "License" "Apache-2.0"
			(at 0 0 0)
			(layer "B.Fab")
			(hide yes)
			(effects
				(font
					(size 1 1)
					(thickness 0.15)
				)
				(justify mirror)
			)
		)
		(property "MPN" "CR0402-FX-1002GLF"
			(at 0 0 0)
			(layer "B.Fab")
			(hide yes)
			(effects
				(font
					(size 1 1)
					(thickness 0.15)
				)
				(justify mirror)
			)
		)
		(property "Manufacturer" "Bourns"
			(at 0 0 0)
			(layer "B.Fab")
			(hide yes)
			(effects
				(font
					(size 1 1)
					(thickness 0.15)
				)
				(justify mirror)
			)
		)
		(property "Public" "False"
			(at 0 0 0)
			(layer "B.Fab")
			(hide yes)
			(effects
				(font
					(size 1 1)
					(thickness 0.15)
				)
				(justify mirror)
			)
		)
		(property "Tolerance" "1%"
			(at 0 0 0)
			(layer "B.Fab")
			(hide yes)
			(effects
				(font
					(size 1 1)
					(thickness 0.15)
				)
				(justify mirror)
			)
		)
		(property "Val" "10k"
			(at 0 0 0)
			(layer "B.Fab")
			(hide yes)
			(effects
				(font
					(size 1 1)
					(thickness 0.15)
				)
				(justify mirror)
			)
		)
		(sheetname "KR to SFI #1")
		(sheetfile "kr_sfi.kicad_sch")
		(attr smd)
		(fp_rect
			(start -0.925 0.47)
			(end 0.925 -0.47)
			(stroke
				(width 0.05)
				(type default)
			)
			(fill no)
			(layer "B.CrtYd")
		)
		(fp_rect
			(start -0.5 0.25)
			(end 0.5 -0.25)
			(stroke
				(width 0.15)
				(type solid)
			)
			(fill no)
			(layer "B.Fab")
		)
		(pad "1" smd roundrect
			(at -0.48 0)
			(size 0.59 0.64)
			(layers "B.Cu" "B.Mask" "B.Paste")
			(roundrect_rratio 0.25)
			(net 657 "Net-(U43A-~{PDTRXA})")
			(pintype "passive")
			(teardrops
				(best_length_ratio 0.2)
				(max_length 1)
				(best_width_ratio 0.9)
				(max_width 2)
				(curved_edges yes)
				(filter_ratio 0.9)
				(enabled yes)
				(allow_two_segments yes)
				(prefer_zone_connections yes)
			)
		)
		(pad "2" smd roundrect
			(at 0.48 0)
			(size 0.59 0.64)
			(layers "B.Cu" "B.Mask" "B.Paste")
			(roundrect_rratio 0.25)
			(net 78 "+1V8")
			(pintype "passive")
			(teardrops
				(best_length_ratio 0.2)
				(max_length 1)
				(best_width_ratio 0.9)
				(max_width 2)
				(curved_edges yes)
				(filter_ratio 0.9)
				(enabled yes)
				(allow_two_segments yes)
				(prefer_zone_connections yes)
			)
		)
	)
	(footprint "antmicro-footprints:R_0402_1005Metric"
		(layer "B.Cu")
		(at 123.4 97.86 180)
		(descr "Resistor SMD 0402")
		(tags "resistor SMD 0402")
		(property "Reference" "R1"
			(at -2.4 -0.45 0)
			(layer "B.SilkS")
			(effects
				(font
					(size 0.7 0.7)
					(thickness 0.15)
				)
				(justify left bottom mirror)
			)
		)
		(property "Value" "R_0R_0402"
			(at -1.011843 -1.772047 0)
			(layer "B.Fab")
			(effects
				(font
					(size 0.7 0.7)
					(thickness 0.15)
				)
				(justify left bottom mirror)
			)
		)
		(property "Datasheet" "https://industrial.panasonic.com/cdbs/www-data/pdf/RDA0000/AOA0000C301.pdf"
			(at 0 0 180)
			(layer "F.Fab")
			(hide yes)
			(effects
				(font
					(size 1.27 1.27)
					(thickness 0.15)
				)
			)
		)
		(property "Author" "Antmicro"
			(at 246.8 195.72 0)
			(layer "B.Fab")
			(hide yes)
			(effects
				(font
					(size 1 1)
					(thickness 0.15)
				)
				(justify mirror)
			)
		)
		(property "Current" "1A"
			(at 246.8 195.72 0)
			(layer "B.Fab")
			(hide yes)
			(effects
				(font
					(size 1 1)
					(thickness 0.15)
				)
				(justify mirror)
			)
		)
		(property "License" "Apache-2.0"
			(at 246.8 195.72 0)
			(layer "B.Fab")
			(hide yes)
			(effects
				(font
					(size 1 1)
					(thickness 0.15)
				)
				(justify mirror)
			)
		)
		(property "MPN" "ERJ2GE0R00X"
			(at 246.8 195.72 0)
			(layer "B.Fab")
			(hide yes)
			(effects
				(font
					(size 1 1)
					(thickness 0.15)
				)
				(justify mirror)
			)
		)
		(property "Manufacturer" "Panasonic"
			(at 246.8 195.72 0)
			(layer "B.Fab")
			(hide yes)
			(effects
				(font
					(size 1 1)
					(thickness 0.15)
				)
				(justify mirror)
			)
		)
		(property "Public" "False"
			(at 246.8 195.72 0)
			(layer "B.Fab")
			(hide yes)
			(effects
				(font
					(size 1 1)
					(thickness 0.15)
				)
				(justify mirror)
			)
		)
		(property "Tolerance" ""
			(at 246.8 195.72 0)
			(layer "B.Fab")
			(hide yes)
			(effects
				(font
					(size 1 1)
					(thickness 0.15)
				)
				(justify mirror)
			)
		)
		(property "Val" "0R"
			(at 246.8 195.72 0)
			(layer "B.Fab")
			(hide yes)
			(effects
				(font
					(size 1 1)
					(thickness 0.15)
				)
				(justify mirror)
			)
		)
		(sheetname "2xUSB3.0+RJ45")
		(sheetfile "usb3+rj45.kicad_sch")
		(attr smd)
		(fp_rect
			(start -0.925 0.47)
			(end 0.925 -0.47)
			(stroke
				(width 0.05)
				(type default)
			)
			(fill no)
			(layer "B.CrtYd")
		)
		(fp_rect
			(start -0.5 0.25)
			(end 0.5 -0.25)
			(stroke
				(width 0.15)
				(type solid)
			)
			(fill no)
			(layer "B.Fab")
		)
		(pad "1" smd roundrect
			(at -0.48 0 180)
			(size 0.59 0.64)
			(layers "B.Cu" "B.Mask" "B.Paste")
			(roundrect_rratio 0.25)
			(net 347 "/2xUSB3.0+RJ45/~{GBE0_ACT}")
			(pintype "passive")
			(teardrops
				(best_length_ratio 0.2)
				(max_length 1)
				(best_width_ratio 0.9)
				(max_width 2)
				(curved_edges yes)
				(filter_ratio 0.9)
				(enabled yes)
				(allow_two_segments yes)
				(prefer_zone_connections yes)
			)
		)
		(pad "2" smd roundrect
			(at 0.48 0 180)
			(size 0.59 0.64)
			(layers "B.Cu" "B.Mask" "B.Paste")
			(roundrect_rratio 0.25)
			(net 154 "Net-(J1A-LED_D1)")
			(pintype "passive")
			(teardrops
				(best_length_ratio 0.2)
				(max_length 1)
				(best_width_ratio 0.9)
				(max_width 2)
				(curved_edges yes)
				(filter_ratio 0.9)
				(enabled yes)
				(allow_two_segments yes)
				(prefer_zone_connections yes)
			)
		)
	)
	(footprint "antmicro-footprints:C_0402_1005Metric"
		(layer "B.Cu")
		(at 113.734999 76.725 180)
		(descr "Capacitor SMD 0402")
		(tags "capacitor SMD 0402")
		(property "Reference" "C32"
			(at 0.784999 -0.435 0)
			(layer "B.SilkS")
			(effects
				(font
					(size 0.7 0.7)
					(thickness 0.15)
				)
				(justify left bottom mirror)
			)
		)
		(property "Value" "C_100n_0402"
			(at -1.022927 -2.155213 0)
			(layer "B.Fab")
			(effects
				(font
					(size 0.7 0.7)
					(thickness 0.15)
				)
				(justify left bottom mirror)
			)
		)
		(property "Datasheet" "https://www.murata.com/products/productdetail?partno=GRM155R61H104KE14%23"
			(at 0 0 180)
			(layer "F.Fab")
			(hide yes)
			(effects
				(font
					(size 1.27 1.27)
					(thickness 0.15)
				)
			)
		)
		(property "Author" "Antmicro"
			(at 227.469998 153.45 0)
			(layer "B.Fab")
			(hide yes)
			(effects
				(font
					(size 1 1)
					(thickness 0.15)
				)
				(justify mirror)
			)
		)
		(property "Dielectric" "X5R"
			(at 227.469998 153.45 0)
			(layer "B.Fab")
			(hide yes)
			(effects
				(font
					(size 1 1)
					(thickness 0.15)
				)
				(justify mirror)
			)
		)
		(property "License" "Apache-2.0"
			(at 227.469998 153.45 0)
			(layer "B.Fab")
			(hide yes)
			(effects
				(font
					(size 1 1)
					(thickness 0.15)
				)
				(justify mirror)
			)
		)
		(property "MPN" "GRM155R61H104KE14D"
			(at 227.469998 153.45 0)
			(layer "B.Fab")
			(hide yes)
			(effects
				(font
					(size 1 1)
					(thickness 0.15)
				)
				(justify mirror)
			)
		)
		(property "Manufacturer" "Murata"
			(at 227.469998 153.45 0)
			(layer "B.Fab")
			(hide yes)
			(effects
				(font
					(size 1 1)
					(thickness 0.15)
				)
				(justify mirror)
			)
		)
		(property "Public" "False"
			(at 227.469998 153.45 0)
			(layer "B.Fab")
			(hide yes)
			(effects
				(font
					(size 1 1)
					(thickness 0.15)
				)
				(justify mirror)
			)
		)
		(property "Val" "100n"
			(at 227.469998 153.45 0)
			(layer "B.Fab")
			(hide yes)
			(effects
				(font
					(size 1 1)
					(thickness 0.15)
				)
				(justify mirror)
			)
		)
		(property "Voltage" "50V"
			(at 227.469998 153.45 0)
			(layer "B.Fab")
			(hide yes)
			(effects
				(font
					(size 1 1)
					(thickness 0.15)
				)
				(justify mirror)
			)
		)
		(sheetname "USB-C console")
		(sheetfile "usb-c_console.kicad_sch")
		(attr smd)
		(fp_rect
			(start -0.925 0.47)
			(end 0.925 -0.47)
			(stroke
				(width 0.05)
				(type default)
			)
			(fill no)
			(layer "B.CrtYd")
		)
		(fp_line
			(start 0.504 0.25)
			(end -0.494 0.25)
			(stroke
				(width 0.15)
				(type solid)
			)
			(layer "B.Fab")
		)
		(fp_line
			(start 0.504 -0.248)
			(end 0.504 0.25)
			(stroke
				(width 0.15)
				(type solid)
			)
			(layer "B.Fab")
		)
		(fp_line
			(start -0.494 0.25)
			(end -0.494 -0.248)
			(stroke
				(width 0.15)
				(type solid)
			)
			(layer "B.Fab")
		)
		(fp_line
			(start -0.494 -0.248)
			(end 0.504 -0.248)
			(stroke
				(width 0.15)
				(type solid)
			)
			(layer "B.Fab")
		)
		(pad "1" smd roundrect
			(at -0.48 0 180)
			(size 0.59 0.64)
			(layers "B.Cu" "B.Mask" "B.Paste")
			(roundrect_rratio 0.25)
			(net 1 "GND")
			(pintype "passive")
			(teardrops
				(best_length_ratio 0.2)
				(max_length 1)
				(best_width_ratio 0.9)
				(max_width 2)
				(curved_edges yes)
				(filter_ratio 0.9)
				(enabled yes)
				(allow_two_segments yes)
				(prefer_zone_connections yes)
			)
		)
		(pad "2" smd roundrect
			(at 0.48 0 180)
			(size 0.59 0.64)
			(layers "B.Cu" "B.Mask" "B.Paste")
			(roundrect_rratio 0.25)
			(net 57 "/USB-C console/FTDI_VCCIO")
			(pintype "passive")
			(teardrops
				(best_length_ratio 0.2)
				(max_length 1)
				(best_width_ratio 0.9)
				(max_width 2)
				(curved_edges yes)
				(filter_ratio 0.9)
				(enabled yes)
				(allow_two_segments yes)
				(prefer_zone_connections yes)
			)
		)
	)
	(footprint "antmicro-footprints:TP_SMD_0.75mm"
		(layer "B.Cu")
		(at 259.95 86.36 180)
		(property "Reference" "TP13"
			(at -3.1 -0.4 0)
			(layer "B.SilkS")
			(effects
				(font
					(size 0.7 0.7)
					(thickness 0.15)
				)
				(justify left bottom mirror)
			)
		)
		(property "Value" "TP_0.75mm_SMD"
			(at 0 -1.2 0)
			(layer "B.Fab")
			(effects
				(font
					(size 0.7 0.7)
					(thickness 0.15)
				)
				(justify left bottom mirror)
			)
		)
		(property "Author" "Antmicro"
			(at 519.9 172.72 0)
			(layer "B.Fab")
			(hide yes)
			(effects
				(font
					(size 1 1)
					(thickness 0.15)
				)
				(justify mirror)
			)
		)
		(property "License" "Apache-2.0"
			(at 519.9 172.72 0)
			(layer "B.Fab")
			(hide yes)
			(effects
				(font
					(size 1 1)
					(thickness 0.15)
				)
				(justify mirror)
			)
		)
		(property "MPN" ""
			(at 519.9 172.72 0)
			(layer "B.Fab")
			(hide yes)
			(effects
				(font
					(size 1 1)
					(thickness 0.15)
				)
				(justify mirror)
			)
		)
		(property "Manufacturer" ""
			(at 519.9 172.72 0)
			(layer "B.Fab")
			(hide yes)
			(effects
				(font
					(size 1 1)
					(thickness 0.15)
				)
				(justify mirror)
			)
		)
		(property "Public" "False"
			(at 519.9 172.72 0)
			(layer "B.Fab")
			(hide yes)
			(effects
				(font
					(size 1 1)
					(thickness 0.15)
				)
				(justify mirror)
			)
		)
		(sheetname "Misc")
		(sheetfile "misc.kicad_sch")
		(attr exclude_from_pos_files exclude_from_bom)
		(fp_circle
			(center 0 0)
			(end 0.475 0)
			(stroke
				(width 0.05)
				(type default)
			)
			(fill no)
			(layer "B.CrtYd")
		)
		(pad "1" smd circle
			(at 0 0 180)
			(size 0.75 0.75)
			(layers "B.Cu" "B.Mask")
			(net 705 "Net-(U24-GPIO1)")
			(pinfunction "1")
			(pintype "passive")
			(teardrops
				(best_length_ratio 0.4)
				(max_length 1)
				(best_width_ratio 0.9)
				(max_width 2)
				(curved_edges yes)
				(filter_ratio 0.9)
				(enabled yes)
				(allow_two_segments yes)
				(prefer_zone_connections yes)
			)
		)
	)
	(footprint "antmicro-footprints:R_0402_1005Metric"
		(layer "B.Cu")
		(at 146.05 169.16 -90)
		(descr "Resistor SMD 0402")
		(tags "resistor SMD 0402")
		(property "Reference" "R49"
			(at -3.9 13.5 90)
			(layer "B.SilkS")
			(effects
				(font
					(size 0.7 0.7)
					(thickness 0.15)
				)
				(justify left bottom mirror)
			)
		)
		(property "Value" "R_1k_0402"
			(at -1.011843 -1.772047 90)
			(layer "B.Fab")
			(effects
				(font
					(size 0.7 0.7)
					(thickness 0.15)
				)
				(justify left bottom mirror)
			)
		)
		(property "Datasheet" "https://www.bourns.com/docs/product-datasheets/cr.pdf"
			(at 0 0 270)
			(layer "F.Fab")
			(hide yes)
			(effects
				(font
					(size 1.27 1.27)
					(thickness 0.15)
				)
			)
		)
		(property "Author" "Antmicro"
			(at -23.11 315.21 0)
			(layer "B.Fab")
			(hide yes)
			(effects
				(font
					(size 1 1)
					(thickness 0.15)
				)
				(justify mirror)
			)
		)
		(property "License" "Apache-2.0"
			(at -23.11 315.21 0)
			(layer "B.Fab")
			(hide yes)
			(effects
				(font
					(size 1 1)
					(thickness 0.15)
				)
				(justify mirror)
			)
		)
		(property "MPN" "CR0402-FX-1001GLF"
			(at -23.11 315.21 0)
			(layer "B.Fab")
			(hide yes)
			(effects
				(font
					(size 1 1)
					(thickness 0.15)
				)
				(justify mirror)
			)
		)
		(property "Manufacturer" "Bourns"
			(at -23.11 315.21 0)
			(layer "B.Fab")
			(hide yes)
			(effects
				(font
					(size 1 1)
					(thickness 0.15)
				)
				(justify mirror)
			)
		)
		(property "Public" "False"
			(at -23.11 315.21 0)
			(layer "B.Fab")
			(hide yes)
			(effects
				(font
					(size 1 1)
					(thickness 0.15)
				)
				(justify mirror)
			)
		)
		(property "Tolerance" "1%"
			(at -23.11 315.21 0)
			(layer "B.Fab")
			(hide yes)
			(effects
				(font
					(size 1 1)
					(thickness 0.15)
				)
				(justify mirror)
			)
		)
		(property "Val" "1k"
			(at -23.11 315.21 0)
			(layer "B.Fab")
			(hide yes)
			(effects
				(font
					(size 1 1)
					(thickness 0.15)
				)
				(justify mirror)
			)
		)
		(sheetname "2xSFP+")
		(sheetfile "2xSFP+.kicad_sch")
		(attr smd)
		(fp_rect
			(start -0.925 0.47)
			(end 0.925 -0.47)
			(stroke
				(width 0.05)
				(type default)
			)
			(fill no)
			(layer "B.CrtYd")
		)
		(fp_rect
			(start -0.5 0.25)
			(end 0.5 -0.25)
			(stroke
				(width 0.15)
				(type solid)
			)
			(fill no)
			(layer "B.Fab")
		)
		(pad "1" smd roundrect
			(at -0.48 0 270)
			(size 0.59 0.64)
			(layers "B.Cu" "B.Mask" "B.Paste")
			(roundrect_rratio 0.25)
			(net 167 "Net-(J2A-RS0)")
			(pintype "passive")
			(teardrops
				(best_length_ratio 0.2)
				(max_length 1)
				(best_width_ratio 0.9)
				(max_width 2)
				(curved_edges yes)
				(filter_ratio 0.9)
				(enabled yes)
				(allow_two_segments yes)
				(prefer_zone_connections yes)
			)
		)
		(pad "2" smd roundrect
			(at 0.48 0 270)
			(size 0.59 0.64)
			(layers "B.Cu" "B.Mask" "B.Paste")
			(roundrect_rratio 0.25)
			(net 2 "+3V3")
			(pintype "passive")
			(teardrops
				(best_length_ratio 0.2)
				(max_length 1)
				(best_width_ratio 0.9)
				(max_width 2)
				(curved_edges yes)
				(filter_ratio 0.9)
				(enabled yes)
				(allow_two_segments yes)
				(prefer_zone_connections yes)
			)
		)
	)
	(footprint "antmicro-footprints:R_0402_1005Metric"
		(layer "B.Cu")
		(at 121.7 161.56)
		(descr "Resistor SMD 0402")
		(tags "resistor SMD 0402")
		(property "Reference" "R79"
			(at 0.85 0.45 0)
			(layer "B.SilkS")
			(effects
				(font
					(size 0.7 0.7)
					(thickness 0.15)
				)
				(justify right bottom mirror)
			)
		)
		(property "Value" "R_10k_0402"
			(at -1.011843 -1.772047 0)
			(layer "B.Fab")
			(effects
				(font
					(size 0.7 0.7)
					(thickness 0.15)
				)
				(justify right bottom mirror)
			)
		)
		(property "Datasheet" "https://www.bourns.com/docs/product-datasheets/cr.pdf"
			(at 0 0 0)
			(layer "F.Fab")
			(hide yes)
			(effects
				(font
					(size 1.27 1.27)
					(thickness 0.15)
				)
			)
		)
		(property "Author" "Antmicro"
			(at 0 0 0)
			(layer "B.Fab")
			(hide yes)
			(effects
				(font
					(size 1 1)
					(thickness 0.15)
				)
				(justify mirror)
			)
		)
		(property "License" "Apache-2.0"
			(at 0 0 0)
			(layer "B.Fab")
			(hide yes)
			(effects
				(font
					(size 1 1)
					(thickness 0.15)
				)
				(justify mirror)
			)
		)
		(property "MPN" "CR0402-FX-1002GLF"
			(at 0 0 0)
			(layer "B.Fab")
			(hide yes)
			(effects
				(font
					(size 1 1)
					(thickness 0.15)
				)
				(justify mirror)
			)
		)
		(property "Manufacturer" "Bourns"
			(at 0 0 0)
			(layer "B.Fab")
			(hide yes)
			(effects
				(font
					(size 1 1)
					(thickness 0.15)
				)
				(justify mirror)
			)
		)
		(property "Public" "False"
			(at 0 0 0)
			(layer "B.Fab")
			(hide yes)
			(effects
				(font
					(size 1 1)
					(thickness 0.15)
				)
				(justify mirror)
			)
		)
		(property "Tolerance" "1%"
			(at 0 0 0)
			(layer "B.Fab")
			(hide yes)
			(effects
				(font
					(size 1 1)
					(thickness 0.15)
				)
				(justify mirror)
			)
		)
		(property "Val" "10k"
			(at 0 0 0)
			(layer "B.Fab")
			(hide yes)
			(effects
				(font
					(size 1 1)
					(thickness 0.15)
				)
				(justify mirror)
			)
		)
		(sheetname "OCuLink")
		(sheetfile "oculink.kicad_sch")
		(attr smd)
		(fp_rect
			(start -0.925 0.47)
			(end 0.925 -0.47)
			(stroke
				(width 0.05)
				(type default)
			)
			(fill no)
			(layer "B.CrtYd")
		)
		(fp_rect
			(start -0.5 0.25)
			(end 0.5 -0.25)
			(stroke
				(width 0.15)
				(type solid)
			)
			(fill no)
			(layer "B.Fab")
		)
		(pad "1" smd roundrect
			(at -0.48 0)
			(size 0.59 0.64)
			(layers "B.Cu" "B.Mask" "B.Paste")
			(roundrect_rratio 0.25)
			(net 201 "/OCuLink/~{CPRSNT_D0}")
			(pintype "passive")
			(teardrops
				(best_length_ratio 0.2)
				(max_length 1)
				(best_width_ratio 0.9)
				(max_width 2)
				(curved_edges yes)
				(filter_ratio 0.9)
				(enabled yes)
				(allow_two_segments yes)
				(prefer_zone_connections yes)
			)
		)
		(pad "2" smd roundrect
			(at 0.48 0)
			(size 0.59 0.64)
			(layers "B.Cu" "B.Mask" "B.Paste")
			(roundrect_rratio 0.25)
			(net 2 "+3V3")
			(pintype "passive")
			(teardrops
				(best_length_ratio 0.2)
				(max_length 1)
				(best_width_ratio 0.9)
				(max_width 2)
				(curved_edges yes)
				(filter_ratio 0.9)
				(enabled yes)
				(allow_two_segments yes)
				(prefer_zone_connections yes)
			)
		)
	)
	(footprint "antmicro-footprints:C_0603_1608Metric"
		(layer "B.Cu")
		(at 129.063 132.09 -90)
		(descr "Capacitor SMD 0603")
		(tags "capacitor 0603")
		(property "Reference" "C183"
			(at -6.98 1.713 90)
			(layer "B.SilkS")
			(effects
				(font
					(size 0.7 0.7)
					(thickness 0.15)
				)
				(justify left bottom mirror)
			)
		)
		(property "Value" "C_22u_16V_0603"
			(at -1.42757 -1.770288 90)
			(layer "B.Fab")
			(effects
				(font
					(size 0.7 0.7)
					(thickness 0.15)
				)
				(justify left bottom mirror)
			)
		)
		(property "Datasheet" "https://product.samsungsem.com/mlcc/CL10A226MO7JZN.do"
			(at 0 0 270)
			(layer "F.Fab")
			(hide yes)
			(effects
				(font
					(size 1.27 1.27)
					(thickness 0.15)
				)
			)
		)
		(property "Author" "Antmicro"
			(at -3.027 261.153 0)
			(layer "B.Fab")
			(hide yes)
			(effects
				(font
					(size 1 1)
					(thickness 0.15)
				)
				(justify mirror)
			)
		)
		(property "Dielectric" ""
			(at -3.027 261.153 0)
			(layer "B.Fab")
			(hide yes)
			(effects
				(font
					(size 1 1)
					(thickness 0.15)
				)
				(justify mirror)
			)
		)
		(property "License" "Apache-2.0"
			(at -3.027 261.153 0)
			(layer "B.Fab")
			(hide yes)
			(effects
				(font
					(size 1 1)
					(thickness 0.15)
				)
				(justify mirror)
			)
		)
		(property "MPN" "CL10A226MO7JZNC"
			(at -3.027 261.153 0)
			(layer "B.Fab")
			(hide yes)
			(effects
				(font
					(size 1 1)
					(thickness 0.15)
				)
				(justify mirror)
			)
		)
		(property "Manufacturer" "Samsung Electro-Mechanics"
			(at -3.027 261.153 0)
			(layer "B.Fab")
			(hide yes)
			(effects
				(font
					(size 1 1)
					(thickness 0.15)
				)
				(justify mirror)
			)
		)
		(property "Public" "False"
			(at -3.027 261.153 0)
			(layer "B.Fab")
			(hide yes)
			(effects
				(font
					(size 1 1)
					(thickness 0.15)
				)
				(justify mirror)
			)
		)
		(property "Val" "22u"
			(at -3.027 261.153 0)
			(layer "B.Fab")
			(hide yes)
			(effects
				(font
					(size 1 1)
					(thickness 0.15)
				)
				(justify mirror)
			)
		)
		(property "Voltage" "16V"
			(at -3.027 261.153 0)
			(layer "B.Fab")
			(hide yes)
			(effects
				(font
					(size 1 1)
					(thickness 0.15)
				)
				(justify mirror)
			)
		)
		(sheetname "KR to SFI #2")
		(sheetfile "kr_sfi.kicad_sch")
		(attr smd)
		(fp_line
			(start 0.15 0.4)
			(end -0.15 0.4)
			(stroke
				(width 0.15)
				(type solid)
			)
			(layer "B.SilkS")
		)
		(fp_line
			(start 0.15 -0.4)
			(end -0.15 -0.4)
			(stroke
				(width 0.15)
				(type solid)
			)
			(layer "B.SilkS")
		)
		(fp_rect
			(start -1.25 0.65)
			(end 1.25 -0.65)
			(stroke
				(width 0.05)
				(type solid)
			)
			(fill no)
			(layer "B.CrtYd")
		)
		(fp_rect
			(start -0.8 0.4)
			(end 0.8 -0.4)
			(stroke
				(width 0.15)
				(type solid)
			)
			(fill no)
			(layer "B.Fab")
		)
		(pad "1" smd roundrect
			(at -0.7 0 270)
			(size 0.8 1)
			(layers "B.Cu" "B.Mask" "B.Paste")
			(roundrect_rratio 0.2)
			(net 1 "GND")
			(pintype "passive")
			(teardrops
				(best_length_ratio 0.2)
				(max_length 1)
				(best_width_ratio 0.9)
				(max_width 2)
				(curved_edges yes)
				(filter_ratio 0.9)
				(enabled yes)
				(allow_two_segments yes)
				(prefer_zone_connections yes)
			)
		)
		(pad "2" smd roundrect
			(at 0.7 0 270)
			(size 0.8 1)
			(layers "B.Cu" "B.Mask" "B.Paste")
			(roundrect_rratio 0.2)
			(net 78 "+1V8")
			(pintype "passive")
			(teardrops
				(best_length_ratio 0.2)
				(max_length 1)
				(best_width_ratio 0.9)
				(max_width 2)
				(curved_edges yes)
				(filter_ratio 0.9)
				(enabled yes)
				(allow_two_segments yes)
				(prefer_zone_connections yes)
			)
		)
	)
	(footprint "antmicro-footprints:R_0402_1005Metric"
		(layer "B.Cu")
		(at 144.25 140.06)
		(descr "Resistor SMD 0402")
		(tags "resistor SMD 0402")
		(property "Reference" "R255"
			(at -1.45 5.4 0)
			(layer "B.SilkS")
			(effects
				(font
					(size 0.7 0.7)
					(thickness 0.15)
				)
				(justify right bottom mirror)
			)
		)
		(property "Value" "R_10k_0402"
			(at -1.011843 -1.772047 0)
			(layer "B.Fab")
			(effects
				(font
					(size 0.7 0.7)
					(thickness 0.15)
				)
				(justify right bottom mirror)
			)
		)
		(property "Datasheet" "https://www.bourns.com/docs/product-datasheets/cr.pdf"
			(at 0 0 0)
			(layer "F.Fab")
			(hide yes)
			(effects
				(font
					(size 1.27 1.27)
					(thickness 0.15)
				)
			)
		)
		(property "Author" "Antmicro"
			(at 0 0 0)
			(layer "B.Fab")
			(hide yes)
			(effects
				(font
					(size 1 1)
					(thickness 0.15)
				)
				(justify mirror)
			)
		)
		(property "License" "Apache-2.0"
			(at 0 0 0)
			(layer "B.Fab")
			(hide yes)
			(effects
				(font
					(size 1 1)
					(thickness 0.15)
				)
				(justify mirror)
			)
		)
		(property "MPN" "CR0402-FX-1002GLF"
			(at 0 0 0)
			(layer "B.Fab")
			(hide yes)
			(effects
				(font
					(size 1 1)
					(thickness 0.15)
				)
				(justify mirror)
			)
		)
		(property "Manufacturer" "Bourns"
			(at 0 0 0)
			(layer "B.Fab")
			(hide yes)
			(effects
				(font
					(size 1 1)
					(thickness 0.15)
				)
				(justify mirror)
			)
		)
		(property "Public" "False"
			(at 0 0 0)
			(layer "B.Fab")
			(hide yes)
			(effects
				(font
					(size 1 1)
					(thickness 0.15)
				)
				(justify mirror)
			)
		)
		(property "Tolerance" "1%"
			(at 0 0 0)
			(layer "B.Fab")
			(hide yes)
			(effects
				(font
					(size 1 1)
					(thickness 0.15)
				)
				(justify mirror)
			)
		)
		(property "Val" "10k"
			(at 0 0 0)
			(layer "B.Fab")
			(hide yes)
			(effects
				(font
					(size 1 1)
					(thickness 0.15)
				)
				(justify mirror)
			)
		)
		(sheetname "KR to SFI #1")
		(sheetfile "kr_sfi.kicad_sch")
		(attr smd)
		(fp_rect
			(start -0.925 0.47)
			(end 0.925 -0.47)
			(stroke
				(width 0.05)
				(type default)
			)
			(fill no)
			(layer "B.CrtYd")
		)
		(fp_rect
			(start -0.5 0.25)
			(end 0.5 -0.25)
			(stroke
				(width 0.15)
				(type solid)
			)
			(fill no)
			(layer "B.Fab")
		)
		(pad "1" smd roundrect
			(at -0.48 0)
			(size 0.59 0.64)
			(layers "B.Cu" "B.Mask" "B.Paste")
			(roundrect_rratio 0.25)
			(net 1 "GND")
			(pintype "passive")
			(teardrops
				(best_length_ratio 0.2)
				(max_length 1)
				(best_width_ratio 0.9)
				(max_width 2)
				(curved_edges yes)
				(filter_ratio 0.9)
				(enabled yes)
				(allow_two_segments yes)
				(prefer_zone_connections yes)
			)
		)
		(pad "2" smd roundrect
			(at 0.48 0)
			(size 0.59 0.64)
			(layers "B.Cu" "B.Mask" "B.Paste")
			(roundrect_rratio 0.25)
			(net 653 "Net-(U43C-TESTEN)")
			(pintype "passive")
			(teardrops
				(best_length_ratio 0.2)
				(max_length 1)
				(best_width_ratio 0.9)
				(max_width 2)
				(curved_edges yes)
				(filter_ratio 0.9)
				(enabled yes)
				(allow_two_segments yes)
				(prefer_zone_connections yes)
			)
		)
	)
	(footprint "antmicro-footprints:C_0402_1005Metric"
		(layer "B.Cu")
		(at 107.893 164.377 180)
		(descr "Capacitor SMD 0402")
		(tags "capacitor SMD 0402")
		(property "Reference" "C145"
			(at -3.707 -0.003 0)
			(layer "B.SilkS")
			(effects
				(font
					(size 0.7 0.7)
					(thickness 0.15)
				)
				(justify left bottom mirror)
			)
		)
		(property "Value" "C_220n_0402"
			(at -1.022927 -2.155213 0)
			(layer "B.Fab")
			(effects
				(font
					(size 0.7 0.7)
					(thickness 0.15)
				)
				(justify left bottom mirror)
			)
		)
		(property "Datasheet" "https://www.yageo.com/en/Chart/Download/pdf/CC0402KRX5R6BB224"
			(at 0 0 180)
			(layer "F.Fab")
			(hide yes)
			(effects
				(font
					(size 1.27 1.27)
					(thickness 0.15)
				)
			)
		)
		(property "Author" "Antmicro"
			(at 215.786 328.754 0)
			(layer "B.Fab")
			(hide yes)
			(effects
				(font
					(size 1 1)
					(thickness 0.15)
				)
				(justify mirror)
			)
		)
		(property "Dielectric" ""
			(at 215.786 328.754 0)
			(layer "B.Fab")
			(hide yes)
			(effects
				(font
					(size 1 1)
					(thickness 0.15)
				)
				(justify mirror)
			)
		)
		(property "License" "Apache-2.0"
			(at 215.786 328.754 0)
			(layer "B.Fab")
			(hide yes)
			(effects
				(font
					(size 1 1)
					(thickness 0.15)
				)
				(justify mirror)
			)
		)
		(property "MPN" "CC0402KRX5R6BB224"
			(at 215.786 328.754 0)
			(layer "B.Fab")
			(hide yes)
			(effects
				(font
					(size 1 1)
					(thickness 0.15)
				)
				(justify mirror)
			)
		)
		(property "Manufacturer" "YAGEO"
			(at 215.786 328.754 0)
			(layer "B.Fab")
			(hide yes)
			(effects
				(font
					(size 1 1)
					(thickness 0.15)
				)
				(justify mirror)
			)
		)
		(property "Public" "False"
			(at 215.786 328.754 0)
			(layer "B.Fab")
			(hide yes)
			(effects
				(font
					(size 1 1)
					(thickness 0.15)
				)
				(justify mirror)
			)
		)
		(property "Val" "220n"
			(at 215.786 328.754 0)
			(layer "B.Fab")
			(hide yes)
			(effects
				(font
					(size 1 1)
					(thickness 0.15)
				)
				(justify mirror)
			)
		)
		(property "Voltage" ""
			(at 215.786 328.754 0)
			(layer "B.Fab")
			(hide yes)
			(effects
				(font
					(size 1 1)
					(thickness 0.15)
				)
				(justify mirror)
			)
		)
		(sheetname "PCIe redriver")
		(sheetfile "pcie_redriver.kicad_sch")
		(attr smd)
		(fp_rect
			(start -0.925 0.47)
			(end 0.925 -0.47)
			(stroke
				(width 0.05)
				(type default)
			)
			(fill no)
			(layer "B.CrtYd")
		)
		(fp_line
			(start 0.504 0.25)
			(end -0.494 0.25)
			(stroke
				(width 0.15)
				(type solid)
			)
			(layer "B.Fab")
		)
		(fp_line
			(start 0.504 -0.248)
			(end 0.504 0.25)
			(stroke
				(width 0.15)
				(type solid)
			)
			(layer "B.Fab")
		)
		(fp_line
			(start -0.494 0.25)
			(end -0.494 -0.248)
			(stroke
				(width 0.15)
				(type solid)
			)
			(layer "B.Fab")
		)
		(fp_line
			(start -0.494 -0.248)
			(end 0.504 -0.248)
			(stroke
				(width 0.15)
				(type solid)
			)
			(layer "B.Fab")
		)
		(pad "1" smd roundrect
			(at -0.48 0 180)
			(size 0.59 0.64)
			(layers "B.Cu" "B.Mask" "B.Paste")
			(roundrect_rratio 0.25)
			(net 965 "/PCIe redriver/PCIe_{O}_C.TX1-")
			(pintype "passive")
			(teardrops
				(best_length_ratio 0.2)
				(max_length 1)
				(best_width_ratio 0.9)
				(max_width 2)
				(curved_edges yes)
				(filter_ratio 0.9)
				(enabled yes)
				(allow_two_segments yes)
				(prefer_zone_connections yes)
			)
		)
		(pad "2" smd roundrect
			(at 0.48 0 180)
			(size 0.59 0.64)
			(layers "B.Cu" "B.Mask" "B.Paste")
			(roundrect_rratio 0.25)
			(net 96 "/OCuLink/PCIe_{x4}.TX1-")
			(pintype "passive")
			(teardrops
				(best_length_ratio 0.2)
				(max_length 1)
				(best_width_ratio 0.9)
				(max_width 2)
				(curved_edges yes)
				(filter_ratio 0.9)
				(enabled yes)
				(allow_two_segments yes)
				(prefer_zone_connections yes)
			)
		)
	)
	(footprint "antmicro-footprints:R_0402_1005Metric"
		(layer "B.Cu")
		(at 146.95 136.06)
		(descr "Resistor SMD 0402")
		(tags "resistor SMD 0402")
		(property "Reference" "R266"
			(at -1.3 -0.5 0)
			(layer "B.SilkS")
			(effects
				(font
					(size 0.7 0.7)
					(thickness 0.15)
				)
				(justify right bottom mirror)
			)
		)
		(property "Value" "R_10k_0402"
			(at -1.011843 -1.772047 0)
			(layer "B.Fab")
			(effects
				(font
					(size 0.7 0.7)
					(thickness 0.15)
				)
				(justify right bottom mirror)
			)
		)
		(property "Datasheet" "https://www.bourns.com/docs/product-datasheets/cr.pdf"
			(at 0 0 0)
			(layer "F.Fab")
			(hide yes)
			(effects
				(font
					(size 1.27 1.27)
					(thickness 0.15)
				)
			)
		)
		(property "Author" "Antmicro"
			(at 0 0 0)
			(layer "B.Fab")
			(hide yes)
			(effects
				(font
					(size 1 1)
					(thickness 0.15)
				)
				(justify mirror)
			)
		)
		(property "License" "Apache-2.0"
			(at 0 0 0)
			(layer "B.Fab")
			(hide yes)
			(effects
				(font
					(size 1 1)
					(thickness 0.15)
				)
				(justify mirror)
			)
		)
		(property "MPN" "CR0402-FX-1002GLF"
			(at 0 0 0)
			(layer "B.Fab")
			(hide yes)
			(effects
				(font
					(size 1 1)
					(thickness 0.15)
				)
				(justify mirror)
			)
		)
		(property "Manufacturer" "Bourns"
			(at 0 0 0)
			(layer "B.Fab")
			(hide yes)
			(effects
				(font
					(size 1 1)
					(thickness 0.15)
				)
				(justify mirror)
			)
		)
		(property "Public" "False"
			(at 0 0 0)
			(layer "B.Fab")
			(hide yes)
			(effects
				(font
					(size 1 1)
					(thickness 0.15)
				)
				(justify mirror)
			)
		)
		(property "Tolerance" "1%"
			(at 0 0 0)
			(layer "B.Fab")
			(hide yes)
			(effects
				(font
					(size 1 1)
					(thickness 0.15)
				)
				(justify mirror)
			)
		)
		(property "Val" "10k"
			(at 0 0 0)
			(layer "B.Fab")
			(hide yes)
			(effects
				(font
					(size 1 1)
					(thickness 0.15)
				)
				(justify mirror)
			)
		)
		(sheetname "KR to SFI #1")
		(sheetfile "kr_sfi.kicad_sch")
		(attr smd)
		(fp_rect
			(start -0.925 0.47)
			(end 0.925 -0.47)
			(stroke
				(width 0.05)
				(type default)
			)
			(fill no)
			(layer "B.CrtYd")
		)
		(fp_rect
			(start -0.5 0.25)
			(end 0.5 -0.25)
			(stroke
				(width 0.15)
				(type solid)
			)
			(fill no)
			(layer "B.Fab")
		)
		(pad "1" smd roundrect
			(at -0.48 0)
			(size 0.59 0.64)
			(layers "B.Cu" "B.Mask" "B.Paste")
			(roundrect_rratio 0.25)
			(net 1 "GND")
			(pintype "passive")
			(teardrops
				(best_length_ratio 0.2)
				(max_length 1)
				(best_width_ratio 0.9)
				(max_width 2)
				(curved_edges yes)
				(filter_ratio 0.9)
				(enabled yes)
				(allow_two_segments yes)
				(prefer_zone_connections yes)
			)
		)
		(pad "2" smd roundrect
			(at 0.48 0)
			(size 0.59 0.64)
			(layers "B.Cu" "B.Mask" "B.Paste")
			(roundrect_rratio 0.25)
			(net 659 "Net-(U43C-PRTAD3)")
			(pintype "passive")
			(teardrops
				(best_length_ratio 0.2)
				(max_length 1)
				(best_width_ratio 0.9)
				(max_width 2)
				(curved_edges yes)
				(filter_ratio 0.9)
				(enabled yes)
				(allow_two_segments yes)
				(prefer_zone_connections yes)
			)
		)
	)
	(footprint "antmicro-footprints:C_0402_1005Metric"
		(layer "B.Cu")
		(at 130.5 169.435 180)
		(descr "Capacitor SMD 0402")
		(tags "capacitor SMD 0402")
		(property "Reference" "C210"
			(at -1.4 0.525 0)
			(layer "B.SilkS")
			(effects
				(font
					(size 0.7 0.7)
					(thickness 0.15)
				)
				(justify left bottom mirror)
			)
		)
		(property "Value" "C_100n_0402"
			(at -1.022927 -2.155213 0)
			(layer "B.Fab")
			(effects
				(font
					(size 0.7 0.7)
					(thickness 0.15)
				)
				(justify left bottom mirror)
			)
		)
		(property "Datasheet" "https://www.murata.com/products/productdetail?partno=GRM155R61H104KE14%23"
			(at 0 0 180)
			(layer "F.Fab")
			(hide yes)
			(effects
				(font
					(size 1.27 1.27)
					(thickness 0.15)
				)
			)
		)
		(property "Author" "Antmicro"
			(at 261 338.87 0)
			(layer "B.Fab")
			(hide yes)
			(effects
				(font
					(size 1 1)
					(thickness 0.15)
				)
				(justify mirror)
			)
		)
		(property "Dielectric" "X5R"
			(at 261 338.87 0)
			(layer "B.Fab")
			(hide yes)
			(effects
				(font
					(size 1 1)
					(thickness 0.15)
				)
				(justify mirror)
			)
		)
		(property "License" "Apache-2.0"
			(at 261 338.87 0)
			(layer "B.Fab")
			(hide yes)
			(effects
				(font
					(size 1 1)
					(thickness 0.15)
				)
				(justify mirror)
			)
		)
		(property "MPN" "GRM155R61H104KE14D"
			(at 261 338.87 0)
			(layer "B.Fab")
			(hide yes)
			(effects
				(font
					(size 1 1)
					(thickness 0.15)
				)
				(justify mirror)
			)
		)
		(property "Manufacturer" "Murata"
			(at 261 338.87 0)
			(layer "B.Fab")
			(hide yes)
			(effects
				(font
					(size 1 1)
					(thickness 0.15)
				)
				(justify mirror)
			)
		)
		(property "Public" "False"
			(at 261 338.87 0)
			(layer "B.Fab")
			(hide yes)
			(effects
				(font
					(size 1 1)
					(thickness 0.15)
				)
				(justify mirror)
			)
		)
		(property "Val" "100n"
			(at 261 338.87 0)
			(layer "B.Fab")
			(hide yes)
			(effects
				(font
					(size 1 1)
					(thickness 0.15)
				)
				(justify mirror)
			)
		)
		(property "Voltage" "50V"
			(at 261 338.87 0)
			(layer "B.Fab")
			(hide yes)
			(effects
				(font
					(size 1 1)
					(thickness 0.15)
				)
				(justify mirror)
			)
		)
		(sheetname "2xSFP+")
		(sheetfile "2xSFP+.kicad_sch")
		(attr smd)
		(fp_rect
			(start -0.925 0.47)
			(end 0.925 -0.47)
			(stroke
				(width 0.05)
				(type default)
			)
			(fill no)
			(layer "B.CrtYd")
		)
		(fp_line
			(start 0.504 0.25)
			(end -0.494 0.25)
			(stroke
				(width 0.15)
				(type solid)
			)
			(layer "B.Fab")
		)
		(fp_line
			(start 0.504 -0.248)
			(end 0.504 0.25)
			(stroke
				(width 0.15)
				(type solid)
			)
			(layer "B.Fab")
		)
		(fp_line
			(start -0.494 0.25)
			(end -0.494 -0.248)
			(stroke
				(width 0.15)
				(type solid)
			)
			(layer "B.Fab")
		)
		(fp_line
			(start -0.494 -0.248)
			(end 0.504 -0.248)
			(stroke
				(width 0.15)
				(type solid)
			)
			(layer "B.Fab")
		)
		(pad "1" smd roundrect
			(at -0.48 0 180)
			(size 0.59 0.64)
			(layers "B.Cu" "B.Mask" "B.Paste")
			(roundrect_rratio 0.25)
			(net 53 "/2xSFP+/SH")
			(pintype "passive")
			(teardrops
				(best_length_ratio 0.2)
				(max_length 1)
				(best_width_ratio 0.9)
				(max_width 2)
				(curved_edges yes)
				(filter_ratio 0.9)
				(enabled yes)
				(allow_two_segments yes)
				(prefer_zone_connections yes)
			)
		)
		(pad "2" smd roundrect
			(at 0.48 0 180)
			(size 0.59 0.64)
			(layers "B.Cu" "B.Mask" "B.Paste")
			(roundrect_rratio 0.25)
			(net 1 "GND")
			(pintype "passive")
			(teardrops
				(best_length_ratio 0.2)
				(max_length 1)
				(best_width_ratio 0.9)
				(max_width 2)
				(curved_edges yes)
				(filter_ratio 0.9)
				(enabled yes)
				(allow_two_segments yes)
				(prefer_zone_connections yes)
			)
		)
	)
	(footprint "antmicro-footprints:C_0402_1005Metric"
		(layer "B.Cu")
		(at 122.55 169.435 180)
		(descr "Capacitor SMD 0402")
		(tags "capacitor SMD 0402")
		(property "Reference" "C209"
			(at -1.2 0.525 0)
			(layer "B.SilkS")
			(effects
				(font
					(size 0.7 0.7)
					(thickness 0.15)
				)
				(justify left bottom mirror)
			)
		)
		(property "Value" "C_100n_0402"
			(at -1.022927 -2.155213 0)
			(layer "B.Fab")
			(effects
				(font
					(size 0.7 0.7)
					(thickness 0.15)
				)
				(justify left bottom mirror)
			)
		)
		(property "Datasheet" "https://www.murata.com/products/productdetail?partno=GRM155R61H104KE14%23"
			(at 0 0 180)
			(layer "F.Fab")
			(hide yes)
			(effects
				(font
					(size 1.27 1.27)
					(thickness 0.15)
				)
			)
		)
		(property "Author" "Antmicro"
			(at 245.1 338.87 0)
			(layer "B.Fab")
			(hide yes)
			(effects
				(font
					(size 1 1)
					(thickness 0.15)
				)
				(justify mirror)
			)
		)
		(property "Dielectric" "X5R"
			(at 245.1 338.87 0)
			(layer "B.Fab")
			(hide yes)
			(effects
				(font
					(size 1 1)
					(thickness 0.15)
				)
				(justify mirror)
			)
		)
		(property "License" "Apache-2.0"
			(at 245.1 338.87 0)
			(layer "B.Fab")
			(hide yes)
			(effects
				(font
					(size 1 1)
					(thickness 0.15)
				)
				(justify mirror)
			)
		)
		(property "MPN" "GRM155R61H104KE14D"
			(at 245.1 338.87 0)
			(layer "B.Fab")
			(hide yes)
			(effects
				(font
					(size 1 1)
					(thickness 0.15)
				)
				(justify mirror)
			)
		)
		(property "Manufacturer" "Murata"
			(at 245.1 338.87 0)
			(layer "B.Fab")
			(hide yes)
			(effects
				(font
					(size 1 1)
					(thickness 0.15)
				)
				(justify mirror)
			)
		)
		(property "Public" "False"
			(at 245.1 338.87 0)
			(layer "B.Fab")
			(hide yes)
			(effects
				(font
					(size 1 1)
					(thickness 0.15)
				)
				(justify mirror)
			)
		)
		(property "Val" "100n"
			(at 245.1 338.87 0)
			(layer "B.Fab")
			(hide yes)
			(effects
				(font
					(size 1 1)
					(thickness 0.15)
				)
				(justify mirror)
			)
		)
		(property "Voltage" "50V"
			(at 245.1 338.87 0)
			(layer "B.Fab")
			(hide yes)
			(effects
				(font
					(size 1 1)
					(thickness 0.15)
				)
				(justify mirror)
			)
		)
		(sheetname "2xSFP+")
		(sheetfile "2xSFP+.kicad_sch")
		(attr smd)
		(fp_rect
			(start -0.925 0.47)
			(end 0.925 -0.47)
			(stroke
				(width 0.05)
				(type default)
			)
			(fill no)
			(layer "B.CrtYd")
		)
		(fp_line
			(start 0.504 0.25)
			(end -0.494 0.25)
			(stroke
				(width 0.15)
				(type solid)
			)
			(layer "B.Fab")
		)
		(fp_line
			(start 0.504 -0.248)
			(end 0.504 0.25)
			(stroke
				(width 0.15)
				(type solid)
			)
			(layer "B.Fab")
		)
		(fp_line
			(start -0.494 0.25)
			(end -0.494 -0.248)
			(stroke
				(width 0.15)
				(type solid)
			)
			(layer "B.Fab")
		)
		(fp_line
			(start -0.494 -0.248)
			(end 0.504 -0.248)
			(stroke
				(width 0.15)
				(type solid)
			)
			(layer "B.Fab")
		)
		(pad "1" smd roundrect
			(at -0.48 0 180)
			(size 0.59 0.64)
			(layers "B.Cu" "B.Mask" "B.Paste")
			(roundrect_rratio 0.25)
			(net 53 "/2xSFP+/SH")
			(pintype "passive")
			(teardrops
				(best_length_ratio 0.2)
				(max_length 1)
				(best_width_ratio 0.9)
				(max_width 2)
				(curved_edges yes)
				(filter_ratio 0.9)
				(enabled yes)
				(allow_two_segments yes)
				(prefer_zone_connections yes)
			)
		)
		(pad "2" smd roundrect
			(at 0.48 0 180)
			(size 0.59 0.64)
			(layers "B.Cu" "B.Mask" "B.Paste")
			(roundrect_rratio 0.25)
			(net 1 "GND")
			(pintype "passive")
			(teardrops
				(best_length_ratio 0.2)
				(max_length 1)
				(best_width_ratio 0.9)
				(max_width 2)
				(curved_edges yes)
				(filter_ratio 0.9)
				(enabled yes)
				(allow_two_segments yes)
				(prefer_zone_connections yes)
			)
		)
	)
	(footprint "antmicro-footprints:R_0402_1005Metric"
		(layer "B.Cu")
		(at 123.4 108.81)
		(descr "Resistor SMD 0402")
		(tags "resistor SMD 0402")
		(property "Reference" "R8"
			(at 0.85 0.4 0)
			(layer "B.SilkS")
			(effects
				(font
					(size 0.7 0.7)
					(thickness 0.15)
				)
				(justify right bottom mirror)
			)
		)
		(property "Value" "R_470R_0402"
			(at -1.011843 -1.772047 0)
			(layer "B.Fab")
			(effects
				(font
					(size 0.7 0.7)
					(thickness 0.15)
				)
				(justify right bottom mirror)
			)
		)
		(property "Datasheet" "https://www.bourns.com/docs/product-datasheets/cr.pdf"
			(at 0 0 0)
			(layer "F.Fab")
			(hide yes)
			(effects
				(font
					(size 1.27 1.27)
					(thickness 0.15)
				)
			)
		)
		(property "Author" "Antmicro"
			(at 0 0 0)
			(layer "B.Fab")
			(hide yes)
			(effects
				(font
					(size 1 1)
					(thickness 0.15)
				)
				(justify mirror)
			)
		)
		(property "License" "Apache-2.0"
			(at 0 0 0)
			(layer "B.Fab")
			(hide yes)
			(effects
				(font
					(size 1 1)
					(thickness 0.15)
				)
				(justify mirror)
			)
		)
		(property "MPN" "CR0402-FX-4700GLF"
			(at 0 0 0)
			(layer "B.Fab")
			(hide yes)
			(effects
				(font
					(size 1 1)
					(thickness 0.15)
				)
				(justify mirror)
			)
		)
		(property "Manufacturer" "Bourns"
			(at 0 0 0)
			(layer "B.Fab")
			(hide yes)
			(effects
				(font
					(size 1 1)
					(thickness 0.15)
				)
				(justify mirror)
			)
		)
		(property "Public" "False"
			(at 0 0 0)
			(layer "B.Fab")
			(hide yes)
			(effects
				(font
					(size 1 1)
					(thickness 0.15)
				)
				(justify mirror)
			)
		)
		(property "Tolerance" "1%"
			(at 0 0 0)
			(layer "B.Fab")
			(hide yes)
			(effects
				(font
					(size 1 1)
					(thickness 0.15)
				)
				(justify mirror)
			)
		)
		(property "Val" "470R"
			(at 0 0 0)
			(layer "B.Fab")
			(hide yes)
			(effects
				(font
					(size 1 1)
					(thickness 0.15)
				)
				(justify mirror)
			)
		)
		(sheetname "2xUSB3.0+RJ45")
		(sheetfile "usb3+rj45.kicad_sch")
		(attr smd)
		(fp_rect
			(start -0.925 0.47)
			(end 0.925 -0.47)
			(stroke
				(width 0.05)
				(type default)
			)
			(fill no)
			(layer "B.CrtYd")
		)
		(fp_rect
			(start -0.5 0.25)
			(end 0.5 -0.25)
			(stroke
				(width 0.15)
				(type solid)
			)
			(fill no)
			(layer "B.Fab")
		)
		(pad "1" smd roundrect
			(at -0.48 0)
			(size 0.59 0.64)
			(layers "B.Cu" "B.Mask" "B.Paste")
			(roundrect_rratio 0.25)
			(net 156 "Net-(J1A-LED_D3)")
			(pintype "passive")
			(teardrops
				(best_length_ratio 0.2)
				(max_length 1)
				(best_width_ratio 0.9)
				(max_width 2)
				(curved_edges yes)
				(filter_ratio 0.9)
				(enabled yes)
				(allow_two_segments yes)
				(prefer_zone_connections yes)
			)
		)
		(pad "2" smd roundrect
			(at 0.48 0)
			(size 0.59 0.64)
			(layers "B.Cu" "B.Mask" "B.Paste")
			(roundrect_rratio 0.25)
			(net 2 "+3V3")
			(pintype "passive")
			(teardrops
				(best_length_ratio 0.2)
				(max_length 1)
				(best_width_ratio 0.9)
				(max_width 2)
				(curved_edges yes)
				(filter_ratio 0.9)
				(enabled yes)
				(allow_two_segments yes)
				(prefer_zone_connections yes)
			)
		)
	)
	(footprint "antmicro-footprints:USON-10_2.5x1mm_P0.5mm"
		(layer "B.Cu")
		(at 314.75 165.71 180)
		(descr "USON-10 2.5x1mm_ Pitch 0.5mm")
		(tags "USON-10 2.5x1mm Pitch 0.5mm")
		(property "Reference" "U15"
			(at 0.85 1.15 90)
			(layer "B.SilkS")
			(effects
				(font
					(size 0.7 0.7)
					(thickness 0.15)
				)
				(justify left bottom mirror)
			)
		)
		(property "Value" "ESD204DQAR"
			(at 0.018 -2.499 0)
			(layer "B.Fab")
			(effects
				(font
					(size 0.7 0.7)
					(thickness 0.15)
				)
				(justify left bottom mirror)
			)
		)
		(property "Datasheet" "https://www.ti.com/lit/ds/symlink/esd204.pdf?ts=1706004844383&ref_url=https%253A%252F%252Fwww.ti.com%252Finterface%252Fdiodes%252Fesd-protection-diodes%252Fproducts.html"
			(at 0 0 180)
			(layer "F.Fab")
			(hide yes)
			(effects
				(font
					(size 1.27 1.27)
					(thickness 0.15)
				)
			)
		)
		(property "Author" "Antmicro"
			(at 625.5 328.62 0)
			(layer "B.Fab")
			(hide yes)
			(effects
				(font
					(size 1 1)
					(thickness 0.15)
				)
				(justify mirror)
			)
		)
		(property "License" "Apache-2.0"
			(at 625.5 328.62 0)
			(layer "B.Fab")
			(hide yes)
			(effects
				(font
					(size 1 1)
					(thickness 0.15)
				)
				(justify mirror)
			)
		)
		(property "MPN" "ESD204DQAR"
			(at 625.5 328.62 0)
			(layer "B.Fab")
			(hide yes)
			(effects
				(font
					(size 1 1)
					(thickness 0.15)
				)
				(justify mirror)
			)
		)
		(property "Manufacturer" "Texas Instruments"
			(at 625.5 328.62 0)
			(layer "B.Fab")
			(hide yes)
			(effects
				(font
					(size 1 1)
					(thickness 0.15)
				)
				(justify mirror)
			)
		)
		(sheetname "Backplane")
		(sheetfile "backplane.kicad_sch")
		(attr smd)
		(fp_line
			(start -0.5 1.401)
			(end 0.498 1.401)
			(stroke
				(width 0.15)
				(type solid)
			)
			(layer "B.SilkS")
		)
		(fp_line
			(start -0.5 -1.398)
			(end 0.498 -1.398)
			(stroke
				(width 0.15)
				(type solid)
			)
			(layer "B.SilkS")
		)
		(fp_circle
			(center -0.68 1.27)
			(end -0.63 1.27)
			(stroke
				(width 0.15)
				(type solid)
			)
			(fill yes)
			(layer "B.SilkS")
		)
		(fp_rect
			(start -0.8 1.5)
			(end 0.8 -1.499)
			(stroke
				(width 0.05)
				(type solid)
			)
			(fill no)
			(layer "B.CrtYd")
		)
		(fp_line
			(start 0.498 -1.249)
			(end 0.498 1.25)
			(stroke
				(width 0.15)
				(type solid)
			)
			(layer "B.Fab")
		)
		(fp_line
			(start 0.498 -1.249)
			(end -0.5 -1.249)
			(stroke
				(width 0.15)
				(type solid)
			)
			(layer "B.Fab")
		)
		(fp_line
			(start -0.25 1.25)
			(end 0.498 1.25)
			(stroke
				(width 0.15)
				(type solid)
			)
			(layer "B.Fab")
		)
		(fp_line
			(start -0.5 1)
			(end -0.25 1.25)
			(stroke
				(width 0.15)
				(type solid)
			)
			(layer "B.Fab")
		)
		(fp_line
			(start -0.5 -1.249)
			(end -0.5 1)
			(stroke
				(width 0.15)
				(type solid)
			)
			(layer "B.Fab")
		)
		(pad "1" smd roundrect
			(at -0.387 1 270)
			(size 0.25 0.55)
			(layers "B.Cu" "B.Mask" "B.Paste")
			(roundrect_rratio 0.25)
			(net 203 "/Backplane/PCIe_{REF}.CK+")
			(pintype "passive")
			(teardrops
				(best_length_ratio 0.2)
				(max_length 1)
				(best_width_ratio 0.9)
				(max_width 2)
				(curved_edges yes)
				(filter_ratio 0.9)
				(enabled yes)
				(allow_two_segments yes)
				(prefer_zone_connections yes)
			)
		)
		(pad "2" smd roundrect
			(at -0.387 0.5 270)
			(size 0.25 0.55)
			(layers "B.Cu" "B.Mask" "B.Paste")
			(roundrect_rratio 0.25)
			(net 205 "/Backplane/PCIe_{REF}.CK-")
			(pintype "passive")
			(teardrops
				(best_length_ratio 0.2)
				(max_length 1)
				(best_width_ratio 0.9)
				(max_width 2)
				(curved_edges yes)
				(filter_ratio 0.9)
				(enabled yes)
				(allow_two_segments yes)
				(prefer_zone_connections yes)
			)
		)
		(pad "3" smd roundrect
			(at -0.387 0 270)
			(size 0.4 0.55)
			(layers "B.Cu" "B.Mask" "B.Paste")
			(roundrect_rratio 0.25)
			(net 1 "GND")
			(pintype "power_in")
			(teardrops
				(best_length_ratio 0.2)
				(max_length 1)
				(best_width_ratio 0.9)
				(max_width 2)
				(curved_edges yes)
				(filter_ratio 0.9)
				(enabled yes)
				(allow_two_segments yes)
				(prefer_zone_connections yes)
			)
		)
		(pad "4" smd roundrect
			(at -0.387 -0.498 270)
			(size 0.25 0.55)
			(layers "B.Cu" "B.Mask" "B.Paste")
			(roundrect_rratio 0.25)
			(net 206 "/Backplane/USB.D+")
			(pintype "passive")
			(teardrops
				(best_length_ratio 0.2)
				(max_length 1)
				(best_width_ratio 0.9)
				(max_width 2)
				(curved_edges yes)
				(filter_ratio 0.9)
				(enabled yes)
				(allow_two_segments yes)
				(prefer_zone_connections yes)
			)
		)
		(pad "5" smd roundrect
			(at -0.387 -0.998 270)
			(size 0.25 0.55)
			(layers "B.Cu" "B.Mask" "B.Paste")
			(roundrect_rratio 0.25)
			(net 204 "/Backplane/USB.D-")
			(pintype "passive")
			(teardrops
				(best_length_ratio 0.2)
				(max_length 1)
				(best_width_ratio 0.9)
				(max_width 2)
				(curved_edges yes)
				(filter_ratio 0.9)
				(enabled yes)
				(allow_two_segments yes)
				(prefer_zone_connections yes)
			)
		)
		(pad "6" smd roundrect
			(at 0.385 -0.998 270)
			(size 0.25 0.55)
			(layers "B.Cu" "B.Mask" "B.Paste")
			(roundrect_rratio 0.25)
			(net 204 "/Backplane/USB.D-")
			(pintype "passive")
			(teardrops
				(best_length_ratio 0.2)
				(max_length 1)
				(best_width_ratio 0.9)
				(max_width 2)
				(curved_edges yes)
				(filter_ratio 0.9)
				(enabled yes)
				(allow_two_segments yes)
				(prefer_zone_connections yes)
			)
		)
		(pad "7" smd roundrect
			(at 0.385 -0.498 270)
			(size 0.25 0.55)
			(layers "B.Cu" "B.Mask" "B.Paste")
			(roundrect_rratio 0.25)
			(net 206 "/Backplane/USB.D+")
			(pintype "passive")
			(teardrops
				(best_length_ratio 0.2)
				(max_length 1)
				(best_width_ratio 0.9)
				(max_width 2)
				(curved_edges yes)
				(filter_ratio 0.9)
				(enabled yes)
				(allow_two_segments yes)
				(prefer_zone_connections yes)
			)
		)
		(pad "8" smd roundrect
			(at 0.385 0 270)
			(size 0.4 0.55)
			(layers "B.Cu" "B.Mask" "B.Paste")
			(roundrect_rratio 0.25)
			(net 1 "GND")
			(pintype "passive")
			(teardrops
				(best_length_ratio 0.2)
				(max_length 1)
				(best_width_ratio 0.9)
				(max_width 2)
				(curved_edges yes)
				(filter_ratio 0.9)
				(enabled yes)
				(allow_two_segments yes)
				(prefer_zone_connections yes)
			)
		)
		(pad "9" smd roundrect
			(at 0.385 0.5 270)
			(size 0.25 0.55)
			(layers "B.Cu" "B.Mask" "B.Paste")
			(roundrect_rratio 0.25)
			(net 205 "/Backplane/PCIe_{REF}.CK-")
			(pintype "passive")
			(teardrops
				(best_length_ratio 0.2)
				(max_length 1)
				(best_width_ratio 0.9)
				(max_width 2)
				(curved_edges yes)
				(filter_ratio 0.9)
				(enabled yes)
				(allow_two_segments yes)
				(prefer_zone_connections yes)
			)
		)
		(pad "10" smd roundrect
			(at 0.385 1 270)
			(size 0.25 0.55)
			(layers "B.Cu" "B.Mask" "B.Paste")
			(roundrect_rratio 0.25)
			(net 203 "/Backplane/PCIe_{REF}.CK+")
			(pintype "passive")
			(teardrops
				(best_length_ratio 0.2)
				(max_length 1)
				(best_width_ratio 0.9)
				(max_width 2)
				(curved_edges yes)
				(filter_ratio 0.9)
				(enabled yes)
				(allow_two_segments yes)
				(prefer_zone_connections yes)
			)
		)
	)
	(footprint "antmicro-footprints:C_0603_1608Metric"
		(layer "B.Cu")
		(at 251.22571 74.06 180)
		(descr "Capacitor SMD 0603")
		(tags "capacitor 0603")
		(property "Reference" "C6"
			(at -0.794998 -1.55 0)
			(layer "B.SilkS")
			(effects
				(font
					(size 0.7 0.7)
					(thickness 0.15)
				)
				(justify left bottom mirror)
			)
		)
		(property "Value" "C_22u_16V_0603"
			(at -1.42757 -1.770288 0)
			(layer "B.Fab")
			(effects
				(font
					(size 0.7 0.7)
					(thickness 0.15)
				)
				(justify left bottom mirror)
			)
		)
		(property "Datasheet" "https://product.samsungsem.com/mlcc/CL10A226MO7JZN.do"
			(at 0 0 180)
			(layer "F.Fab")
			(hide yes)
			(effects
				(font
					(size 1.27 1.27)
					(thickness 0.15)
				)
			)
		)
		(property "Author" "Antmicro"
			(at 502.45142 148.12 0)
			(layer "B.Fab")
			(hide yes)
			(effects
				(font
					(size 1 1)
					(thickness 0.15)
				)
				(justify mirror)
			)
		)
		(property "Dielectric" ""
			(at 502.45142 148.12 0)
			(layer "B.Fab")
			(hide yes)
			(effects
				(font
					(size 1 1)
					(thickness 0.15)
				)
				(justify mirror)
			)
		)
		(property "License" "Apache-2.0"
			(at 502.45142 148.12 0)
			(layer "B.Fab")
			(hide yes)
			(effects
				(font
					(size 1 1)
					(thickness 0.15)
				)
				(justify mirror)
			)
		)
		(property "MPN" "CL10A226MO7JZNC"
			(at 502.45142 148.12 0)
			(layer "B.Fab")
			(hide yes)
			(effects
				(font
					(size 1 1)
					(thickness 0.15)
				)
				(justify mirror)
			)
		)
		(property "Manufacturer" "Samsung Electro-Mechanics"
			(at 502.45142 148.12 0)
			(layer "B.Fab")
			(hide yes)
			(effects
				(font
					(size 1 1)
					(thickness 0.15)
				)
				(justify mirror)
			)
		)
		(property "Public" "False"
			(at 502.45142 148.12 0)
			(layer "B.Fab")
			(hide yes)
			(effects
				(font
					(size 1 1)
					(thickness 0.15)
				)
				(justify mirror)
			)
		)
		(property "Val" "22u"
			(at 502.45142 148.12 0)
			(layer "B.Fab")
			(hide yes)
			(effects
				(font
					(size 1 1)
					(thickness 0.15)
				)
				(justify mirror)
			)
		)
		(property "Voltage" "16V"
			(at 502.45142 148.12 0)
			(layer "B.Fab")
			(hide yes)
			(effects
				(font
					(size 1 1)
					(thickness 0.15)
				)
				(justify mirror)
			)
		)
		(sheetname "Misc")
		(sheetfile "misc.kicad_sch")
		(attr smd)
		(fp_line
			(start 0.15 0.4)
			(end -0.15 0.4)
			(stroke
				(width 0.15)
				(type solid)
			)
			(layer "B.SilkS")
		)
		(fp_line
			(start 0.15 -0.4)
			(end -0.15 -0.4)
			(stroke
				(width 0.15)
				(type solid)
			)
			(layer "B.SilkS")
		)
		(fp_rect
			(start -1.25 0.65)
			(end 1.25 -0.65)
			(stroke
				(width 0.05)
				(type solid)
			)
			(fill no)
			(layer "B.CrtYd")
		)
		(fp_rect
			(start -0.8 0.4)
			(end 0.8 -0.4)
			(stroke
				(width 0.15)
				(type solid)
			)
			(fill no)
			(layer "B.Fab")
		)
		(pad "1" smd roundrect
			(at -0.7 0 180)
			(size 0.8 1)
			(layers "B.Cu" "B.Mask" "B.Paste")
			(roundrect_rratio 0.2)
			(net 1 "GND")
			(pintype "passive")
			(teardrops
				(best_length_ratio 0.2)
				(max_length 1)
				(best_width_ratio 0.9)
				(max_width 2)
				(curved_edges yes)
				(filter_ratio 0.9)
				(enabled yes)
				(allow_two_segments yes)
				(prefer_zone_connections yes)
			)
		)
		(pad "2" smd roundrect
			(at 0.7 0 180)
			(size 0.8 1)
			(layers "B.Cu" "B.Mask" "B.Paste")
			(roundrect_rratio 0.2)
			(net 81 "/Misc/FAN_12V")
			(pintype "passive")
			(teardrops
				(best_length_ratio 0.2)
				(max_length 1)
				(best_width_ratio 0.9)
				(max_width 2)
				(curved_edges yes)
				(filter_ratio 0.9)
				(enabled yes)
				(allow_two_segments yes)
				(prefer_zone_connections yes)
			)
		)
	)
	(footprint "antmicro-footprints:C_0402_1005Metric"
		(layer "B.Cu")
		(at 116.9 90.81)
		(descr "Capacitor SMD 0402")
		(tags "capacitor SMD 0402")
		(property "Reference" "C16"
			(at -1.1 -0.5 0)
			(layer "B.SilkS")
			(effects
				(font
					(size 0.7 0.7)
					(thickness 0.15)
				)
				(justify right bottom mirror)
			)
		)
		(property "Value" "C_100n_0402"
			(at -1.022927 -2.155213 0)
			(layer "B.Fab")
			(effects
				(font
					(size 0.7 0.7)
					(thickness 0.15)
				)
				(justify right bottom mirror)
			)
		)
		(property "Datasheet" "https://www.murata.com/products/productdetail?partno=GRM155R61H104KE14%23"
			(at 0 0 0)
			(layer "F.Fab")
			(hide yes)
			(effects
				(font
					(size 1.27 1.27)
					(thickness 0.15)
				)
			)
		)
		(property "Author" "Antmicro"
			(at 0 0 0)
			(layer "B.Fab")
			(hide yes)
			(effects
				(font
					(size 1 1)
					(thickness 0.15)
				)
				(justify mirror)
			)
		)
		(property "Dielectric" "X5R"
			(at 0 0 0)
			(layer "B.Fab")
			(hide yes)
			(effects
				(font
					(size 1 1)
					(thickness 0.15)
				)
				(justify mirror)
			)
		)
		(property "License" "Apache-2.0"
			(at 0 0 0)
			(layer "B.Fab")
			(hide yes)
			(effects
				(font
					(size 1 1)
					(thickness 0.15)
				)
				(justify mirror)
			)
		)
		(property "MPN" "GRM155R61H104KE14D"
			(at 0 0 0)
			(layer "B.Fab")
			(hide yes)
			(effects
				(font
					(size 1 1)
					(thickness 0.15)
				)
				(justify mirror)
			)
		)
		(property "Manufacturer" "Murata"
			(at 0 0 0)
			(layer "B.Fab")
			(hide yes)
			(effects
				(font
					(size 1 1)
					(thickness 0.15)
				)
				(justify mirror)
			)
		)
		(property "Public" "False"
			(at 0 0 0)
			(layer "B.Fab")
			(hide yes)
			(effects
				(font
					(size 1 1)
					(thickness 0.15)
				)
				(justify mirror)
			)
		)
		(property "Val" "100n"
			(at 0 0 0)
			(layer "B.Fab")
			(hide yes)
			(effects
				(font
					(size 1 1)
					(thickness 0.15)
				)
				(justify mirror)
			)
		)
		(property "Voltage" "50V"
			(at 0 0 0)
			(layer "B.Fab")
			(hide yes)
			(effects
				(font
					(size 1 1)
					(thickness 0.15)
				)
				(justify mirror)
			)
		)
		(sheetname "2xUSB3.0+RJ45")
		(sheetfile "usb3+rj45.kicad_sch")
		(attr smd)
		(fp_rect
			(start -0.925 0.47)
			(end 0.925 -0.47)
			(stroke
				(width 0.05)
				(type default)
			)
			(fill no)
			(layer "B.CrtYd")
		)
		(fp_line
			(start -0.494 -0.248)
			(end 0.504 -0.248)
			(stroke
				(width 0.15)
				(type solid)
			)
			(layer "B.Fab")
		)
		(fp_line
			(start -0.494 0.25)
			(end -0.494 -0.248)
			(stroke
				(width 0.15)
				(type solid)
			)
			(layer "B.Fab")
		)
		(fp_line
			(start 0.504 -0.248)
			(end 0.504 0.25)
			(stroke
				(width 0.15)
				(type solid)
			)
			(layer "B.Fab")
		)
		(fp_line
			(start 0.504 0.25)
			(end -0.494 0.25)
			(stroke
				(width 0.15)
				(type solid)
			)
			(layer "B.Fab")
		)
		(pad "1" smd roundrect
			(at -0.48 0)
			(size 0.59 0.64)
			(layers "B.Cu" "B.Mask" "B.Paste")
			(roundrect_rratio 0.25)
			(net 1 "GND")
			(pintype "passive")
			(teardrops
				(best_length_ratio 0.2)
				(max_length 1)
				(best_width_ratio 0.9)
				(max_width 2)
				(curved_edges yes)
				(filter_ratio 0.9)
				(enabled yes)
				(allow_two_segments yes)
				(prefer_zone_connections yes)
			)
		)
		(pad "2" smd roundrect
			(at 0.48 0)
			(size 0.59 0.64)
			(layers "B.Cu" "B.Mask" "B.Paste")
			(roundrect_rratio 0.25)
			(net 52 "+5V")
			(pintype "passive")
			(teardrops
				(best_length_ratio 0.2)
				(max_length 1)
				(best_width_ratio 0.9)
				(max_width 2)
				(curved_edges yes)
				(filter_ratio 0.9)
				(enabled yes)
				(allow_two_segments yes)
				(prefer_zone_connections yes)
			)
		)
	)
	(footprint "antmicro-footprints:R_0402_1005Metric"
		(layer "B.Cu")
		(at 193.246788 140.972629 135)
		(descr "Resistor SMD 0402")
		(tags "resistor SMD 0402")
		(property "Reference" "R223"
			(at -1.04693 0.452587 135)
			(layer "B.SilkS")
			(effects
				(font
					(size 0.7 0.7)
					(thickness 0.15)
				)
				(justify right top mirror)
			)
		)
		(property "Value" "R_1k_0402"
			(at -1.011843 -1.772046 135)
			(layer "B.Fab")
			(effects
				(font
					(size 0.7 0.7)
					(thickness 0.15)
				)
				(justify right top mirror)
			)
		)
		(property "Datasheet" "https://www.bourns.com/docs/product-datasheets/cr.pdf"
			(at 0 0 135)
			(layer "B.Fab")
			(hide yes)
			(effects
				(font
					(size 1.27 1.27)
					(thickness 0.15)
				)
				(justify mirror)
			)
		)
		(property "Author" "Antmicro"
			(at 331.685 54.215 45)
			(layer "B.Fab")
			(hide yes)
			(effects
				(font
					(size 1 1)
					(thickness 0.15)
				)
				(justify mirror)
			)
		)
		(property "License" "Apache-2.0"
			(at 331.685 54.215 45)
			(layer "B.Fab")
			(hide yes)
			(effects
				(font
					(size 1 1)
					(thickness 0.15)
				)
				(justify mirror)
			)
		)
		(property "MPN" "CR0402-FX-1001GLF"
			(at 331.685 54.215 45)
			(layer "B.Fab")
			(hide yes)
			(effects
				(font
					(size 1 1)
					(thickness 0.15)
				)
				(justify mirror)
			)
		)
		(property "Manufacturer" "Bourns"
			(at 331.685 54.215 45)
			(layer "B.Fab")
			(hide yes)
			(effects
				(font
					(size 1 1)
					(thickness 0.15)
				)
				(justify mirror)
			)
		)
		(property "Public" "False"
			(at 331.685 54.215 45)
			(layer "B.Fab")
			(hide yes)
			(effects
				(font
					(size 1 1)
					(thickness 0.15)
				)
				(justify mirror)
			)
		)
		(property "Tolerance" "1%"
			(at 331.685 54.215 45)
			(layer "B.Fab")
			(hide yes)
			(effects
				(font
					(size 1 1)
					(thickness 0.15)
				)
				(justify mirror)
			)
		)
		(property "Val" "1k"
			(at 331.685 54.215 45)
			(layer "B.Fab")
			(hide yes)
			(effects
				(font
					(size 1 1)
					(thickness 0.15)
				)
				(justify mirror)
			)
		)
		(sheetname "PCIe redriver")
		(sheetfile "pcie_redriver.kicad_sch")
		(attr smd dnp)
		(fp_poly
			(pts
				(xy -0.925 0.47) (xy 0.925 0.47) (xy 0.925 -0.47) (xy -0.925 -0.47)
			)
			(stroke
				(width 0.05)
				(type default)
			)
			(fill no)
			(layer "B.CrtYd")
		)
		(fp_poly
			(pts
				(xy -0.5 0.25) (xy 0.5 0.25) (xy 0.5 -0.25) (xy -0.5 -0.25)
			)
			(stroke
				(width 0.15)
				(type solid)
			)
			(fill no)
			(layer "B.Fab")
		)
		(pad "1" smd roundrect
			(at -0.48 0 135)
			(size 0.59 0.64)
			(layers "B.Cu" "B.Mask" "B.Paste")
			(roundrect_rratio 0.25)
			(net 2 "+3V3")
			(pintype "passive")
			(teardrops
				(best_length_ratio 0.2)
				(max_length 1)
				(best_width_ratio 0.9)
				(max_width 2)
				(curved_edges yes)
				(filter_ratio 0.9)
				(enabled yes)
				(allow_two_segments yes)
				(prefer_zone_connections yes)
			)
		)
		(pad "2" smd roundrect
			(at 0.48 0 135)
			(size 0.59 0.64)
			(layers "B.Cu" "B.Mask" "B.Paste")
			(roundrect_rratio 0.25)
			(net 975 "/PCIe redriver/RX_FG0")
			(pintype "passive")
			(teardrops
				(best_length_ratio 0.2)
				(max_length 1)
				(best_width_ratio 0.9)
				(max_width 2)
				(curved_edges yes)
				(filter_ratio 0.9)
				(enabled yes)
				(allow_two_segments yes)
				(prefer_zone_connections yes)
			)
		)
	)
	(footprint "antmicro-footprints:C_0402_1005Metric"
		(layer "B.Cu")
		(at 120.5 73.61 90)
		(descr "Capacitor SMD 0402")
		(tags "capacitor SMD 0402")
		(property "Reference" "C34"
			(at -1.1 -0.45 90)
			(layer "B.SilkS")
			(effects
				(font
					(size 0.7 0.7)
					(thickness 0.15)
				)
				(justify right bottom mirror)
			)
		)
		(property "Value" "C_100n_0402"
			(at -1.022927 -2.155213 90)
			(layer "B.Fab")
			(effects
				(font
					(size 0.7 0.7)
					(thickness 0.15)
				)
				(justify right bottom mirror)
			)
		)
		(property "Datasheet" "https://www.murata.com/products/productdetail?partno=GRM155R61H104KE14%23"
			(at 0 0 90)
			(layer "F.Fab")
			(hide yes)
			(effects
				(font
					(size 1.27 1.27)
					(thickness 0.15)
				)
			)
		)
		(property "Author" "Antmicro"
			(at 194.11 -46.89 0)
			(layer "B.Fab")
			(hide yes)
			(effects
				(font
					(size 1 1)
					(thickness 0.15)
				)
				(justify mirror)
			)
		)
		(property "Dielectric" "X5R"
			(at 194.11 -46.89 0)
			(layer "B.Fab")
			(hide yes)
			(effects
				(font
					(size 1 1)
					(thickness 0.15)
				)
				(justify mirror)
			)
		)
		(property "License" "Apache-2.0"
			(at 194.11 -46.89 0)
			(layer "B.Fab")
			(hide yes)
			(effects
				(font
					(size 1 1)
					(thickness 0.15)
				)
				(justify mirror)
			)
		)
		(property "MPN" "GRM155R61H104KE14D"
			(at 194.11 -46.89 0)
			(layer "B.Fab")
			(hide yes)
			(effects
				(font
					(size 1 1)
					(thickness 0.15)
				)
				(justify mirror)
			)
		)
		(property "Manufacturer" "Murata"
			(at 194.11 -46.89 0)
			(layer "B.Fab")
			(hide yes)
			(effects
				(font
					(size 1 1)
					(thickness 0.15)
				)
				(justify mirror)
			)
		)
		(property "Public" "False"
			(at 194.11 -46.89 0)
			(layer "B.Fab")
			(hide yes)
			(effects
				(font
					(size 1 1)
					(thickness 0.15)
				)
				(justify mirror)
			)
		)
		(property "Val" "100n"
			(at 194.11 -46.89 0)
			(layer "B.Fab")
			(hide yes)
			(effects
				(font
					(size 1 1)
					(thickness 0.15)
				)
				(justify mirror)
			)
		)
		(property "Voltage" "50V"
			(at 194.11 -46.89 0)
			(layer "B.Fab")
			(hide yes)
			(effects
				(font
					(size 1 1)
					(thickness 0.15)
				)
				(justify mirror)
			)
		)
		(sheetname "USB-C console")
		(sheetfile "usb-c_console.kicad_sch")
		(attr smd)
		(fp_rect
			(start -0.925 0.47)
			(end 0.925 -0.47)
			(stroke
				(width 0.05)
				(type default)
			)
			(fill no)
			(layer "B.CrtYd")
		)
		(fp_line
			(start 0.504 -0.248)
			(end 0.504 0.25)
			(stroke
				(width 0.15)
				(type solid)
			)
			(layer "B.Fab")
		)
		(fp_line
			(start -0.494 -0.248)
			(end 0.504 -0.248)
			(stroke
				(width 0.15)
				(type solid)
			)
			(layer "B.Fab")
		)
		(fp_line
			(start 0.504 0.25)
			(end -0.494 0.25)
			(stroke
				(width 0.15)
				(type solid)
			)
			(layer "B.Fab")
		)
		(fp_line
			(start -0.494 0.25)
			(end -0.494 -0.248)
			(stroke
				(width 0.15)
				(type solid)
			)
			(layer "B.Fab")
		)
		(pad "1" smd roundrect
			(at -0.48 0 90)
			(size 0.59 0.64)
			(layers "B.Cu" "B.Mask" "B.Paste")
			(roundrect_rratio 0.25)
			(net 1 "GND")
			(pintype "passive")
			(teardrops
				(best_length_ratio 0.2)
				(max_length 1)
				(best_width_ratio 0.9)
				(max_width 2)
				(curved_edges yes)
				(filter_ratio 0.9)
				(enabled yes)
				(allow_two_segments yes)
				(prefer_zone_connections yes)
			)
		)
		(pad "2" smd roundrect
			(at 0.48 0 90)
			(size 0.59 0.64)
			(layers "B.Cu" "B.Mask" "B.Paste")
			(roundrect_rratio 0.25)
			(net 58 "/USB-C console/VBUS_FTDI")
			(pintype "passive")
			(teardrops
				(best_length_ratio 0.2)
				(max_length 1)
				(best_width_ratio 0.9)
				(max_width 2)
				(curved_edges yes)
				(filter_ratio 0.9)
				(enabled yes)
				(allow_two_segments yes)
				(prefer_zone_connections yes)
			)
		)
	)
	(footprint "antmicro-footprints:C_0603_1608Metric"
		(layer "B.Cu")
		(at 150.45 162.46 90)
		(descr "Capacitor SMD 0603")
		(tags "capacitor 0603")
		(property "Reference" "C22"
			(at -3.3 0.4 90)
			(layer "B.SilkS")
			(effects
				(font
					(size 0.7 0.7)
					(thickness 0.15)
				)
				(justify right bottom mirror)
			)
		)
		(property "Value" "C_22u_16V_0603"
			(at -1.42757 -1.770288 90)
			(layer "B.Fab")
			(effects
				(font
					(size 0.7 0.7)
					(thickness 0.15)
				)
				(justify right bottom mirror)
			)
		)
		(property "Datasheet" "https://product.samsungsem.com/mlcc/CL10A226MO7JZN.do"
			(at 0 0 90)
			(layer "F.Fab")
			(hide yes)
			(effects
				(font
					(size 1.27 1.27)
					(thickness 0.15)
				)
			)
		)
		(property "Author" "Antmicro"
			(at 312.91 12.01 0)
			(layer "B.Fab")
			(hide yes)
			(effects
				(font
					(size 1 1)
					(thickness 0.15)
				)
				(justify mirror)
			)
		)
		(property "Dielectric" ""
			(at 312.91 12.01 0)
			(layer "B.Fab")
			(hide yes)
			(effects
				(font
					(size 1 1)
					(thickness 0.15)
				)
				(justify mirror)
			)
		)
		(property "License" "Apache-2.0"
			(at 312.91 12.01 0)
			(layer "B.Fab")
			(hide yes)
			(effects
				(font
					(size 1 1)
					(thickness 0.15)
				)
				(justify mirror)
			)
		)
		(property "MPN" "CL10A226MO7JZNC"
			(at 312.91 12.01 0)
			(layer "B.Fab")
			(hide yes)
			(effects
				(font
					(size 1 1)
					(thickness 0.15)
				)
				(justify mirror)
			)
		)
		(property "Manufacturer" "Samsung Electro-Mechanics"
			(at 312.91 12.01 0)
			(layer "B.Fab")
			(hide yes)
			(effects
				(font
					(size 1 1)
					(thickness 0.15)
				)
				(justify mirror)
			)
		)
		(property "Public" "False"
			(at 312.91 12.01 0)
			(layer "B.Fab")
			(hide yes)
			(effects
				(font
					(size 1 1)
					(thickness 0.15)
				)
				(justify mirror)
			)
		)
		(property "Val" "22u"
			(at 312.91 12.01 0)
			(layer "B.Fab")
			(hide yes)
			(effects
				(font
					(size 1 1)
					(thickness 0.15)
				)
				(justify mirror)
			)
		)
		(property "Voltage" "16V"
			(at 312.91 12.01 0)
			(layer "B.Fab")
			(hide yes)
			(effects
				(font
					(size 1 1)
					(thickness 0.15)
				)
				(justify mirror)
			)
		)
		(sheetname "2xSFP+")
		(sheetfile "2xSFP+.kicad_sch")
		(attr smd)
		(fp_line
			(start 0.15 -0.4)
			(end -0.15 -0.4)
			(stroke
				(width 0.15)
				(type solid)
			)
			(layer "B.SilkS")
		)
		(fp_line
			(start 0.15 0.4)
			(end -0.15 0.4)
			(stroke
				(width 0.15)
				(type solid)
			)
			(layer "B.SilkS")
		)
		(fp_rect
			(start -1.25 0.65)
			(end 1.25 -0.65)
			(stroke
				(width 0.05)
				(type solid)
			)
			(fill no)
			(layer "B.CrtYd")
		)
		(fp_rect
			(start -0.8 0.4)
			(end 0.8 -0.4)
			(stroke
				(width 0.15)
				(type solid)
			)
			(fill no)
			(layer "B.Fab")
		)
		(pad "1" smd roundrect
			(at -0.7 0 90)
			(size 0.8 1)
			(layers "B.Cu" "B.Mask" "B.Paste")
			(roundrect_rratio 0.2)
			(net 1 "GND")
			(pintype "passive")
			(teardrops
				(best_length_ratio 0.2)
				(max_length 1)
				(best_width_ratio 0.9)
				(max_width 2)
				(curved_edges yes)
				(filter_ratio 0.9)
				(enabled yes)
				(allow_two_segments yes)
				(prefer_zone_connections yes)
			)
		)
		(pad "2" smd roundrect
			(at 0.7 0 90)
			(size 0.8 1)
			(layers "B.Cu" "B.Mask" "B.Paste")
			(roundrect_rratio 0.2)
			(net 2 "+3V3")
			(pintype "passive")
			(teardrops
				(best_length_ratio 0.2)
				(max_length 1)
				(best_width_ratio 0.9)
				(max_width 2)
				(curved_edges yes)
				(filter_ratio 0.9)
				(enabled yes)
				(allow_two_segments yes)
				(prefer_zone_connections yes)
			)
		)
	)
	(footprint "antmicro-footprints:R_0402_1005Metric"
		(layer "B.Cu")
		(at 192.539682 141.679736 135)
		(descr "Resistor SMD 0402")
		(tags "resistor SMD 0402")
		(property "Reference" "R221"
			(at -1.04693 0.452587 135)
			(layer "B.SilkS")
			(effects
				(font
					(size 0.7 0.7)
					(thickness 0.15)
				)
				(justify right top mirror)
			)
		)
		(property "Value" "R_1k_0402"
			(at -1.011843 -1.772046 135)
			(layer "B.Fab")
			(effects
				(font
					(size 0.7 0.7)
					(thickness 0.15)
				)
				(justify right top mirror)
			)
		)
		(property "Datasheet" "https://www.bourns.com/docs/product-datasheets/cr.pdf"
			(at 0 0 135)
			(layer "B.Fab")
			(hide yes)
			(effects
				(font
					(size 1.27 1.27)
					(thickness 0.15)
				)
				(justify mirror)
			)
		)
		(property "Author" "Antmicro"
			(at 332.685 55.214999 45)
			(layer "B.Fab")
			(hide yes)
			(effects
				(font
					(size 1 1)
					(thickness 0.15)
				)
				(justify mirror)
			)
		)
		(property "License" "Apache-2.0"
			(at 332.685 55.214999 45)
			(layer "B.Fab")
			(hide yes)
			(effects
				(font
					(size 1 1)
					(thickness 0.15)
				)
				(justify mirror)
			)
		)
		(property "MPN" "CR0402-FX-1001GLF"
			(at 332.685 55.214999 45)
			(layer "B.Fab")
			(hide yes)
			(effects
				(font
					(size 1 1)
					(thickness 0.15)
				)
				(justify mirror)
			)
		)
		(property "Manufacturer" "Bourns"
			(at 332.685 55.214999 45)
			(layer "B.Fab")
			(hide yes)
			(effects
				(font
					(size 1 1)
					(thickness 0.15)
				)
				(justify mirror)
			)
		)
		(property "Public" "False"
			(at 332.685 55.214999 45)
			(layer "B.Fab")
			(hide yes)
			(effects
				(font
					(size 1 1)
					(thickness 0.15)
				)
				(justify mirror)
			)
		)
		(property "Tolerance" "1%"
			(at 332.685 55.214999 45)
			(layer "B.Fab")
			(hide yes)
			(effects
				(font
					(size 1 1)
					(thickness 0.15)
				)
				(justify mirror)
			)
		)
		(property "Val" "1k"
			(at 332.685 55.214999 45)
			(layer "B.Fab")
			(hide yes)
			(effects
				(font
					(size 1 1)
					(thickness 0.15)
				)
				(justify mirror)
			)
		)
		(sheetname "PCIe redriver")
		(sheetfile "pcie_redriver.kicad_sch")
		(attr smd)
		(fp_poly
			(pts
				(xy -0.925 0.47) (xy 0.925 0.47) (xy 0.925 -0.47) (xy -0.925 -0.47)
			)
			(stroke
				(width 0.05)
				(type default)
			)
			(fill no)
			(layer "B.CrtYd")
		)
		(fp_poly
			(pts
				(xy -0.5 0.25) (xy 0.5 0.25) (xy 0.5 -0.25) (xy -0.5 -0.25)
			)
			(stroke
				(width 0.15)
				(type solid)
			)
			(fill no)
			(layer "B.Fab")
		)
		(pad "1" smd roundrect
			(at -0.48 0 135)
			(size 0.59 0.64)
			(layers "B.Cu" "B.Mask" "B.Paste")
			(roundrect_rratio 0.25)
			(net 2 "+3V3")
			(pintype "passive")
			(teardrops
				(best_length_ratio 0.2)
				(max_length 1)
				(best_width_ratio 0.9)
				(max_width 2)
				(curved_edges yes)
				(filter_ratio 0.9)
				(enabled yes)
				(allow_two_segments yes)
				(prefer_zone_connections yes)
			)
		)
		(pad "2" smd roundrect
			(at 0.48 0 135)
			(size 0.59 0.64)
			(layers "B.Cu" "B.Mask" "B.Paste")
			(roundrect_rratio 0.25)
			(net 974 "/PCIe redriver/RX_FG1")
			(pintype "passive")
			(teardrops
				(best_length_ratio 0.2)
				(max_length 1)
				(best_width_ratio 0.9)
				(max_width 2)
				(curved_edges yes)
				(filter_ratio 0.9)
				(enabled yes)
				(allow_two_segments yes)
				(prefer_zone_connections yes)
			)
		)
	)
	(footprint "antmicro-footprints:R_0402_1005Metric"
		(layer "B.Cu")
		(at 143.05 169.16 -90)
		(descr "Resistor SMD 0402")
		(tags "resistor SMD 0402")
		(property "Reference" "R51"
			(at -3.9 13.5 90)
			(layer "B.SilkS")
			(effects
				(font
					(size 0.7 0.7)
					(thickness 0.15)
				)
				(justify left bottom mirror)
			)
		)
		(property "Value" "R_1k_0402"
			(at -1.011843 -1.772047 90)
			(layer "B.Fab")
			(effects
				(font
					(size 0.7 0.7)
					(thickness 0.15)
				)
				(justify left bottom mirror)
			)
		)
		(property "Datasheet" "https://www.bourns.com/docs/product-datasheets/cr.pdf"
			(at 0 0 270)
			(layer "F.Fab")
			(hide yes)
			(effects
				(font
					(size 1.27 1.27)
					(thickness 0.15)
				)
			)
		)
		(property "Author" "Antmicro"
			(at -26.11 312.21 0)
			(layer "B.Fab")
			(hide yes)
			(effects
				(font
					(size 1 1)
					(thickness 0.15)
				)
				(justify mirror)
			)
		)
		(property "License" "Apache-2.0"
			(at -26.11 312.21 0)
			(layer "B.Fab")
			(hide yes)
			(effects
				(font
					(size 1 1)
					(thickness 0.15)
				)
				(justify mirror)
			)
		)
		(property "MPN" "CR0402-FX-1001GLF"
			(at -26.11 312.21 0)
			(layer "B.Fab")
			(hide yes)
			(effects
				(font
					(size 1 1)
					(thickness 0.15)
				)
				(justify mirror)
			)
		)
		(property "Manufacturer" "Bourns"
			(at -26.11 312.21 0)
			(layer "B.Fab")
			(hide yes)
			(effects
				(font
					(size 1 1)
					(thickness 0.15)
				)
				(justify mirror)
			)
		)
		(property "Public" "False"
			(at -26.11 312.21 0)
			(layer "B.Fab")
			(hide yes)
			(effects
				(font
					(size 1 1)
					(thickness 0.15)
				)
				(justify mirror)
			)
		)
		(property "Tolerance" "1%"
			(at -26.11 312.21 0)
			(layer "B.Fab")
			(hide yes)
			(effects
				(font
					(size 1 1)
					(thickness 0.15)
				)
				(justify mirror)
			)
		)
		(property "Val" "1k"
			(at -26.11 312.21 0)
			(layer "B.Fab")
			(hide yes)
			(effects
				(font
					(size 1 1)
					(thickness 0.15)
				)
				(justify mirror)
			)
		)
		(sheetname "2xSFP+")
		(sheetfile "2xSFP+.kicad_sch")
		(attr smd)
		(fp_rect
			(start -0.925 0.47)
			(end 0.925 -0.47)
			(stroke
				(width 0.05)
				(type default)
			)
			(fill no)
			(layer "B.CrtYd")
		)
		(fp_rect
			(start -0.5 0.25)
			(end 0.5 -0.25)
			(stroke
				(width 0.15)
				(type solid)
			)
			(fill no)
			(layer "B.Fab")
		)
		(pad "1" smd roundrect
			(at -0.48 0 270)
			(size 0.59 0.64)
			(layers "B.Cu" "B.Mask" "B.Paste")
			(roundrect_rratio 0.25)
			(net 162 "Net-(J2A-TX_{FAULT})")
			(pintype "passive")
			(teardrops
				(best_length_ratio 0.2)
				(max_length 1)
				(best_width_ratio 0.9)
				(max_width 2)
				(curved_edges yes)
				(filter_ratio 0.9)
				(enabled yes)
				(allow_two_segments yes)
				(prefer_zone_connections yes)
			)
		)
		(pad "2" smd roundrect
			(at 0.48 0 270)
			(size 0.59 0.64)
			(layers "B.Cu" "B.Mask" "B.Paste")
			(roundrect_rratio 0.25)
			(net 2 "+3V3")
			(pintype "passive")
			(teardrops
				(best_length_ratio 0.2)
				(max_length 1)
				(best_width_ratio 0.9)
				(max_width 2)
				(curved_edges yes)
				(filter_ratio 0.9)
				(enabled yes)
				(allow_two_segments yes)
				(prefer_zone_connections yes)
			)
		)
	)
	(footprint "antmicro-footprints:R_0402_1005Metric"
		(layer "B.Cu")
		(at 114.95 69.86 -90)
		(descr "Resistor SMD 0402")
		(tags "resistor SMD 0402")
		(property "Reference" "R139"
			(at 0.8 -0.45 90)
			(layer "B.SilkS")
			(effects
				(font
					(size 0.7 0.7)
					(thickness 0.15)
				)
				(justify left bottom mirror)
			)
		)
		(property "Value" "R_220R_0402"
			(at -1.011843 -1.772047 90)
			(layer "B.Fab")
			(effects
				(font
					(size 0.7 0.7)
					(thickness 0.15)
				)
				(justify left bottom mirror)
			)
		)
		(property "Datasheet" "https://www.bourns.com/docs/product-datasheets/cr.pdf"
			(at 0 0 270)
			(layer "F.Fab")
			(hide yes)
			(effects
				(font
					(size 1.27 1.27)
					(thickness 0.15)
				)
			)
		)
		(property "Author" "Antmicro"
			(at 45.09 184.81 0)
			(layer "B.Fab")
			(hide yes)
			(effects
				(font
					(size 1 1)
					(thickness 0.15)
				)
				(justify mirror)
			)
		)
		(property "License" "Apache-2.0"
			(at 45.09 184.81 0)
			(layer "B.Fab")
			(hide yes)
			(effects
				(font
					(size 1 1)
					(thickness 0.15)
				)
				(justify mirror)
			)
		)
		(property "MPN" "CR0402-FX-2200GLF"
			(at 45.09 184.81 0)
			(layer "B.Fab")
			(hide yes)
			(effects
				(font
					(size 1 1)
					(thickness 0.15)
				)
				(justify mirror)
			)
		)
		(property "Manufacturer" "Bourns"
			(at 45.09 184.81 0)
			(layer "B.Fab")
			(hide yes)
			(effects
				(font
					(size 1 1)
					(thickness 0.15)
				)
				(justify mirror)
			)
		)
		(property "Public" "False"
			(at 45.09 184.81 0)
			(layer "B.Fab")
			(hide yes)
			(effects
				(font
					(size 1 1)
					(thickness 0.15)
				)
				(justify mirror)
			)
		)
		(property "Tolerance" "1%"
			(at 45.09 184.81 0)
			(layer "B.Fab")
			(hide yes)
			(effects
				(font
					(size 1 1)
					(thickness 0.15)
				)
				(justify mirror)
			)
		)
		(property "Val" "220R"
			(at 45.09 184.81 0)
			(layer "B.Fab")
			(hide yes)
			(effects
				(font
					(size 1 1)
					(thickness 0.15)
				)
				(justify mirror)
			)
		)
		(sheetname "M.2 key E")
		(sheetfile "m2keye.kicad_sch")
		(attr smd)
		(fp_rect
			(start -0.925 0.47)
			(end 0.925 -0.47)
			(stroke
				(width 0.05)
				(type default)
			)
			(fill no)
			(layer "B.CrtYd")
		)
		(fp_rect
			(start -0.5 0.25)
			(end 0.5 -0.25)
			(stroke
				(width 0.15)
				(type solid)
			)
			(fill no)
			(layer "B.Fab")
		)
		(pad "1" smd roundrect
			(at -0.48 0 270)
			(size 0.59 0.64)
			(layers "B.Cu" "B.Mask" "B.Paste")
			(roundrect_rratio 0.25)
			(net 938 "Net-(D16-A)")
			(pintype "passive")
			(teardrops
				(best_length_ratio 0.2)
				(max_length 1)
				(best_width_ratio 0.9)
				(max_width 2)
				(curved_edges yes)
				(filter_ratio 0.9)
				(enabled yes)
				(allow_two_segments yes)
				(prefer_zone_connections yes)
			)
		)
		(pad "2" smd roundrect
			(at 0.48 0 270)
			(size 0.59 0.64)
			(layers "B.Cu" "B.Mask" "B.Paste")
			(roundrect_rratio 0.25)
			(net 2 "+3V3")
			(pintype "passive")
			(teardrops
				(best_length_ratio 0.2)
				(max_length 1)
				(best_width_ratio 0.9)
				(max_width 2)
				(curved_edges yes)
				(filter_ratio 0.9)
				(enabled yes)
				(allow_two_segments yes)
				(prefer_zone_connections yes)
			)
		)
	)
	(footprint "antmicro-footprints:TP_SMD_0.75mm"
		(layer "B.Cu")
		(at 208.8 155.95 180)
		(property "Reference" "TP42"
			(at 0.8 -0.4 0)
			(layer "B.SilkS")
			(effects
				(font
					(size 0.7 0.7)
					(thickness 0.15)
				)
				(justify left bottom mirror)
			)
		)
		(property "Value" "TP_0.75mm_SMD"
			(at 3.225 -53.865 0)
			(layer "B.Fab")
			(hide yes)
			(effects
				(font
					(size 0.7 0.7)
					(thickness 0.15)
				)
				(justify left bottom mirror)
			)
		)
		(property "Author" "Antmicro"
			(at 395.05 321.57 0)
			(layer "B.Fab")
			(hide yes)
			(effects
				(font
					(size 1 1)
					(thickness 0.15)
				)
				(justify mirror)
			)
		)
		(property "License" "Apache-2.0"
			(at 395.05 321.57 0)
			(layer "B.Fab")
			(hide yes)
			(effects
				(font
					(size 1 1)
					(thickness 0.15)
				)
				(justify mirror)
			)
		)
		(property "MPN" ""
			(at 395.05 321.57 0)
			(layer "B.Fab")
			(hide yes)
			(effects
				(font
					(size 1 1)
					(thickness 0.15)
				)
				(justify mirror)
			)
		)
		(property "Manufacturer" ""
			(at 395.05 321.57 0)
			(layer "B.Fab")
			(hide yes)
			(effects
				(font
					(size 1 1)
					(thickness 0.15)
				)
				(justify mirror)
			)
		)
		(property "Public" "False"
			(at 395.05 321.57 0)
			(layer "B.Fab")
			(hide yes)
			(effects
				(font
					(size 1 1)
					(thickness 0.15)
				)
				(justify mirror)
			)
		)
		(sheetname "Com Express 7 MGMT")
		(sheetfile "com_express_7_mgmt.kicad_sch")
		(attr exclude_from_pos_files exclude_from_bom)
		(fp_circle
			(center 0 0)
			(end 0.475 0)
			(stroke
				(width 0.05)
				(type default)
			)
			(fill no)
			(layer "B.CrtYd")
		)
		(pad "1" smd circle
			(at 0 0 180)
			(size 0.75 0.75)
			(layers "B.Cu" "B.Mask")
			(net 439 "Net-(J12L-RAPID_SHUTDOWN)")
			(pinfunction "1")
			(pintype "passive")
			(teardrops
				(best_length_ratio 0.4)
				(max_length 1)
				(best_width_ratio 0.9)
				(max_width 2)
				(curved_edges yes)
				(filter_ratio 0.9)
				(enabled yes)
				(allow_two_segments yes)
				(prefer_zone_connections yes)
			)
		)
	)
	(footprint "antmicro-footprints:R_0402_1005Metric"
		(layer "B.Cu")
		(at 99.3 77.81)
		(descr "Resistor SMD 0402")
		(tags "resistor SMD 0402")
		(property "Reference" "R140"
			(at -3.65 0.4 0)
			(layer "B.SilkS")
			(effects
				(font
					(size 0.7 0.7)
					(thickness 0.15)
				)
				(justify right bottom mirror)
			)
		)
		(property "Value" "R_10k_0402"
			(at -1.011843 -1.772047 0)
			(layer "B.Fab")
			(effects
				(font
					(size 0.7 0.7)
					(thickness 0.15)
				)
				(justify right bottom mirror)
			)
		)
		(property "Datasheet" "https://www.bourns.com/docs/product-datasheets/cr.pdf"
			(at 0 0 0)
			(layer "F.Fab")
			(hide yes)
			(effects
				(font
					(size 1.27 1.27)
					(thickness 0.15)
				)
			)
		)
		(property "Description" "SMD Chip Resistor, 10 kohm, ± 1%, 62.5 mW, 0402 [1005 Metric], Thick Film, General Purpose"
			(at 0 0 0)
			(layer "F.Fab")
			(hide yes)
			(effects
				(font
					(size 1.27 1.27)
					(thickness 0.15)
				)
			)
		)
		(property "Author" "Antmicro"
			(at 0 0 0)
			(layer "B.Fab")
			(hide yes)
			(effects
				(font
					(size 1 1)
					(thickness 0.15)
				)
				(justify mirror)
			)
		)
		(property "License" "Apache-2.0"
			(at 0 0 0)
			(layer "B.Fab")
			(hide yes)
			(effects
				(font
					(size 1 1)
					(thickness 0.15)
				)
				(justify mirror)
			)
		)
		(property "MPN" "CR0402-FX-1002GLF"
			(at 0 0 0)
			(layer "B.Fab")
			(hide yes)
			(effects
				(font
					(size 1 1)
					(thickness 0.15)
				)
				(justify mirror)
			)
		)
		(property "Manufacturer" "Bourns"
			(at 0 0 0)
			(layer "B.Fab")
			(hide yes)
			(effects
				(font
					(size 1 1)
					(thickness 0.15)
				)
				(justify mirror)
			)
		)
		(property "Tolerance" "1%"
			(at 0 0 0)
			(layer "B.Fab")
			(hide yes)
			(effects
				(font
					(size 1 1)
					(thickness 0.15)
				)
				(justify mirror)
			)
		)
		(property "Val" "10k"
			(at 0 0 0)
			(layer "B.Fab")
			(hide yes)
			(effects
				(font
					(size 1 1)
					(thickness 0.15)
				)
				(justify mirror)
			)
		)
		(sheetname "Misc")
		(sheetfile "misc.kicad_sch")
		(attr smd)
		(fp_rect
			(start -0.925 0.47)
			(end 0.925 -0.47)
			(stroke
				(width 0.05)
				(type default)
			)
			(fill no)
			(layer "B.CrtYd")
		)
		(fp_rect
			(start -0.5 0.25)
			(end 0.5 -0.25)
			(stroke
				(width 0.15)
				(type solid)
			)
			(fill no)
			(layer "B.Fab")
		)
		(pad "1" smd roundrect
			(at -0.48 0)
			(size 0.59 0.64)
			(layers "B.Cu" "B.Mask" "B.Paste")
			(roundrect_rratio 0.25)
			(net 943 "/GPIO expander/GPIOEX1")
			(pintype "passive")
			(teardrops
				(best_length_ratio 0.2)
				(max_length 1)
				(best_width_ratio 0.9)
				(max_width 2)
				(curved_edges yes)
				(filter_ratio 0.9)
				(enabled yes)
				(allow_two_segments yes)
				(prefer_zone_connections yes)
			)
		)
		(pad "2" smd roundrect
			(at 0.48 0)
			(size 0.59 0.64)
			(layers "B.Cu" "B.Mask" "B.Paste")
			(roundrect_rratio 0.25)
			(net 131 "Net-(D17-C_{B})")
			(pintype "passive")
			(teardrops
				(best_length_ratio 0.2)
				(max_length 1)
				(best_width_ratio 0.9)
				(max_width 2)
				(curved_edges yes)
				(filter_ratio 0.9)
				(enabled yes)
				(allow_two_segments yes)
				(prefer_zone_connections yes)
			)
		)
	)
	(footprint "antmicro-footprints:TP_SMD_0.75mm"
		(layer "B.Cu")
		(at 186.7 168.7 -90)
		(property "Reference" "TP37"
			(at -0.5 3.15 0)
			(layer "B.SilkS")
			(effects
				(font
					(size 0.7 0.7)
					(thickness 0.15)
				)
				(justify right top mirror)
			)
		)
		(property "Value" "TP_0.75mm_SMD"
			(at 0 -1.2 90)
			(layer "B.Fab")
			(effects
				(font
					(size 0.7 0.7)
					(thickness 0.15)
				)
				(justify left bottom mirror)
			)
		)
		(property "Author" "Antmicro"
			(at 432.2 298.12 90)
			(layer "B.Fab")
			(hide yes)
			(effects
				(font
					(size 1 1)
					(thickness 0.15)
				)
				(justify mirror)
			)
		)
		(property "License" "Apache-2.0"
			(at 432.2 298.12 90)
			(layer "B.Fab")
			(hide yes)
			(effects
				(font
					(size 1 1)
					(thickness 0.15)
				)
				(justify mirror)
			)
		)
		(property "MPN" ""
			(at 432.2 298.12 90)
			(layer "B.Fab")
			(hide yes)
			(effects
				(font
					(size 1 1)
					(thickness 0.15)
				)
				(justify mirror)
			)
		)
		(property "Manufacturer" ""
			(at 432.2 298.12 90)
			(layer "B.Fab")
			(hide yes)
			(effects
				(font
					(size 1 1)
					(thickness 0.15)
				)
				(justify mirror)
			)
		)
		(property "Public" "False"
			(at 432.2 298.12 90)
			(layer "B.Fab")
			(hide yes)
			(effects
				(font
					(size 1 1)
					(thickness 0.15)
				)
				(justify mirror)
			)
		)
		(sheetname "Com Express 7 MGMT")
		(sheetfile "com_express_7_mgmt.kicad_sch")
		(attr exclude_from_pos_files exclude_from_bom)
		(fp_circle
			(center 0 0)
			(end 0.475 0)
			(stroke
				(width 0.05)
				(type default)
			)
			(fill no)
			(layer "B.CrtYd")
		)
		(pad "1" smd circle
			(at 0 0 270)
			(size 0.75 0.75)
			(layers "B.Cu" "B.Mask")
			(net 304 "Net-(J12D-~{BATLOW})")
			(pinfunction "1")
			(pintype "passive")
			(teardrops
				(best_length_ratio 0.4)
				(max_length 1)
				(best_width_ratio 0.9)
				(max_width 2)
				(curved_edges yes)
				(filter_ratio 0.9)
				(enabled yes)
				(allow_two_segments yes)
				(prefer_zone_connections yes)
			)
		)
	)
	(footprint "antmicro-footprints:R_0402_1005Metric"
		(layer "B.Cu")
		(at 123.4 112.81 180)
		(descr "Resistor SMD 0402")
		(tags "resistor SMD 0402")
		(property "Reference" "R4"
			(at -2.35 -0.45 0)
			(layer "B.SilkS")
			(effects
				(font
					(size 0.7 0.7)
					(thickness 0.15)
				)
				(justify left bottom mirror)
			)
		)
		(property "Value" "R_0R_0402"
			(at -1.011843 -1.772047 0)
			(layer "B.Fab")
			(effects
				(font
					(size 0.7 0.7)
					(thickness 0.15)
				)
				(justify left bottom mirror)
			)
		)
		(property "Datasheet" "https://industrial.panasonic.com/cdbs/www-data/pdf/RDA0000/AOA0000C301.pdf"
			(at 0 0 180)
			(layer "F.Fab")
			(hide yes)
			(effects
				(font
					(size 1.27 1.27)
					(thickness 0.15)
				)
			)
		)
		(property "Author" "Antmicro"
			(at 246.8 225.62 0)
			(layer "B.Fab")
			(hide yes)
			(effects
				(font
					(size 1 1)
					(thickness 0.15)
				)
				(justify mirror)
			)
		)
		(property "Current" "1A"
			(at 246.8 225.62 0)
			(layer "B.Fab")
			(hide yes)
			(effects
				(font
					(size 1 1)
					(thickness 0.15)
				)
				(justify mirror)
			)
		)
		(property "License" "Apache-2.0"
			(at 246.8 225.62 0)
			(layer "B.Fab")
			(hide yes)
			(effects
				(font
					(size 1 1)
					(thickness 0.15)
				)
				(justify mirror)
			)
		)
		(property "MPN" "ERJ2GE0R00X"
			(at 246.8 225.62 0)
			(layer "B.Fab")
			(hide yes)
			(effects
				(font
					(size 1 1)
					(thickness 0.15)
				)
				(justify mirror)
			)
		)
		(property "Manufacturer" "Panasonic"
			(at 246.8 225.62 0)
			(layer "B.Fab")
			(hide yes)
			(effects
				(font
					(size 1 1)
					(thickness 0.15)
				)
				(justify mirror)
			)
		)
		(property "Public" "False"
			(at 246.8 225.62 0)
			(layer "B.Fab")
			(hide yes)
			(effects
				(font
					(size 1 1)
					(thickness 0.15)
				)
				(justify mirror)
			)
		)
		(property "Tolerance" ""
			(at 246.8 225.62 0)
			(layer "B.Fab")
			(hide yes)
			(effects
				(font
					(size 1 1)
					(thickness 0.15)
				)
				(justify mirror)
			)
		)
		(property "Val" "0R"
			(at 246.8 225.62 0)
			(layer "B.Fab")
			(hide yes)
			(effects
				(font
					(size 1 1)
					(thickness 0.15)
				)
				(justify mirror)
			)
		)
		(sheetname "2xUSB3.0+RJ45")
		(sheetfile "usb3+rj45.kicad_sch")
		(attr smd dnp)
		(fp_rect
			(start -0.925 0.47)
			(end 0.925 -0.47)
			(stroke
				(width 0.05)
				(type default)
			)
			(fill no)
			(layer "B.CrtYd")
		)
		(fp_rect
			(start -0.5 0.25)
			(end 0.5 -0.25)
			(stroke
				(width 0.15)
				(type solid)
			)
			(fill no)
			(layer "B.Fab")
		)
		(pad "1" smd roundrect
			(at -0.48 0 180)
			(size 0.59 0.64)
			(layers "B.Cu" "B.Mask" "B.Paste")
			(roundrect_rratio 0.25)
			(net 291 "/2xUSB3.0+RJ45/~{GBE0_LINK}")
			(pintype "passive")
			(teardrops
				(best_length_ratio 0.2)
				(max_length 1)
				(best_width_ratio 0.9)
				(max_width 2)
				(curved_edges yes)
				(filter_ratio 0.9)
				(enabled yes)
				(allow_two_segments yes)
				(prefer_zone_connections yes)
			)
		)
		(pad "2" smd roundrect
			(at 0.48 0 180)
			(size 0.59 0.64)
			(layers "B.Cu" "B.Mask" "B.Paste")
			(roundrect_rratio 0.25)
			(net 157 "Net-(J1A-LED_D4)")
			(pintype "passive")
			(teardrops
				(best_length_ratio 0.2)
				(max_length 1)
				(best_width_ratio 0.9)
				(max_width 2)
				(curved_edges yes)
				(filter_ratio 0.9)
				(enabled yes)
				(allow_two_segments yes)
				(prefer_zone_connections yes)
			)
		)
	)
	(footprint "antmicro-footprints:C_0603_1608Metric"
		(layer "B.Cu")
		(at 154.6 132.06 -90)
		(descr "Capacitor SMD 0603")
		(tags "capacitor 0603")
		(property "Reference" "C155"
			(at -1.42757 -1.55 90)
			(layer "B.SilkS")
			(effects
				(font
					(size 0.7 0.7)
					(thickness 0.15)
				)
				(justify left bottom mirror)
			)
		)
		(property "Value" "C_22u_16V_0603"
			(at -1.42757 -1.770288 90)
			(layer "B.Fab")
			(effects
				(font
					(size 0.7 0.7)
					(thickness 0.15)
				)
				(justify left bottom mirror)
			)
		)
		(property "Datasheet" "https://product.samsungsem.com/mlcc/CL10A226MO7JZN.do"
			(at 0 0 270)
			(layer "F.Fab")
			(hide yes)
			(effects
				(font
					(size 1.27 1.27)
					(thickness 0.15)
				)
			)
		)
		(property "Author" "Antmicro"
			(at 22.54 286.66 0)
			(layer "B.Fab")
			(hide yes)
			(effects
				(font
					(size 1 1)
					(thickness 0.15)
				)
				(justify mirror)
			)
		)
		(property "Dielectric" ""
			(at 22.54 286.66 0)
			(layer "B.Fab")
			(hide yes)
			(effects
				(font
					(size 1 1)
					(thickness 0.15)
				)
				(justify mirror)
			)
		)
		(property "License" "Apache-2.0"
			(at 22.54 286.66 0)
			(layer "B.Fab")
			(hide yes)
			(effects
				(font
					(size 1 1)
					(thickness 0.15)
				)
				(justify mirror)
			)
		)
		(property "MPN" "CL10A226MO7JZNC"
			(at 22.54 286.66 0)
			(layer "B.Fab")
			(hide yes)
			(effects
				(font
					(size 1 1)
					(thickness 0.15)
				)
				(justify mirror)
			)
		)
		(property "Manufacturer" "Samsung Electro-Mechanics"
			(at 22.54 286.66 0)
			(layer "B.Fab")
			(hide yes)
			(effects
				(font
					(size 1 1)
					(thickness 0.15)
				)
				(justify mirror)
			)
		)
		(property "Public" "False"
			(at 22.54 286.66 0)
			(layer "B.Fab")
			(hide yes)
			(effects
				(font
					(size 1 1)
					(thickness 0.15)
				)
				(justify mirror)
			)
		)
		(property "Val" "22u"
			(at 22.54 286.66 0)
			(layer "B.Fab")
			(hide yes)
			(effects
				(font
					(size 1 1)
					(thickness 0.15)
				)
				(justify mirror)
			)
		)
		(property "Voltage" "16V"
			(at 22.54 286.66 0)
			(layer "B.Fab")
			(hide yes)
			(effects
				(font
					(size 1 1)
					(thickness 0.15)
				)
				(justify mirror)
			)
		)
		(sheetname "KR to SFI #1")
		(sheetfile "kr_sfi.kicad_sch")
		(attr smd)
		(fp_line
			(start 0.15 0.4)
			(end -0.15 0.4)
			(stroke
				(width 0.15)
				(type solid)
			)
			(layer "B.SilkS")
		)
		(fp_line
			(start 0.15 -0.4)
			(end -0.15 -0.4)
			(stroke
				(width 0.15)
				(type solid)
			)
			(layer "B.SilkS")
		)
		(fp_rect
			(start -1.25 0.65)
			(end 1.25 -0.65)
			(stroke
				(width 0.05)
				(type solid)
			)
			(fill no)
			(layer "B.CrtYd")
		)
		(fp_rect
			(start -0.8 0.4)
			(end 0.8 -0.4)
			(stroke
				(width 0.15)
				(type solid)
			)
			(fill no)
			(layer "B.Fab")
		)
		(pad "1" smd roundrect
			(at -0.7 0 270)
			(size 0.8 1)
			(layers "B.Cu" "B.Mask" "B.Paste")
			(roundrect_rratio 0.2)
			(net 1 "GND")
			(pintype "passive")
			(teardrops
				(best_length_ratio 0.2)
				(max_length 1)
				(best_width_ratio 0.9)
				(max_width 2)
				(curved_edges yes)
				(filter_ratio 0.9)
				(enabled yes)
				(allow_two_segments yes)
				(prefer_zone_connections yes)
			)
		)
		(pad "2" smd roundrect
			(at 0.7 0 270)
			(size 0.8 1)
			(layers "B.Cu" "B.Mask" "B.Paste")
			(roundrect_rratio 0.2)
			(net 74 "+1V0")
			(pintype "passive")
			(teardrops
				(best_length_ratio 0.2)
				(max_length 1)
				(best_width_ratio 0.9)
				(max_width 2)
				(curved_edges yes)
				(filter_ratio 0.9)
				(enabled yes)
				(allow_two_segments yes)
				(prefer_zone_connections yes)
			)
		)
	)
	(footprint "antmicro-footprints:R_0603_1608Metric"
		(layer "B.Cu")
		(at 304.7 81.46)
		(descr "Resistor SMD 0603")
		(tags "resistor SMD 0603")
		(property "Reference" "R131"
			(at -1.45 1.55 0)
			(layer "B.SilkS")
			(effects
				(font
					(size 0.7 0.7)
					(thickness 0.15)
				)
				(justify right bottom mirror)
			)
		)
		(property "Value" "R_0R_22.4A_0603"
			(at 0 -1.6 0)
			(layer "B.Fab")
			(effects
				(font
					(size 0.7 0.7)
					(thickness 0.15)
				)
				(justify right bottom mirror)
			)
		)
		(property "Datasheet" "https://fscdn.rohm.com/en/products/databook/datasheet/passive/resistor/chip_resistor/pmr-jpw-e.pdf"
			(at 0 0 0)
			(layer "F.Fab")
			(hide yes)
			(effects
				(font
					(size 1.27 1.27)
					(thickness 0.15)
				)
			)
		)
		(property "Author" "Antmicro"
			(at 0 0 0)
			(layer "B.Fab")
			(hide yes)
			(effects
				(font
					(size 1 1)
					(thickness 0.15)
				)
				(justify mirror)
			)
		)
		(property "License" "Apache-2.0"
			(at 0 0 0)
			(layer "B.Fab")
			(hide yes)
			(effects
				(font
					(size 1 1)
					(thickness 0.15)
				)
				(justify mirror)
			)
		)
		(property "MPN" "PMR03EZPJ000"
			(at 0 0 0)
			(layer "B.Fab")
			(hide yes)
			(effects
				(font
					(size 1 1)
					(thickness 0.15)
				)
				(justify mirror)
			)
		)
		(property "Manufacturer" "ROHM Semiconductor"
			(at 0 0 0)
			(layer "B.Fab")
			(hide yes)
			(effects
				(font
					(size 1 1)
					(thickness 0.15)
				)
				(justify mirror)
			)
		)
		(property "Max. Curr." "22.4A"
			(at 0 0 0)
			(layer "B.Fab")
			(hide yes)
			(effects
				(font
					(size 1 1)
					(thickness 0.15)
				)
				(justify mirror)
			)
		)
		(property "Public" "False"
			(at 0 0 0)
			(layer "B.Fab")
			(hide yes)
			(effects
				(font
					(size 1 1)
					(thickness 0.15)
				)
				(justify mirror)
			)
		)
		(property "Tolerance" "template_tolerance"
			(at 0 0 0)
			(layer "B.Fab")
			(hide yes)
			(effects
				(font
					(size 1 1)
					(thickness 0.15)
				)
				(justify mirror)
			)
		)
		(property "Val" "0R"
			(at 0 0 0)
			(layer "B.Fab")
			(hide yes)
			(effects
				(font
					(size 1 1)
					(thickness 0.15)
				)
				(justify mirror)
			)
		)
		(sheetname "M.2 key M #2")
		(sheetfile "m2keym.kicad_sch")
		(attr smd)
		(fp_line
			(start 0.15 -0.4)
			(end -0.15 -0.4)
			(stroke
				(width 0.15)
				(type solid)
			)
			(layer "B.SilkS")
		)
		(fp_line
			(start 0.15 0.4)
			(end -0.15 0.4)
			(stroke
				(width 0.15)
				(type solid)
			)
			(layer "B.SilkS")
		)
		(fp_rect
			(start -1.25 0.65)
			(end 1.25 -0.65)
			(stroke
				(width 0.05)
				(type solid)
			)
			(fill no)
			(layer "B.CrtYd")
		)
		(fp_rect
			(start -0.8 0.4)
			(end 0.8 -0.4)
			(stroke
				(width 0.15)
				(type solid)
			)
			(fill no)
			(layer "B.Fab")
		)
		(pad "1" smd roundrect
			(at -0.7 0)
			(size 0.8 1)
			(layers "B.Cu" "B.Mask" "B.Paste")
			(roundrect_rratio 0.2)
			(net 970 "/M.2 key M #2/M2_3V3")
			(pintype "passive")
			(teardrops
				(best_length_ratio 0.2)
				(max_length 1)
				(best_width_ratio 0.9)
				(max_width 2)
				(curved_edges yes)
				(filter_ratio 0.9)
				(enabled yes)
				(allow_two_segments yes)
				(prefer_zone_connections yes)
			)
		)
		(pad "2" smd roundrect
			(at 0.7 0)
			(size 0.8 1)
			(layers "B.Cu" "B.Mask" "B.Paste")
			(roundrect_rratio 0.2)
			(net 2 "+3V3")
			(pintype "passive")
			(teardrops
				(best_length_ratio 0.2)
				(max_length 1)
				(best_width_ratio 0.9)
				(max_width 2)
				(curved_edges yes)
				(filter_ratio 0.9)
				(enabled yes)
				(allow_two_segments yes)
				(prefer_zone_connections yes)
			)
		)
	)
	(footprint "antmicro-footprints:R_0402_1005Metric"
		(layer "B.Cu")
		(at 147.05 169.16 -90)
		(descr "Resistor SMD 0402")
		(tags "resistor SMD 0402")
		(property "Reference" "R58"
			(at -3.9 13.5 90)
			(layer "B.SilkS")
			(effects
				(font
					(size 0.7 0.7)
					(thickness 0.15)
				)
				(justify left bottom mirror)
			)
		)
		(property "Value" "R_0R_0402"
			(at -1.011843 -1.772047 90)
			(layer "B.Fab")
			(effects
				(font
					(size 0.7 0.7)
					(thickness 0.15)
				)
				(justify left bottom mirror)
			)
		)
		(property "Datasheet" "https://industrial.panasonic.com/cdbs/www-data/pdf/RDA0000/AOA0000C301.pdf"
			(at 0 0 270)
			(layer "F.Fab")
			(hide yes)
			(effects
				(font
					(size 1.27 1.27)
					(thickness 0.15)
				)
			)
		)
		(property "Author" "Antmicro"
			(at -22.11 316.21 0)
			(layer "B.Fab")
			(hide yes)
			(effects
				(font
					(size 1 1)
					(thickness 0.15)
				)
				(justify mirror)
			)
		)
		(property "Current" "1A"
			(at -22.11 316.21 0)
			(layer "B.Fab")
			(hide yes)
			(effects
				(font
					(size 1 1)
					(thickness 0.15)
				)
				(justify mirror)
			)
		)
		(property "License" "Apache-2.0"
			(at -22.11 316.21 0)
			(layer "B.Fab")
			(hide yes)
			(effects
				(font
					(size 1 1)
					(thickness 0.15)
				)
				(justify mirror)
			)
		)
		(property "MPN" "ERJ2GE0R00X"
			(at -22.11 316.21 0)
			(layer "B.Fab")
			(hide yes)
			(effects
				(font
					(size 1 1)
					(thickness 0.15)
				)
				(justify mirror)
			)
		)
		(property "Manufacturer" "Panasonic"
			(at -22.11 316.21 0)
			(layer "B.Fab")
			(hide yes)
			(effects
				(font
					(size 1 1)
					(thickness 0.15)
				)
				(justify mirror)
			)
		)
		(property "Public" "False"
			(at -22.11 316.21 0)
			(layer "B.Fab")
			(hide yes)
			(effects
				(font
					(size 1 1)
					(thickness 0.15)
				)
				(justify mirror)
			)
		)
		(property "Tolerance" ""
			(at -22.11 316.21 0)
			(layer "B.Fab")
			(hide yes)
			(effects
				(font
					(size 1 1)
					(thickness 0.15)
				)
				(justify mirror)
			)
		)
		(property "Val" "0R"
			(at -22.11 316.21 0)
			(layer "B.Fab")
			(hide yes)
			(effects
				(font
					(size 1 1)
					(thickness 0.15)
				)
				(justify mirror)
			)
		)
		(sheetname "2xSFP+")
		(sheetfile "2xSFP+.kicad_sch")
		(attr smd)
		(fp_rect
			(start -0.925 0.47)
			(end 0.925 -0.47)
			(stroke
				(width 0.05)
				(type default)
			)
			(fill no)
			(layer "B.CrtYd")
		)
		(fp_rect
			(start -0.5 0.25)
			(end 0.5 -0.25)
			(stroke
				(width 0.15)
				(type solid)
			)
			(fill no)
			(layer "B.Fab")
		)
		(pad "1" smd roundrect
			(at -0.48 0 270)
			(size 0.59 0.64)
			(layers "B.Cu" "B.Mask" "B.Paste")
			(roundrect_rratio 0.25)
			(net 169 "Net-(J2A-RS1)")
			(pintype "passive")
			(teardrops
				(best_length_ratio 0.2)
				(max_length 1)
				(best_width_ratio 0.9)
				(max_width 2)
				(curved_edges yes)
				(filter_ratio 0.9)
				(enabled yes)
				(allow_two_segments yes)
				(prefer_zone_connections yes)
			)
		)
		(pad "2" smd roundrect
			(at 0.48 0 270)
			(size 0.59 0.64)
			(layers "B.Cu" "B.Mask" "B.Paste")
			(roundrect_rratio 0.25)
			(net 1 "GND")
			(pintype "passive")
			(teardrops
				(best_length_ratio 0.2)
				(max_length 1)
				(best_width_ratio 0.9)
				(max_width 2)
				(curved_edges yes)
				(filter_ratio 0.9)
				(enabled yes)
				(allow_two_segments yes)
				(prefer_zone_connections yes)
			)
		)
	)
	(footprint "antmicro-footprints:C_0402_1005Metric"
		(layer "B.Cu")
		(at 242.620708 78.135)
		(descr "Capacitor SMD 0402")
		(tags "capacitor SMD 0402")
		(property "Reference" "C85"
			(at -1.1 1.375 0)
			(layer "B.SilkS")
			(effects
				(font
					(size 0.7 0.7)
					(thickness 0.15)
				)
				(justify right bottom mirror)
			)
		)
		(property "Value" "C_100n_0402"
			(at -1.022927 -2.155213 0)
			(layer "B.Fab")
			(effects
				(font
					(size 0.7 0.7)
					(thickness 0.15)
				)
				(justify right bottom mirror)
			)
		)
		(property "Datasheet" "https://www.murata.com/products/productdetail?partno=GRM155R61H104KE14%23"
			(at 0 0 0)
			(layer "F.Fab")
			(hide yes)
			(effects
				(font
					(size 1.27 1.27)
					(thickness 0.15)
				)
			)
		)
		(property "Author" "Antmicro"
			(at 0 0 0)
			(layer "B.Fab")
			(hide yes)
			(effects
				(font
					(size 1 1)
					(thickness 0.15)
				)
				(justify mirror)
			)
		)
		(property "Dielectric" "X5R"
			(at 0 0 0)
			(layer "B.Fab")
			(hide yes)
			(effects
				(font
					(size 1 1)
					(thickness 0.15)
				)
				(justify mirror)
			)
		)
		(property "License" "Apache-2.0"
			(at 0 0 0)
			(layer "B.Fab")
			(hide yes)
			(effects
				(font
					(size 1 1)
					(thickness 0.15)
				)
				(justify mirror)
			)
		)
		(property "MPN" "GRM155R61H104KE14D"
			(at 0 0 0)
			(layer "B.Fab")
			(hide yes)
			(effects
				(font
					(size 1 1)
					(thickness 0.15)
				)
				(justify mirror)
			)
		)
		(property "Manufacturer" "Murata"
			(at 0 0 0)
			(layer "B.Fab")
			(hide yes)
			(effects
				(font
					(size 1 1)
					(thickness 0.15)
				)
				(justify mirror)
			)
		)
		(property "Public" "False"
			(at 0 0 0)
			(layer "B.Fab")
			(hide yes)
			(effects
				(font
					(size 1 1)
					(thickness 0.15)
				)
				(justify mirror)
			)
		)
		(property "Val" "100n"
			(at 0 0 0)
			(layer "B.Fab")
			(hide yes)
			(effects
				(font
					(size 1 1)
					(thickness 0.15)
				)
				(justify mirror)
			)
		)
		(property "Voltage" "50V"
			(at 0 0 0)
			(layer "B.Fab")
			(hide yes)
			(effects
				(font
					(size 1 1)
					(thickness 0.15)
				)
				(justify mirror)
			)
		)
		(sheetname "Misc")
		(sheetfile "misc.kicad_sch")
		(attr smd)
		(fp_rect
			(start -0.925 0.47)
			(end 0.925 -0.47)
			(stroke
				(width 0.05)
				(type default)
			)
			(fill no)
			(layer "B.CrtYd")
		)
		(fp_line
			(start -0.494 -0.248)
			(end 0.504 -0.248)
			(stroke
				(width 0.15)
				(type solid)
			)
			(layer "B.Fab")
		)
		(fp_line
			(start -0.494 0.25)
			(end -0.494 -0.248)
			(stroke
				(width 0.15)
				(type solid)
			)
			(layer "B.Fab")
		)
		(fp_line
			(start 0.504 -0.248)
			(end 0.504 0.25)
			(stroke
				(width 0.15)
				(type solid)
			)
			(layer "B.Fab")
		)
		(fp_line
			(start 0.504 0.25)
			(end -0.494 0.25)
			(stroke
				(width 0.15)
				(type solid)
			)
			(layer "B.Fab")
		)
		(pad "1" smd roundrect
			(at -0.48 0)
			(size 0.59 0.64)
			(layers "B.Cu" "B.Mask" "B.Paste")
			(roundrect_rratio 0.25)
			(net 1 "GND")
			(pintype "passive")
			(teardrops
				(best_length_ratio 0.2)
				(max_length 1)
				(best_width_ratio 0.9)
				(max_width 2)
				(curved_edges yes)
				(filter_ratio 0.9)
				(enabled yes)
				(allow_two_segments yes)
				(prefer_zone_connections yes)
			)
		)
		(pad "2" smd roundrect
			(at 0.48 0)
			(size 0.59 0.64)
			(layers "B.Cu" "B.Mask" "B.Paste")
			(roundrect_rratio 0.25)
			(net 2 "+3V3")
			(pintype "passive")
			(teardrops
				(best_length_ratio 0.2)
				(max_length 1)
				(best_width_ratio 0.9)
				(max_width 2)
				(curved_edges yes)
				(filter_ratio 0.9)
				(enabled yes)
				(allow_two_segments yes)
				(prefer_zone_connections yes)
			)
		)
	)
	(footprint "antmicro-footprints:C_0402_1005Metric"
		(layer "B.Cu")
		(at 150.45 136.36 -90)
		(descr "Capacitor SMD 0402")
		(tags "capacitor SMD 0402")
		(property "Reference" "C159"
			(at -1.15 0.5 270)
			(layer "B.SilkS")
			(effects
				(font
					(size 0.7 0.7)
					(thickness 0.15)
				)
				(justify left bottom mirror)
			)
		)
		(property "Value" "C_100n_0402"
			(at -1.022927 -2.155213 90)
			(layer "B.Fab")
			(effects
				(font
					(size 0.7 0.7)
					(thickness 0.15)
				)
				(justify left bottom mirror)
			)
		)
		(property "Datasheet" "https://www.murata.com/products/productdetail?partno=GRM155R61H104KE14%23"
			(at 0 0 270)
			(layer "F.Fab")
			(hide yes)
			(effects
				(font
					(size 1.27 1.27)
					(thickness 0.15)
				)
			)
		)
		(property "Author" "Antmicro"
			(at 14.09 286.81 0)
			(layer "B.Fab")
			(hide yes)
			(effects
				(font
					(size 1 1)
					(thickness 0.15)
				)
				(justify mirror)
			)
		)
		(property "Dielectric" "X5R"
			(at 14.09 286.81 0)
			(layer "B.Fab")
			(hide yes)
			(effects
				(font
					(size 1 1)
					(thickness 0.15)
				)
				(justify mirror)
			)
		)
		(property "License" "Apache-2.0"
			(at 14.09 286.81 0)
			(layer "B.Fab")
			(hide yes)
			(effects
				(font
					(size 1 1)
					(thickness 0.15)
				)
				(justify mirror)
			)
		)
		(property "MPN" "GRM155R61H104KE14D"
			(at 14.09 286.81 0)
			(layer "B.Fab")
			(hide yes)
			(effects
				(font
					(size 1 1)
					(thickness 0.15)
				)
				(justify mirror)
			)
		)
		(property "Manufacturer" "Murata"
			(at 14.09 286.81 0)
			(layer "B.Fab")
			(hide yes)
			(effects
				(font
					(size 1 1)
					(thickness 0.15)
				)
				(justify mirror)
			)
		)
		(property "Public" "False"
			(at 14.09 286.81 0)
			(layer "B.Fab")
			(hide yes)
			(effects
				(font
					(size 1 1)
					(thickness 0.15)
				)
				(justify mirror)
			)
		)
		(property "Val" "100n"
			(at 14.09 286.81 0)
			(layer "B.Fab")
			(hide yes)
			(effects
				(font
					(size 1 1)
					(thickness 0.15)
				)
				(justify mirror)
			)
		)
		(property "Voltage" "50V"
			(at 14.09 286.81 0)
			(layer "B.Fab")
			(hide yes)
			(effects
				(font
					(size 1 1)
					(thickness 0.15)
				)
				(justify mirror)
			)
		)
		(sheetname "KR to SFI #1")
		(sheetfile "kr_sfi.kicad_sch")
		(attr smd)
		(fp_rect
			(start -0.925 0.47)
			(end 0.925 -0.47)
			(stroke
				(width 0.05)
				(type default)
			)
			(fill no)
			(layer "B.CrtYd")
		)
		(fp_line
			(start -0.494 0.25)
			(end -0.494 -0.248)
			(stroke
				(width 0.15)
				(type solid)
			)
			(layer "B.Fab")
		)
		(fp_line
			(start 0.504 0.25)
			(end -0.494 0.25)
			(stroke
				(width 0.15)
				(type solid)
			)
			(layer "B.Fab")
		)
		(fp_line
			(start -0.494 -0.248)
			(end 0.504 -0.248)
			(stroke
				(width 0.15)
				(type solid)
			)
			(layer "B.Fab")
		)
		(fp_line
			(start 0.504 -0.248)
			(end 0.504 0.25)
			(stroke
				(width 0.15)
				(type solid)
			)
			(layer "B.Fab")
		)
		(pad "1" smd roundrect
			(at -0.48 0 270)
			(size 0.59 0.64)
			(layers "B.Cu" "B.Mask" "B.Paste")
			(roundrect_rratio 0.25)
			(net 1 "GND")
			(pintype "passive")
			(teardrops
				(best_length_ratio 0.2)
				(max_length 1)
				(best_width_ratio 0.9)
				(max_width 2)
				(curved_edges yes)
				(filter_ratio 0.9)
				(enabled yes)
				(allow_two_segments yes)
				(prefer_zone_connections yes)
			)
		)
		(pad "2" smd roundrect
			(at 0.48 0 270)
			(size 0.59 0.64)
			(layers "B.Cu" "B.Mask" "B.Paste")
			(roundrect_rratio 0.25)
			(net 74 "+1V0")
			(pintype "passive")
			(teardrops
				(best_length_ratio 0.2)
				(max_length 1)
				(best_width_ratio 0.9)
				(max_width 2)
				(curved_edges yes)
				(filter_ratio 0.9)
				(enabled yes)
				(allow_two_segments yes)
				(prefer_zone_connections yes)
			)
		)
	)
	(footprint "antmicro-footprints:C_0402_1005Metric"
		(layer "B.Cu")
		(at 249.725 131.51)
		(descr "Capacitor SMD 0402")
		(tags "capacitor SMD 0402")
		(property "Reference" "C99"
			(at -1.065 1.34 0)
			(layer "B.SilkS")
			(effects
				(font
					(size 0.7 0.7)
					(thickness 0.15)
				)
				(justify right bottom mirror)
			)
		)
		(property "Value" "C_100n_0402"
			(at -1.022927 -2.155213 0)
			(layer "B.Fab")
			(effects
				(font
					(size 0.7 0.7)
					(thickness 0.15)
				)
				(justify right bottom mirror)
			)
		)
		(property "Datasheet" "https://www.murata.com/products/productdetail?partno=GRM155R61H104KE14%23"
			(at 0 0 0)
			(layer "F.Fab")
			(hide yes)
			(effects
				(font
					(size 1.27 1.27)
					(thickness 0.15)
				)
			)
		)
		(property "Author" "Antmicro"
			(at 0 0 0)
			(layer "B.Fab")
			(hide yes)
			(effects
				(font
					(size 1 1)
					(thickness 0.15)
				)
				(justify mirror)
			)
		)
		(property "Dielectric" "X5R"
			(at 0 0 0)
			(layer "B.Fab")
			(hide yes)
			(effects
				(font
					(size 1 1)
					(thickness 0.15)
				)
				(justify mirror)
			)
		)
		(property "License" "Apache-2.0"
			(at 0 0 0)
			(layer "B.Fab")
			(hide yes)
			(effects
				(font
					(size 1 1)
					(thickness 0.15)
				)
				(justify mirror)
			)
		)
		(property "MPN" "GRM155R61H104KE14D"
			(at 0 0 0)
			(layer "B.Fab")
			(hide yes)
			(effects
				(font
					(size 1 1)
					(thickness 0.15)
				)
				(justify mirror)
			)
		)
		(property "Manufacturer" "Murata"
			(at 0 0 0)
			(layer "B.Fab")
			(hide yes)
			(effects
				(font
					(size 1 1)
					(thickness 0.15)
				)
				(justify mirror)
			)
		)
		(property "Public" "False"
			(at 0 0 0)
			(layer "B.Fab")
			(hide yes)
			(effects
				(font
					(size 1 1)
					(thickness 0.15)
				)
				(justify mirror)
			)
		)
		(property "Val" "100n"
			(at 0 0 0)
			(layer "B.Fab")
			(hide yes)
			(effects
				(font
					(size 1 1)
					(thickness 0.15)
				)
				(justify mirror)
			)
		)
		(property "Voltage" "50V"
			(at 0 0 0)
			(layer "B.Fab")
			(hide yes)
			(effects
				(font
					(size 1 1)
					(thickness 0.15)
				)
				(justify mirror)
			)
		)
		(sheetname "Com Express 7 MGMT")
		(sheetfile "com_express_7_mgmt.kicad_sch")
		(attr smd)
		(fp_rect
			(start -0.925 0.47)
			(end 0.925 -0.47)
			(stroke
				(width 0.05)
				(type default)
			)
			(fill no)
			(layer "B.CrtYd")
		)
		(fp_line
			(start -0.494 -0.248)
			(end 0.504 -0.248)
			(stroke
				(width 0.15)
				(type solid)
			)
			(layer "B.Fab")
		)
		(fp_line
			(start -0.494 0.25)
			(end -0.494 -0.248)
			(stroke
				(width 0.15)
				(type solid)
			)
			(layer "B.Fab")
		)
		(fp_line
			(start 0.504 -0.248)
			(end 0.504 0.25)
			(stroke
				(width 0.15)
				(type solid)
			)
			(layer "B.Fab")
		)
		(fp_line
			(start 0.504 0.25)
			(end -0.494 0.25)
			(stroke
				(width 0.15)
				(type solid)
			)
			(layer "B.Fab")
		)
		(pad "1" smd roundrect
			(at -0.48 0)
			(size 0.59 0.64)
			(layers "B.Cu" "B.Mask" "B.Paste")
			(roundrect_rratio 0.25)
			(net 1 "GND")
			(pintype "passive")
			(teardrops
				(best_length_ratio 0.2)
				(max_length 1)
				(best_width_ratio 0.9)
				(max_width 2)
				(curved_edges yes)
				(filter_ratio 0.9)
				(enabled yes)
				(allow_two_segments yes)
				(prefer_zone_connections yes)
			)
		)
		(pad "2" smd roundrect
			(at 0.48 0)
			(size 0.59 0.64)
			(layers "B.Cu" "B.Mask" "B.Paste")
			(roundrect_rratio 0.25)
			(net 73 "+3V3_AON")
			(pintype "passive")
			(teardrops
				(best_length_ratio 0.2)
				(max_length 1)
				(best_width_ratio 0.9)
				(max_width 2)
				(curved_edges yes)
				(filter_ratio 0.9)
				(enabled yes)
				(allow_two_segments yes)
				(prefer_zone_connections yes)
			)
		)
	)
	(footprint "antmicro-footprints:USON-10_2.5x1mm_P0.5mm"
		(layer "B.Cu")
		(at 123.4 104.3)
		(descr "USON-10 2.5x1mm_ Pitch 0.5mm")
		(tags "USON-10 2.5x1mm Pitch 0.5mm")
		(property "Reference" "U2"
			(at -0.85 0.81 90)
			(layer "B.SilkS")
			(effects
				(font
					(size 0.7 0.7)
					(thickness 0.15)
				)
				(justify right bottom mirror)
			)
		)
		(property "Value" "ESD204DQAR"
			(at 0.018 -2.499 0)
			(layer "B.Fab")
			(effects
				(font
					(size 0.7 0.7)
					(thickness 0.15)
				)
				(justify right bottom mirror)
			)
		)
		(property "Datasheet" "https://www.ti.com/lit/ds/symlink/esd204.pdf?ts=1706004844383&ref_url=https%253A%252F%252Fwww.ti.com%252Finterface%252Fdiodes%252Fesd-protection-diodes%252Fproducts.html"
			(at 0 0 0)
			(layer "F.Fab")
			(hide yes)
			(effects
				(font
					(size 1.27 1.27)
					(thickness 0.15)
				)
			)
		)
		(property "Author" "Antmicro"
			(at 0 0 0)
			(layer "B.Fab")
			(hide yes)
			(effects
				(font
					(size 1 1)
					(thickness 0.15)
				)
				(justify mirror)
			)
		)
		(property "License" "Apache-2.0"
			(at 0 0 0)
			(layer "B.Fab")
			(hide yes)
			(effects
				(font
					(size 1 1)
					(thickness 0.15)
				)
				(justify mirror)
			)
		)
		(property "MPN" "ESD204DQAR"
			(at 0 0 0)
			(layer "B.Fab")
			(hide yes)
			(effects
				(font
					(size 1 1)
					(thickness 0.15)
				)
				(justify mirror)
			)
		)
		(property "Manufacturer" "Texas Instruments"
			(at 0 0 0)
			(layer "B.Fab")
			(hide yes)
			(effects
				(font
					(size 1 1)
					(thickness 0.15)
				)
				(justify mirror)
			)
		)
		(sheetname "2xUSB3.0+RJ45")
		(sheetfile "usb3+rj45.kicad_sch")
		(attr smd)
		(fp_line
			(start -0.5 -1.398)
			(end 0.498 -1.398)
			(stroke
				(width 0.15)
				(type solid)
			)
			(layer "B.SilkS")
		)
		(fp_line
			(start -0.5 1.401)
			(end 0.498 1.401)
			(stroke
				(width 0.15)
				(type solid)
			)
			(layer "B.SilkS")
		)
		(fp_circle
			(center -0.68 1.27)
			(end -0.63 1.27)
			(stroke
				(width 0.15)
				(type solid)
			)
			(fill yes)
			(layer "B.SilkS")
		)
		(fp_rect
			(start -0.8 1.5)
			(end 0.8 -1.499)
			(stroke
				(width 0.05)
				(type solid)
			)
			(fill no)
			(layer "B.CrtYd")
		)
		(fp_line
			(start -0.5 -1.249)
			(end -0.5 1)
			(stroke
				(width 0.15)
				(type solid)
			)
			(layer "B.Fab")
		)
		(fp_line
			(start -0.5 1)
			(end -0.25 1.25)
			(stroke
				(width 0.15)
				(type solid)
			)
			(layer "B.Fab")
		)
		(fp_line
			(start -0.25 1.25)
			(end 0.498 1.25)
			(stroke
				(width 0.15)
				(type solid)
			)
			(layer "B.Fab")
		)
		(fp_line
			(start 0.498 -1.249)
			(end -0.5 -1.249)
			(stroke
				(width 0.15)
				(type solid)
			)
			(layer "B.Fab")
		)
		(fp_line
			(start 0.498 -1.249)
			(end 0.498 1.25)
			(stroke
				(width 0.15)
				(type solid)
			)
			(layer "B.Fab")
		)
		(pad "1" smd roundrect
			(at -0.387 1 90)
			(size 0.25 0.55)
			(layers "B.Cu" "B.Mask" "B.Paste")
			(roundrect_rratio 0.25)
			(net 160 "/2xUSB3.0+RJ45/USBSS_2.RX-")
			(pintype "passive")
			(teardrops
				(best_length_ratio 0.2)
				(max_length 1)
				(best_width_ratio 0.9)
				(max_width 2)
				(curved_edges yes)
				(filter_ratio 0.9)
				(enabled yes)
				(allow_two_segments yes)
				(prefer_zone_connections yes)
			)
		)
		(pad "2" smd roundrect
			(at -0.387 0.5 90)
			(size 0.25 0.55)
			(layers "B.Cu" "B.Mask" "B.Paste")
			(roundrect_rratio 0.25)
			(net 161 "/2xUSB3.0+RJ45/USBSS_2.RX+")
			(pintype "passive")
			(teardrops
				(best_length_ratio 0.2)
				(max_length 1)
				(best_width_ratio 0.9)
				(max_width 2)
				(curved_edges yes)
				(filter_ratio 0.9)
				(enabled yes)
				(allow_two_segments yes)
				(prefer_zone_connections yes)
			)
		)
		(pad "3" smd roundrect
			(at -0.387 0 90)
			(size 0.4 0.55)
			(layers "B.Cu" "B.Mask" "B.Paste")
			(roundrect_rratio 0.25)
			(net 1 "GND")
			(pintype "power_in")
			(teardrops
				(best_length_ratio 0.2)
				(max_length 1)
				(best_width_ratio 0.9)
				(max_width 2)
				(curved_edges yes)
				(filter_ratio 0.9)
				(enabled yes)
				(allow_two_segments yes)
				(prefer_zone_connections yes)
			)
		)
		(pad "4" smd roundrect
			(at -0.387 -0.498 90)
			(size 0.25 0.55)
			(layers "B.Cu" "B.Mask" "B.Paste")
			(roundrect_rratio 0.25)
			(net 49 "/2xUSB3.0+RJ45/USBSS_2.TX-")
			(pintype "passive")
			(teardrops
				(best_length_ratio 0.2)
				(max_length 1)
				(best_width_ratio 0.9)
				(max_width 2)
				(curved_edges yes)
				(filter_ratio 0.9)
				(enabled yes)
				(allow_two_segments yes)
				(prefer_zone_connections yes)
			)
		)
		(pad "5" smd roundrect
			(at -0.387 -0.998 90)
			(size 0.25 0.55)
			(layers "B.Cu" "B.Mask" "B.Paste")
			(roundrect_rratio 0.25)
			(net 45 "/2xUSB3.0+RJ45/USBSS_2.TX+")
			(pintype "passive")
			(teardrops
				(best_length_ratio 0.2)
				(max_length 1)
				(best_width_ratio 0.9)
				(max_width 2)
				(curved_edges yes)
				(filter_ratio 0.9)
				(enabled yes)
				(allow_two_segments yes)
				(prefer_zone_connections yes)
			)
		)
		(pad "6" smd roundrect
			(at 0.385 -0.998 90)
			(size 0.25 0.55)
			(layers "B.Cu" "B.Mask" "B.Paste")
			(roundrect_rratio 0.25)
			(net 45 "/2xUSB3.0+RJ45/USBSS_2.TX+")
			(pintype "passive")
			(teardrops
				(best_length_ratio 0.2)
				(max_length 1)
				(best_width_ratio 0.9)
				(max_width 2)
				(curved_edges yes)
				(filter_ratio 0.9)
				(enabled yes)
				(allow_two_segments yes)
				(prefer_zone_connections yes)
			)
		)
		(pad "7" smd roundrect
			(at 0.385 -0.498 90)
			(size 0.25 0.55)
			(layers "B.Cu" "B.Mask" "B.Paste")
			(roundrect_rratio 0.25)
			(net 49 "/2xUSB3.0+RJ45/USBSS_2.TX-")
			(pintype "passive")
			(teardrops
				(best_length_ratio 0.2)
				(max_length 1)
				(best_width_ratio 0.9)
				(max_width 2)
				(curved_edges yes)
				(filter_ratio 0.9)
				(enabled yes)
				(allow_two_segments yes)
				(prefer_zone_connections yes)
			)
		)
		(pad "8" smd roundrect
			(at 0.385 0 90)
			(size 0.4 0.55)
			(layers "B.Cu" "B.Mask" "B.Paste")
			(roundrect_rratio 0.25)
			(net 1 "GND")
			(pintype "passive")
			(teardrops
				(best_length_ratio 0.2)
				(max_length 1)
				(best_width_ratio 0.9)
				(max_width 2)
				(curved_edges yes)
				(filter_ratio 0.9)
				(enabled yes)
				(allow_two_segments yes)
				(prefer_zone_connections yes)
			)
		)
		(pad "9" smd roundrect
			(at 0.385 0.5 90)
			(size 0.25 0.55)
			(layers "B.Cu" "B.Mask" "B.Paste")
			(roundrect_rratio 0.25)
			(net 161 "/2xUSB3.0+RJ45/USBSS_2.RX+")
			(pintype "passive")
			(teardrops
				(best_length_ratio 0.2)
				(max_length 1)
				(best_width_ratio 0.9)
				(max_width 2)
				(curved_edges yes)
				(filter_ratio 0.9)
				(enabled yes)
				(allow_two_segments yes)
				(prefer_zone_connections yes)
			)
		)
		(pad "10" smd roundrect
			(at 0.385 1 90)
			(size 0.25 0.55)
			(layers "B.Cu" "B.Mask" "B.Paste")
			(roundrect_rratio 0.25)
			(net 160 "/2xUSB3.0+RJ45/USBSS_2.RX-")
			(pintype "passive")
			(teardrops
				(best_length_ratio 0.2)
				(max_length 1)
				(best_width_ratio 0.9)
				(max_width 2)
				(curved_edges yes)
				(filter_ratio 0.9)
				(enabled yes)
				(allow_two_segments yes)
				(prefer_zone_connections yes)
			)
		)
	)
	(footprint "antmicro-footprints:C_0402_1005Metric"
		(layer "B.Cu")
		(at 148.45 142.36 90)
		(descr "Capacitor SMD 0402")
		(tags "capacitor SMD 0402")
		(property "Reference" "C162"
			(at -1.35 -0.5 90)
			(layer "B.SilkS")
			(effects
				(font
					(size 0.7 0.7)
					(thickness 0.15)
				)
				(justify right bottom mirror)
			)
		)
		(property "Value" "C_100n_0402"
			(at -1.022927 -2.155213 90)
			(layer "B.Fab")
			(effects
				(font
					(size 0.7 0.7)
					(thickness 0.15)
				)
				(justify right bottom mirror)
			)
		)
		(property "Datasheet" "https://www.murata.com/products/productdetail?partno=GRM155R61H104KE14%23"
			(at 0 0 90)
			(layer "F.Fab")
			(hide yes)
			(effects
				(font
					(size 1.27 1.27)
					(thickness 0.15)
				)
			)
		)
		(property "Author" "Antmicro"
			(at 290.81 -6.09 0)
			(layer "B.Fab")
			(hide yes)
			(effects
				(font
					(size 1 1)
					(thickness 0.15)
				)
				(justify mirror)
			)
		)
		(property "Dielectric" "X5R"
			(at 290.81 -6.09 0)
			(layer "B.Fab")
			(hide yes)
			(effects
				(font
					(size 1 1)
					(thickness 0.15)
				)
				(justify mirror)
			)
		)
		(property "License" "Apache-2.0"
			(at 290.81 -6.09 0)
			(layer "B.Fab")
			(hide yes)
			(effects
				(font
					(size 1 1)
					(thickness 0.15)
				)
				(justify mirror)
			)
		)
		(property "MPN" "GRM155R61H104KE14D"
			(at 290.81 -6.09 0)
			(layer "B.Fab")
			(hide yes)
			(effects
				(font
					(size 1 1)
					(thickness 0.15)
				)
				(justify mirror)
			)
		)
		(property "Manufacturer" "Murata"
			(at 290.81 -6.09 0)
			(layer "B.Fab")
			(hide yes)
			(effects
				(font
					(size 1 1)
					(thickness 0.15)
				)
				(justify mirror)
			)
		)
		(property "Public" "False"
			(at 290.81 -6.09 0)
			(layer "B.Fab")
			(hide yes)
			(effects
				(font
					(size 1 1)
					(thickness 0.15)
				)
				(justify mirror)
			)
		)
		(property "Val" "100n"
			(at 290.81 -6.09 0)
			(layer "B.Fab")
			(hide yes)
			(effects
				(font
					(size 1 1)
					(thickness 0.15)
				)
				(justify mirror)
			)
		)
		(property "Voltage" "50V"
			(at 290.81 -6.09 0)
			(layer "B.Fab")
			(hide yes)
			(effects
				(font
					(size 1 1)
					(thickness 0.15)
				)
				(justify mirror)
			)
		)
		(sheetname "KR to SFI #1")
		(sheetfile "kr_sfi.kicad_sch")
		(attr smd)
		(fp_rect
			(start -0.925 0.47)
			(end 0.925 -0.47)
			(stroke
				(width 0.05)
				(type default)
			)
			(fill no)
			(layer "B.CrtYd")
		)
		(fp_line
			(start 0.504 -0.248)
			(end 0.504 0.25)
			(stroke
				(width 0.15)
				(type solid)
			)
			(layer "B.Fab")
		)
		(fp_line
			(start -0.494 -0.248)
			(end 0.504 -0.248)
			(stroke
				(width 0.15)
				(type solid)
			)
			(layer "B.Fab")
		)
		(fp_line
			(start 0.504 0.25)
			(end -0.494 0.25)
			(stroke
				(width 0.15)
				(type solid)
			)
			(layer "B.Fab")
		)
		(fp_line
			(start -0.494 0.25)
			(end -0.494 -0.248)
			(stroke
				(width 0.15)
				(type solid)
			)
			(layer "B.Fab")
		)
		(pad "1" smd roundrect
			(at -0.48 0 90)
			(size 0.59 0.64)
			(layers "B.Cu" "B.Mask" "B.Paste")
			(roundrect_rratio 0.25)
			(net 1 "GND")
			(pintype "passive")
			(teardrops
				(best_length_ratio 0.2)
				(max_length 1)
				(best_width_ratio 0.9)
				(max_width 2)
				(curved_edges yes)
				(filter_ratio 0.9)
				(enabled yes)
				(allow_two_segments yes)
				(prefer_zone_connections yes)
			)
		)
		(pad "2" smd roundrect
			(at 0.48 0 90)
			(size 0.59 0.64)
			(layers "B.Cu" "B.Mask" "B.Paste")
			(roundrect_rratio 0.25)
			(net 78 "+1V8")
			(pintype "passive")
			(teardrops
				(best_length_ratio 0.2)
				(max_length 1)
				(best_width_ratio 0.9)
				(max_width 2)
				(curved_edges yes)
				(filter_ratio 0.9)
				(enabled yes)
				(allow_two_segments yes)
				(prefer_zone_connections yes)
			)
		)
	)
	(footprint "antmicro-footprints:C_0402_1005Metric"
		(layer "B.Cu")
		(at 133.29 136.36 -90)
		(descr "Capacitor SMD 0402")
		(tags "capacitor SMD 0402")
		(property "Reference" "C201"
			(at -1.2 -1.36 90)
			(layer "B.SilkS")
			(effects
				(font
					(size 0.7 0.7)
					(thickness 0.15)
				)
				(justify left bottom mirror)
			)
		)
		(property "Value" "C_100n_0402"
			(at -1.022927 -2.155213 90)
			(layer "B.Fab")
			(effects
				(font
					(size 0.7 0.7)
					(thickness 0.15)
				)
				(justify left bottom mirror)
			)
		)
		(property "Datasheet" "https://www.murata.com/products/productdetail?partno=GRM155R61H104KE14%23"
			(at 0 0 270)
			(layer "F.Fab")
			(hide yes)
			(effects
				(font
					(size 1.27 1.27)
					(thickness 0.15)
				)
			)
		)
		(property "Author" "Antmicro"
			(at -3.07 269.65 0)
			(layer "B.Fab")
			(hide yes)
			(effects
				(font
					(size 1 1)
					(thickness 0.15)
				)
				(justify mirror)
			)
		)
		(property "Dielectric" "X5R"
			(at -3.07 269.65 0)
			(layer "B.Fab")
			(hide yes)
			(effects
				(font
					(size 1 1)
					(thickness 0.15)
				)
				(justify mirror)
			)
		)
		(property "License" "Apache-2.0"
			(at -3.07 269.65 0)
			(layer "B.Fab")
			(hide yes)
			(effects
				(font
					(size 1 1)
					(thickness 0.15)
				)
				(justify mirror)
			)
		)
		(property "MPN" "GRM155R61H104KE14D"
			(at -3.07 269.65 0)
			(layer "B.Fab")
			(hide yes)
			(effects
				(font
					(size 1 1)
					(thickness 0.15)
				)
				(justify mirror)
			)
		)
		(property "Manufacturer" "Murata"
			(at -3.07 269.65 0)
			(layer "B.Fab")
			(hide yes)
			(effects
				(font
					(size 1 1)
					(thickness 0.15)
				)
				(justify mirror)
			)
		)
		(property "Public" "False"
			(at -3.07 269.65 0)
			(layer "B.Fab")
			(hide yes)
			(effects
				(font
					(size 1 1)
					(thickness 0.15)
				)
				(justify mirror)
			)
		)
		(property "Val" "100n"
			(at -3.07 269.65 0)
			(layer "B.Fab")
			(hide yes)
			(effects
				(font
					(size 1 1)
					(thickness 0.15)
				)
				(justify mirror)
			)
		)
		(property "Voltage" "50V"
			(at -3.07 269.65 0)
			(layer "B.Fab")
			(hide yes)
			(effects
				(font
					(size 1 1)
					(thickness 0.15)
				)
				(justify mirror)
			)
		)
		(sheetname "KR to SFI #2")
		(sheetfile "kr_sfi.kicad_sch")
		(attr smd)
		(fp_rect
			(start -0.925 0.47)
			(end 0.925 -0.47)
			(stroke
				(width 0.05)
				(type default)
			)
			(fill no)
			(layer "B.CrtYd")
		)
		(fp_line
			(start -0.494 0.25)
			(end -0.494 -0.248)
			(stroke
				(width 0.15)
				(type solid)
			)
			(layer "B.Fab")
		)
		(fp_line
			(start 0.504 0.25)
			(end -0.494 0.25)
			(stroke
				(width 0.15)
				(type solid)
			)
			(layer "B.Fab")
		)
		(fp_line
			(start -0.494 -0.248)
			(end 0.504 -0.248)
			(stroke
				(width 0.15)
				(type solid)
			)
			(layer "B.Fab")
		)
		(fp_line
			(start 0.504 -0.248)
			(end 0.504 0.25)
			(stroke
				(width 0.15)
				(type solid)
			)
			(layer "B.Fab")
		)
		(pad "1" smd roundrect
			(at -0.48 0 270)
			(size 0.59 0.64)
			(layers "B.Cu" "B.Mask" "B.Paste")
			(roundrect_rratio 0.25)
			(net 1 "GND")
			(pintype "passive")
			(teardrops
				(best_length_ratio 0.2)
				(max_length 1)
				(best_width_ratio 0.9)
				(max_width 2)
				(curved_edges yes)
				(filter_ratio 0.9)
				(enabled yes)
				(allow_two_segments yes)
				(prefer_zone_connections yes)
			)
		)
		(pad "2" smd roundrect
			(at 0.48 0 270)
			(size 0.59 0.64)
			(layers "B.Cu" "B.Mask" "B.Paste")
			(roundrect_rratio 0.25)
			(net 74 "+1V0")
			(pintype "passive")
			(teardrops
				(best_length_ratio 0.2)
				(max_length 1)
				(best_width_ratio 0.9)
				(max_width 2)
				(curved_edges yes)
				(filter_ratio 0.9)
				(enabled yes)
				(allow_two_segments yes)
				(prefer_zone_connections yes)
			)
		)
	)
	(footprint "antmicro-footprints:TP_SMD_0.75mm"
		(layer "B.Cu")
		(at 157.7 162.46 -90)
		(property "Reference" "TP1"
			(at -2.437 -0.449 90)
			(layer "B.SilkS")
			(effects
				(font
					(size 0.7 0.7)
					(thickness 0.15)
				)
				(justify left bottom mirror)
			)
		)
		(property "Value" "TP_0.75mm_SMD"
			(at 0 -1.2 90)
			(layer "B.Fab")
			(effects
				(font
					(size 0.7 0.7)
					(thickness 0.15)
				)
				(justify left bottom mirror)
			)
		)
		(property "Author" "Antmicro"
			(at -4.76 320.16 0)
			(layer "B.Fab")
			(hide yes)
			(effects
				(font
					(size 1 1)
					(thickness 0.15)
				)
				(justify mirror)
			)
		)
		(property "License" "Apache-2.0"
			(at -4.76 320.16 0)
			(layer "B.Fab")
			(hide yes)
			(effects
				(font
					(size 1 1)
					(thickness 0.15)
				)
				(justify mirror)
			)
		)
		(property "MPN" ""
			(at -4.76 320.16 0)
			(layer "B.Fab")
			(hide yes)
			(effects
				(font
					(size 1 1)
					(thickness 0.15)
				)
				(justify mirror)
			)
		)
		(property "Manufacturer" ""
			(at -4.76 320.16 0)
			(layer "B.Fab")
			(hide yes)
			(effects
				(font
					(size 1 1)
					(thickness 0.15)
				)
				(justify mirror)
			)
		)
		(property "Public" "False"
			(at -4.76 320.16 0)
			(layer "B.Fab")
			(hide yes)
			(effects
				(font
					(size 1 1)
					(thickness 0.15)
				)
				(justify mirror)
			)
		)
		(sheetname "2xSFP+")
		(sheetfile "2xSFP+.kicad_sch")
		(attr exclude_from_pos_files exclude_from_bom)
		(fp_circle
			(center 0 0)
			(end 0.475 0)
			(stroke
				(width 0.05)
				(type default)
			)
			(fill no)
			(layer "B.CrtYd")
		)
		(pad "1" smd circle
			(at 0 0 270)
			(size 0.75 0.75)
			(layers "B.Cu" "B.Mask")
			(net 697 "Net-(U5-IO0_6)")
			(pinfunction "1")
			(pintype "passive")
			(teardrops
				(best_length_ratio 0.4)
				(max_length 1)
				(best_width_ratio 0.9)
				(max_width 2)
				(curved_edges yes)
				(filter_ratio 0.9)
				(enabled yes)
				(allow_two_segments yes)
				(prefer_zone_connections yes)
			)
		)
	)
	(footprint "antmicro-footprints:TP_SMD_0.75mm"
		(layer "B.Cu")
		(at 176.25 165.05)
		(property "Reference" "TP23"
			(at 1 -0.3 180)
			(layer "B.SilkS")
			(effects
				(font
					(size 0.7 0.7)
					(thickness 0.15)
				)
				(justify right top mirror)
			)
		)
		(property "Value" "TP_0.75mm_SMD"
			(at 3.225 -53.865 0)
			(layer "B.Fab")
			(hide yes)
			(effects
				(font
					(size 0.7 0.7)
					(thickness 0.15)
				)
				(justify right top mirror)
			)
		)
		(property "Author" "Antmicro"
			(at 456 306.12 0)
			(layer "B.Fab")
			(hide yes)
			(effects
				(font
					(size 1 1)
					(thickness 0.15)
				)
				(justify mirror)
			)
		)
		(property "License" "Apache-2.0"
			(at 456 306.12 0)
			(layer "B.Fab")
			(hide yes)
			(effects
				(font
					(size 1 1)
					(thickness 0.15)
				)
				(justify mirror)
			)
		)
		(property "MPN" ""
			(at 456 306.12 0)
			(layer "B.Fab")
			(hide yes)
			(effects
				(font
					(size 1 1)
					(thickness 0.15)
				)
				(justify mirror)
			)
		)
		(property "Manufacturer" ""
			(at 456 306.12 0)
			(layer "B.Fab")
			(hide yes)
			(effects
				(font
					(size 1 1)
					(thickness 0.15)
				)
				(justify mirror)
			)
		)
		(property "Public" "False"
			(at 456 306.12 0)
			(layer "B.Fab")
			(hide yes)
			(effects
				(font
					(size 1 1)
					(thickness 0.15)
				)
				(justify mirror)
			)
		)
		(sheetname "Com Express 7 MGMT")
		(sheetfile "com_express_7_mgmt.kicad_sch")
		(attr exclude_from_pos_files exclude_from_bom)
		(fp_circle
			(center 0 0)
			(end 0.475 0)
			(stroke
				(width 0.05)
				(type default)
			)
			(fill no)
			(layer "B.CrtYd")
		)
		(pad "1" smd circle
			(at 0 0)
			(size 0.75 0.75)
			(layers "B.Cu" "B.Mask")
			(net 351 "Net-(J12D-LPC_AD2{slash}ESPI_IO_2)")
			(pinfunction "1")
			(pintype "passive")
			(teardrops
				(best_length_ratio 0.4)
				(max_length 1)
				(best_width_ratio 0.9)
				(max_width 2)
				(curved_edges yes)
				(filter_ratio 0.9)
				(enabled yes)
				(allow_two_segments yes)
				(prefer_zone_connections yes)
			)
		)
	)
	(footprint "antmicro-footprints:R_0402_1005Metric"
		(layer "B.Cu")
		(at 123.4 95.86 180)
		(descr "Resistor SMD 0402")
		(tags "resistor SMD 0402")
		(property "Reference" "R331"
			(at -3.7 -0.41 0)
			(layer "B.SilkS")
			(effects
				(font
					(size 0.7 0.7)
					(thickness 0.15)
				)
				(justify left bottom mirror)
			)
		)
		(property "Value" "R_470R_0402"
			(at -1.011843 -1.772047 0)
			(layer "B.Fab")
			(effects
				(font
					(size 0.7 0.7)
					(thickness 0.15)
				)
				(justify left bottom mirror)
			)
		)
		(property "Datasheet" "https://www.bourns.com/docs/product-datasheets/cr.pdf"
			(at 0 0 0)
			(layer "B.Fab")
			(hide yes)
			(effects
				(font
					(size 1.27 1.27)
					(thickness 0.15)
				)
				(justify mirror)
			)
		)
		(property "MPN" "CR0402-FX-4700GLF"
			(at 0 0 0)
			(unlocked yes)
			(layer "B.Fab")
			(hide yes)
			(effects
				(font
					(size 1 1)
					(thickness 0.15)
				)
				(justify mirror)
			)
		)
		(property "Manufacturer" "Bourns"
			(at 0 0 0)
			(unlocked yes)
			(layer "B.Fab")
			(hide yes)
			(effects
				(font
					(size 1 1)
					(thickness 0.15)
				)
				(justify mirror)
			)
		)
		(property "License" "Apache-2.0"
			(at 0 0 0)
			(unlocked yes)
			(layer "B.Fab")
			(hide yes)
			(effects
				(font
					(size 1 1)
					(thickness 0.15)
				)
				(justify mirror)
			)
		)
		(property "Author" "Antmicro"
			(at 0 0 0)
			(unlocked yes)
			(layer "B.Fab")
			(hide yes)
			(effects
				(font
					(size 1 1)
					(thickness 0.15)
				)
				(justify mirror)
			)
		)
		(property "Val" "470R"
			(at 0 0 0)
			(unlocked yes)
			(layer "B.Fab")
			(hide yes)
			(effects
				(font
					(size 1 1)
					(thickness 0.15)
				)
				(justify mirror)
			)
		)
		(property "Tolerance" "1%"
			(at 0 0 0)
			(unlocked yes)
			(layer "B.Fab")
			(hide yes)
			(effects
				(font
					(size 1 1)
					(thickness 0.15)
				)
				(justify mirror)
			)
		)
		(property "Public" "False"
			(at 0 0 0)
			(unlocked yes)
			(layer "B.Fab")
			(hide yes)
			(effects
				(font
					(size 1 1)
					(thickness 0.15)
				)
				(justify mirror)
			)
		)
		(sheetname "2xUSB3.0+RJ45")
		(sheetfile "usb3+rj45.kicad_sch")
		(attr smd dnp)
		(fp_rect
			(start -0.925 0.47)
			(end 0.925 -0.47)
			(stroke
				(width 0.05)
				(type default)
			)
			(fill no)
			(layer "B.CrtYd")
		)
		(fp_rect
			(start -0.5 0.25)
			(end 0.5 -0.25)
			(stroke
				(width 0.15)
				(type solid)
			)
			(fill no)
			(layer "B.Fab")
		)
		(pad "1" smd roundrect
			(at -0.48 0 180)
			(size 0.59 0.64)
			(layers "B.Cu" "B.Mask" "B.Paste")
			(roundrect_rratio 0.25)
			(net 1 "GND")
			(pintype "passive")
			(teardrops
				(best_length_ratio 0.2)
				(max_length 1)
				(best_width_ratio 0.9)
				(max_width 2)
				(curved_edges yes)
				(filter_ratio 0.9)
				(enabled yes)
				(allow_two_segments yes)
				(prefer_zone_connections yes)
			)
		)
		(pad "2" smd roundrect
			(at 0.48 0 180)
			(size 0.59 0.64)
			(layers "B.Cu" "B.Mask" "B.Paste")
			(roundrect_rratio 0.25)
			(net 154 "Net-(J1A-LED_D1)")
			(pintype "passive")
			(teardrops
				(best_length_ratio 0.2)
				(max_length 1)
				(best_width_ratio 0.9)
				(max_width 2)
				(curved_edges yes)
				(filter_ratio 0.9)
				(enabled yes)
				(allow_two_segments yes)
				(prefer_zone_connections yes)
			)
		)
	)
	(footprint "antmicro-footprints:C_0402_1005Metric"
		(layer "B.Cu")
		(at 218.25 127.324)
		(descr "Capacitor SMD 0402")
		(tags "capacitor SMD 0402")
		(property "Reference" "C103"
			(at -1.4 -0.464 0)
			(layer "B.SilkS")
			(effects
				(font
					(size 0.7 0.7)
					(thickness 0.15)
				)
				(justify right bottom mirror)
			)
		)
		(property "Value" "C_100n_0402"
			(at -1.022927 -2.155213 0)
			(layer "B.Fab")
			(effects
				(font
					(size 0.7 0.7)
					(thickness 0.15)
				)
				(justify right bottom mirror)
			)
		)
		(property "Datasheet" "https://www.murata.com/products/productdetail?partno=GRM155R61H104KE14%23"
			(at 0 0 0)
			(layer "F.Fab")
			(hide yes)
			(effects
				(font
					(size 1.27 1.27)
					(thickness 0.15)
				)
			)
		)
		(property "Author" "Antmicro"
			(at 0 0 0)
			(layer "B.Fab")
			(hide yes)
			(effects
				(font
					(size 1 1)
					(thickness 0.15)
				)
				(justify mirror)
			)
		)
		(property "Dielectric" "X5R"
			(at 0 0 0)
			(layer "B.Fab")
			(hide yes)
			(effects
				(font
					(size 1 1)
					(thickness 0.15)
				)
				(justify mirror)
			)
		)
		(property "License" "Apache-2.0"
			(at 0 0 0)
			(layer "B.Fab")
			(hide yes)
			(effects
				(font
					(size 1 1)
					(thickness 0.15)
				)
				(justify mirror)
			)
		)
		(property "MPN" "GRM155R61H104KE14D"
			(at 0 0 0)
			(layer "B.Fab")
			(hide yes)
			(effects
				(font
					(size 1 1)
					(thickness 0.15)
				)
				(justify mirror)
			)
		)
		(property "Manufacturer" "Murata"
			(at 0 0 0)
			(layer "B.Fab")
			(hide yes)
			(effects
				(font
					(size 1 1)
					(thickness 0.15)
				)
				(justify mirror)
			)
		)
		(property "Public" "False"
			(at 0 0 0)
			(layer "B.Fab")
			(hide yes)
			(effects
				(font
					(size 1 1)
					(thickness 0.15)
				)
				(justify mirror)
			)
		)
		(property "Val" "100n"
			(at 0 0 0)
			(layer "B.Fab")
			(hide yes)
			(effects
				(font
					(size 1 1)
					(thickness 0.15)
				)
				(justify mirror)
			)
		)
		(property "Voltage" "50V"
			(at 0 0 0)
			(layer "B.Fab")
			(hide yes)
			(effects
				(font
					(size 1 1)
					(thickness 0.15)
				)
				(justify mirror)
			)
		)
		(sheetname "PCIe misc")
		(sheetfile "pcie_misc.kicad_sch")
		(attr smd)
		(fp_rect
			(start -0.925 0.47)
			(end 0.925 -0.47)
			(stroke
				(width 0.05)
				(type default)
			)
			(fill no)
			(layer "B.CrtYd")
		)
		(fp_line
			(start -0.494 -0.248)
			(end 0.504 -0.248)
			(stroke
				(width 0.15)
				(type solid)
			)
			(layer "B.Fab")
		)
		(fp_line
			(start -0.494 0.25)
			(end -0.494 -0.248)
			(stroke
				(width 0.15)
				(type solid)
			)
			(layer "B.Fab")
		)
		(fp_line
			(start 0.504 -0.248)
			(end 0.504 0.25)
			(stroke
				(width 0.15)
				(type solid)
			)
			(layer "B.Fab")
		)
		(fp_line
			(start 0.504 0.25)
			(end -0.494 0.25)
			(stroke
				(width 0.15)
				(type solid)
			)
			(layer "B.Fab")
		)
		(pad "1" smd roundrect
			(at -0.48 0)
			(size 0.59 0.64)
			(layers "B.Cu" "B.Mask" "B.Paste")
			(roundrect_rratio 0.25)
			(net 1 "GND")
			(pintype "passive")
			(teardrops
				(best_length_ratio 0.2)
				(max_length 1)
				(best_width_ratio 0.9)
				(max_width 2)
				(curved_edges yes)
				(filter_ratio 0.9)
				(enabled yes)
				(allow_two_segments yes)
				(prefer_zone_connections yes)
			)
		)
		(pad "2" smd roundrect
			(at 0.48 0)
			(size 0.59 0.64)
			(layers "B.Cu" "B.Mask" "B.Paste")
			(roundrect_rratio 0.25)
			(net 2 "+3V3")
			(pintype "passive")
			(teardrops
				(best_length_ratio 0.2)
				(max_length 1)
				(best_width_ratio 0.9)
				(max_width 2)
				(curved_edges yes)
				(filter_ratio 0.9)
				(enabled yes)
				(allow_two_segments yes)
				(prefer_zone_connections yes)
			)
		)
	)
	(footprint "antmicro-footprints:R_0402_1005Metric"
		(layer "B.Cu")
		(at 107.5 163.01 180)
		(descr "Resistor SMD 0402")
		(tags "resistor SMD 0402")
		(property "Reference" "R83"
			(at -3 -0.43 0)
			(layer "B.SilkS")
			(effects
				(font
					(size 0.7 0.7)
					(thickness 0.15)
				)
				(justify left bottom mirror)
			)
		)
		(property "Value" "R_0R_0402"
			(at -1.011843 -1.772047 0)
			(layer "B.Fab")
			(effects
				(font
					(size 0.7 0.7)
					(thickness 0.15)
				)
				(justify left bottom mirror)
			)
		)
		(property "Datasheet" "https://industrial.panasonic.com/cdbs/www-data/pdf/RDA0000/AOA0000C301.pdf"
			(at 0 0 180)
			(layer "F.Fab")
			(hide yes)
			(effects
				(font
					(size 1.27 1.27)
					(thickness 0.15)
				)
			)
		)
		(property "Author" "Antmicro"
			(at 215 326.02 0)
			(layer "B.Fab")
			(hide yes)
			(effects
				(font
					(size 1 1)
					(thickness 0.15)
				)
				(justify mirror)
			)
		)
		(property "Current" "1A"
			(at 215 326.02 0)
			(layer "B.Fab")
			(hide yes)
			(effects
				(font
					(size 1 1)
					(thickness 0.15)
				)
				(justify mirror)
			)
		)
		(property "License" "Apache-2.0"
			(at 215 326.02 0)
			(layer "B.Fab")
			(hide yes)
			(effects
				(font
					(size 1 1)
					(thickness 0.15)
				)
				(justify mirror)
			)
		)
		(property "MPN" "ERJ2GE0R00X"
			(at 215 326.02 0)
			(layer "B.Fab")
			(hide yes)
			(effects
				(font
					(size 1 1)
					(thickness 0.15)
				)
				(justify mirror)
			)
		)
		(property "Manufacturer" "Panasonic"
			(at 215 326.02 0)
			(layer "B.Fab")
			(hide yes)
			(effects
				(font
					(size 1 1)
					(thickness 0.15)
				)
				(justify mirror)
			)
		)
		(property "Public" "False"
			(at 215 326.02 0)
			(layer "B.Fab")
			(hide yes)
			(effects
				(font
					(size 1 1)
					(thickness 0.15)
				)
				(justify mirror)
			)
		)
		(property "Tolerance" ""
			(at 215 326.02 0)
			(layer "B.Fab")
			(hide yes)
			(effects
				(font
					(size 1 1)
					(thickness 0.15)
				)
				(justify mirror)
			)
		)
		(property "Val" "0R"
			(at 215 326.02 0)
			(layer "B.Fab")
			(hide yes)
			(effects
				(font
					(size 1 1)
					(thickness 0.15)
				)
				(justify mirror)
			)
		)
		(sheetname "OCuLink")
		(sheetfile "oculink.kicad_sch")
		(attr smd)
		(fp_rect
			(start -0.925 0.47)
			(end 0.925 -0.47)
			(stroke
				(width 0.05)
				(type default)
			)
			(fill no)
			(layer "B.CrtYd")
		)
		(fp_rect
			(start -0.5 0.25)
			(end 0.5 -0.25)
			(stroke
				(width 0.15)
				(type solid)
			)
			(fill no)
			(layer "B.Fab")
		)
		(pad "1" smd roundrect
			(at -0.48 0 180)
			(size 0.59 0.64)
			(layers "B.Cu" "B.Mask" "B.Paste")
			(roundrect_rratio 0.25)
			(net 357 "/Com Express 7 MGMT/SMBus.SCL")
			(pintype "passive")
			(teardrops
				(best_length_ratio 0.2)
				(max_length 1)
				(best_width_ratio 0.9)
				(max_width 2)
				(curved_edges yes)
				(filter_ratio 0.9)
				(enabled yes)
				(allow_two_segments yes)
				(prefer_zone_connections yes)
			)
		)
		(pad "2" smd roundrect
			(at 0.48 0 180)
			(size 0.59 0.64)
			(layers "B.Cu" "B.Mask" "B.Paste")
			(roundrect_rratio 0.25)
			(net 198 "/OCuLink/SCL")
			(pintype "passive")
			(teardrops
				(best_length_ratio 0.2)
				(max_length 1)
				(best_width_ratio 0.9)
				(max_width 2)
				(curved_edges yes)
				(filter_ratio 0.9)
				(enabled yes)
				(allow_two_segments yes)
				(prefer_zone_connections yes)
			)
		)
	)
	(footprint "antmicro-footprints:R_0402_1005Metric"
		(layer "B.Cu")
		(at 310.5 118.16 90)
		(descr "Resistor SMD 0402")
		(tags "resistor SMD 0402")
		(property "Reference" "R95"
			(at -1 -0.45 90)
			(layer "B.SilkS")
			(effects
				(font
					(size 0.7 0.7)
					(thickness 0.15)
				)
				(justify right bottom mirror)
			)
		)
		(property "Value" "R_10k_0402"
			(at -1.011843 -1.772047 90)
			(layer "B.Fab")
			(effects
				(font
					(size 0.7 0.7)
					(thickness 0.15)
				)
				(justify right bottom mirror)
			)
		)
		(property "Datasheet" "https://www.bourns.com/docs/product-datasheets/cr.pdf"
			(at 0 0 90)
			(layer "F.Fab")
			(hide yes)
			(effects
				(font
					(size 1.27 1.27)
					(thickness 0.15)
				)
			)
		)
		(property "Author" "Antmicro"
			(at 428.66 -192.34 0)
			(layer "B.Fab")
			(hide yes)
			(effects
				(font
					(size 1 1)
					(thickness 0.15)
				)
				(justify mirror)
			)
		)
		(property "License" "Apache-2.0"
			(at 428.66 -192.34 0)
			(layer "B.Fab")
			(hide yes)
			(effects
				(font
					(size 1 1)
					(thickness 0.15)
				)
				(justify mirror)
			)
		)
		(property "MPN" "CR0402-FX-1002GLF"
			(at 428.66 -192.34 0)
			(layer "B.Fab")
			(hide yes)
			(effects
				(font
					(size 1 1)
					(thickness 0.15)
				)
				(justify mirror)
			)
		)
		(property "Manufacturer" "Bourns"
			(at 428.66 -192.34 0)
			(layer "B.Fab")
			(hide yes)
			(effects
				(font
					(size 1 1)
					(thickness 0.15)
				)
				(justify mirror)
			)
		)
		(property "Public" "False"
			(at 428.66 -192.34 0)
			(layer "B.Fab")
			(hide yes)
			(effects
				(font
					(size 1 1)
					(thickness 0.15)
				)
				(justify mirror)
			)
		)
		(property "Tolerance" "1%"
			(at 428.66 -192.34 0)
			(layer "B.Fab")
			(hide yes)
			(effects
				(font
					(size 1 1)
					(thickness 0.15)
				)
				(justify mirror)
			)
		)
		(property "Val" "10k"
			(at 428.66 -192.34 0)
			(layer "B.Fab")
			(hide yes)
			(effects
				(font
					(size 1 1)
					(thickness 0.15)
				)
				(justify mirror)
			)
		)
		(sheetname "Power")
		(sheetfile "power.kicad_sch")
		(attr smd)
		(fp_rect
			(start -0.925 0.47)
			(end 0.925 -0.47)
			(stroke
				(width 0.05)
				(type default)
			)
			(fill no)
			(layer "B.CrtYd")
		)
		(fp_rect
			(start -0.5 0.25)
			(end 0.5 -0.25)
			(stroke
				(width 0.15)
				(type solid)
			)
			(fill no)
			(layer "B.Fab")
		)
		(pad "1" smd roundrect
			(at -0.48 0 90)
			(size 0.59 0.64)
			(layers "B.Cu" "B.Mask" "B.Paste")
			(roundrect_rratio 0.25)
			(net 578 "/Power/PG_{1V0}")
			(pintype "passive")
			(teardrops
				(best_length_ratio 0.2)
				(max_length 1)
				(best_width_ratio 0.9)
				(max_width 2)
				(curved_edges yes)
				(filter_ratio 0.9)
				(enabled yes)
				(allow_two_segments yes)
				(prefer_zone_connections yes)
			)
		)
		(pad "2" smd roundrect
			(at 0.48 0 90)
			(size 0.59 0.64)
			(layers "B.Cu" "B.Mask" "B.Paste")
			(roundrect_rratio 0.25)
			(net 2 "+3V3")
			(pintype "passive")
			(teardrops
				(best_length_ratio 0.2)
				(max_length 1)
				(best_width_ratio 0.9)
				(max_width 2)
				(curved_edges yes)
				(filter_ratio 0.9)
				(enabled yes)
				(allow_two_segments yes)
				(prefer_zone_connections yes)
			)
		)
	)
	(footprint "antmicro-footprints:WQFN-42-1EP_3.5x9mm_P0.5mm"
		(layer "B.Cu")
		(at 117.401 147.361 -90)
		(descr "WQFN, 42 Pin (http://www.ti.com/lit/ds/symlink/ts3l501e.pdf#page=23), generated with kicad-footprint-generator ipc_noLead_generator.py")
		(tags "WQFN NoLead")
		(property "Reference" "U39"
			(at -2.301 5.001 90)
			(layer "B.SilkS")
			(effects
				(font
					(size 0.7 0.7)
					(thickness 0.15)
				)
				(justify left bottom mirror)
			)
		)
		(property "Value" "PI3EQX16904GL"
			(at 0 -5.82 90)
			(layer "B.Fab")
			(effects
				(font
					(size 0.7 0.7)
					(thickness 0.15)
				)
				(justify left bottom mirror)
			)
		)
		(property "Datasheet" "https://www.diodes.com/part/view/PI3EQX16904GL"
			(at 0 0 270)
			(layer "F.Fab")
			(hide yes)
			(effects
				(font
					(size 1.27 1.27)
					(thickness 0.15)
				)
			)
		)
		(property "Author" "Antmicro"
			(at -29.96 264.762 0)
			(layer "B.Fab")
			(hide yes)
			(effects
				(font
					(size 1 1)
					(thickness 0.15)
				)
				(justify mirror)
			)
		)
		(property "License" "Apache-2.0"
			(at -29.96 264.762 0)
			(layer "B.Fab")
			(hide yes)
			(effects
				(font
					(size 1 1)
					(thickness 0.15)
				)
				(justify mirror)
			)
		)
		(property "MPN" "PI3EQX16904GLZHEX"
			(at -29.96 264.762 0)
			(layer "B.Fab")
			(hide yes)
			(effects
				(font
					(size 1 1)
					(thickness 0.15)
				)
				(justify mirror)
			)
		)
		(property "Manufacturer" "Diodes Incorporated"
			(at -29.96 264.762 0)
			(layer "B.Fab")
			(hide yes)
			(effects
				(font
					(size 1 1)
					(thickness 0.15)
				)
				(justify mirror)
			)
		)
		(sheetname "PCIe redriver")
		(sheetfile "pcie_redriver.kicad_sch")
		(attr smd)
		(fp_line
			(start -1.861 4.611)
			(end -1.135 4.611)
			(stroke
				(width 0.15)
				(type solid)
			)
			(layer "B.SilkS")
		)
		(fp_line
			(start 1.86 4.611)
			(end 1.134 4.611)
			(stroke
				(width 0.15)
				(type solid)
			)
			(layer "B.SilkS")
		)
		(fp_line
			(start 1.86 4.385)
			(end 1.86 4.611)
			(stroke
				(width 0.15)
				(type solid)
			)
			(layer "B.SilkS")
		)
		(fp_line
			(start -1.861 -4.384)
			(end -1.861 -4.61)
			(stroke
				(width 0.15)
				(type solid)
			)
			(layer "B.SilkS")
		)
		(fp_line
			(start 1.86 -4.384)
			(end 1.86 -4.61)
			(stroke
				(width 0.15)
				(type solid)
			)
			(layer "B.SilkS")
		)
		(fp_line
			(start -1.861 -4.61)
			(end -1.135 -4.61)
			(stroke
				(width 0.15)
				(type solid)
			)
			(layer "B.SilkS")
		)
		(fp_line
			(start 1.86 -4.61)
			(end 1.134 -4.61)
			(stroke
				(width 0.15)
				(type solid)
			)
			(layer "B.SilkS")
		)
		(fp_circle
			(center -2.68 4)
			(end -2.63 4)
			(stroke
				(width 0.15)
				(type solid)
			)
			(fill yes)
			(layer "B.SilkS")
		)
		(fp_rect
			(start -2.25 5)
			(end 2.249 -4.998)
			(stroke
				(width 0.05)
				(type solid)
			)
			(fill no)
			(layer "B.CrtYd")
		)
		(fp_line
			(start -0.875 4.5)
			(end -1.75 3.625)
			(stroke
				(width 0.15)
				(type solid)
			)
			(layer "B.Fab")
		)
		(fp_line
			(start 1.749 4.5)
			(end -0.875 4.5)
			(stroke
				(width 0.15)
				(type solid)
			)
			(layer "B.Fab")
		)
		(fp_line
			(start -1.75 3.625)
			(end -1.75 -4.498)
			(stroke
				(width 0.15)
				(type solid)
			)
			(layer "B.Fab")
		)
		(fp_line
			(start -1.75 -4.498)
			(end 1.749 -4.498)
			(stroke
				(width 0.15)
				(type solid)
			)
			(layer "B.Fab")
		)
		(fp_line
			(start 1.749 -4.498)
			(end 1.749 4.5)
			(stroke
				(width 0.15)
				(type solid)
			)
			(layer "B.Fab")
		)
		(pad "" smd roundrect
			(at -0.51 -3.24 270)
			(size 0.83 0.87)
			(layers "B.Paste")
			(roundrect_rratio 0.25)
			(teardrops
				(best_length_ratio 0.2)
				(max_length 1)
				(best_width_ratio 0.9)
				(max_width 2)
				(curved_edges yes)
				(filter_ratio 0.9)
				(enabled yes)
				(allow_two_segments yes)
				(prefer_zone_connections yes)
			)
		)
		(pad "" smd roundrect
			(at -0.51 -2.16 270)
			(size 0.83 0.87)
			(layers "B.Paste")
			(roundrect_rratio 0.25)
			(teardrops
				(best_length_ratio 0.2)
				(max_length 1)
				(best_width_ratio 0.9)
				(max_width 2)
				(curved_edges yes)
				(filter_ratio 0.9)
				(enabled yes)
				(allow_two_segments yes)
				(prefer_zone_connections yes)
			)
		)
		(pad "" smd roundrect
			(at -0.51 -1.08 270)
			(size 0.83 0.87)
			(layers "B.Paste")
			(roundrect_rratio 0.25)
			(teardrops
				(best_length_ratio 0.2)
				(max_length 1)
				(best_width_ratio 0.9)
				(max_width 2)
				(curved_edges yes)
				(filter_ratio 0.9)
				(enabled yes)
				(allow_two_segments yes)
				(prefer_zone_connections yes)
			)
		)
		(pad "" smd roundrect
			(at -0.51 0 270)
			(size 0.83 0.87)
			(layers "B.Paste")
			(roundrect_rratio 0.25)
			(teardrops
				(best_length_ratio 0.2)
				(max_length 1)
				(best_width_ratio 0.9)
				(max_width 2)
				(curved_edges yes)
				(filter_ratio 0.9)
				(enabled yes)
				(allow_two_segments yes)
				(prefer_zone_connections yes)
			)
		)
		(pad "" smd roundrect
			(at -0.51 1.081 270)
			(size 0.83 0.87)
			(layers "B.Paste")
			(roundrect_rratio 0.25)
			(teardrops
				(best_length_ratio 0.2)
				(max_length 1)
				(best_width_ratio 0.9)
				(max_width 2)
				(curved_edges yes)
				(filter_ratio 0.9)
				(enabled yes)
				(allow_two_segments yes)
				(prefer_zone_connections yes)
			)
		)
		(pad "" smd roundrect
			(at -0.51 2.161 270)
			(size 0.83 0.87)
			(layers "B.Paste")
			(roundrect_rratio 0.25)
			(teardrops
				(best_length_ratio 0.2)
				(max_length 1)
				(best_width_ratio 0.9)
				(max_width 2)
				(curved_edges yes)
				(filter_ratio 0.9)
				(enabled yes)
				(allow_two_segments yes)
				(prefer_zone_connections yes)
			)
		)
		(pad "" smd roundrect
			(at -0.51 3.242 270)
			(size 0.83 0.87)
			(layers "B.Paste")
			(roundrect_rratio 0.25)
			(teardrops
				(best_length_ratio 0.2)
				(max_length 1)
				(best_width_ratio 0.9)
				(max_width 2)
				(curved_edges yes)
				(filter_ratio 0.9)
				(enabled yes)
				(allow_two_segments yes)
				(prefer_zone_connections yes)
			)
		)
		(pad "" smd roundrect
			(at 0.508 -3.24 270)
			(size 0.83 0.87)
			(layers "B.Paste")
			(roundrect_rratio 0.25)
			(teardrops
				(best_length_ratio 0.2)
				(max_length 1)
				(best_width_ratio 0.9)
				(max_width 2)
				(curved_edges yes)
				(filter_ratio 0.9)
				(enabled yes)
				(allow_two_segments yes)
				(prefer_zone_connections yes)
			)
		)
		(pad "" smd roundrect
			(at 0.508 -2.16 270)
			(size 0.83 0.87)
			(layers "B.Paste")
			(roundrect_rratio 0.25)
			(teardrops
				(best_length_ratio 0.2)
				(max_length 1)
				(best_width_ratio 0.9)
				(max_width 2)
				(curved_edges yes)
				(filter_ratio 0.9)
				(enabled yes)
				(allow_two_segments yes)
				(prefer_zone_connections yes)
			)
		)
		(pad "" smd roundrect
			(at 0.508 -1.08 270)
			(size 0.83 0.87)
			(layers "B.Paste")
			(roundrect_rratio 0.25)
			(teardrops
				(best_length_ratio 0.2)
				(max_length 1)
				(best_width_ratio 0.9)
				(max_width 2)
				(curved_edges yes)
				(filter_ratio 0.9)
				(enabled yes)
				(allow_two_segments yes)
				(prefer_zone_connections yes)
			)
		)
		(pad "" smd roundrect
			(at 0.508 0 270)
			(size 0.83 0.87)
			(layers "B.Paste")
			(roundrect_rratio 0.25)
			(teardrops
				(best_length_ratio 0.2)
				(max_length 1)
				(best_width_ratio 0.9)
				(max_width 2)
				(curved_edges yes)
				(filter_ratio 0.9)
				(enabled yes)
				(allow_two_segments yes)
				(prefer_zone_connections yes)
			)
		)
		(pad "" smd roundrect
			(at 0.508 1.081 270)
			(size 0.83 0.87)
			(layers "B.Paste")
			(roundrect_rratio 0.25)
			(teardrops
				(best_length_ratio 0.2)
				(max_length 1)
				(best_width_ratio 0.9)
				(max_width 2)
				(curved_edges yes)
				(filter_ratio 0.9)
				(enabled yes)
				(allow_two_segments yes)
				(prefer_zone_connections yes)
			)
		)
		(pad "" smd roundrect
			(at 0.508 2.161 270)
			(size 0.83 0.87)
			(layers "B.Paste")
			(roundrect_rratio 0.25)
			(teardrops
				(best_length_ratio 0.2)
				(max_length 1)
				(best_width_ratio 0.9)
				(max_width 2)
				(curved_edges yes)
				(filter_ratio 0.9)
				(enabled yes)
				(allow_two_segments yes)
				(prefer_zone_connections yes)
			)
		)
		(pad "" smd roundrect
			(at 0.508 3.242 270)
			(size 0.83 0.87)
			(layers "B.Paste")
			(roundrect_rratio 0.25)
			(teardrops
				(best_length_ratio 0.2)
				(max_length 1)
				(best_width_ratio 0.9)
				(max_width 2)
				(curved_edges yes)
				(filter_ratio 0.9)
				(enabled yes)
				(allow_two_segments yes)
				(prefer_zone_connections yes)
			)
		)
		(pad "1" smd roundrect
			(at -1.688 4 270)
			(size 0.875 0.25)
			(layers "B.Cu" "B.Mask" "B.Paste")
			(roundrect_rratio 0.25)
			(net 625 "/PCIe redriver/TX_EQ2")
			(pinfunction "EQ2")
			(pintype "passive")
			(teardrops
				(best_length_ratio 0.2)
				(max_length 1)
				(best_width_ratio 0.9)
				(max_width 2)
				(curved_edges yes)
				(filter_ratio 0.9)
				(enabled yes)
				(allow_two_segments yes)
				(prefer_zone_connections yes)
			)
		)
		(pad "2" smd roundrect
			(at -1.688 3.5 270)
			(size 0.875 0.25)
			(layers "B.Cu" "B.Mask" "B.Paste")
			(roundrect_rratio 0.25)
			(net 628 "/PCIe redriver/TX_SW")
			(pinfunction "SW1")
			(pintype "input")
			(teardrops
				(best_length_ratio 0.2)
				(max_length 1)
				(best_width_ratio 0.9)
				(max_width 2)
				(curved_edges yes)
				(filter_ratio 0.9)
				(enabled yes)
				(allow_two_segments yes)
				(prefer_zone_connections yes)
			)
		)
		(pad "3" smd roundrect
			(at -1.688 3 270)
			(size 0.875 0.25)
			(layers "B.Cu" "B.Mask" "B.Paste")
			(roundrect_rratio 0.25)
			(net 2 "+3V3")
			(pinfunction "VCC")
			(pintype "passive")
			(teardrops
				(best_length_ratio 0.2)
				(max_length 1)
				(best_width_ratio 0.9)
				(max_width 2)
				(curved_edges yes)
				(filter_ratio 0.9)
				(enabled yes)
				(allow_two_segments yes)
				(prefer_zone_connections yes)
			)
		)
		(pad "4" smd roundrect
			(at -1.688 2.5 270)
			(size 0.875 0.25)
			(layers "B.Cu" "B.Mask" "B.Paste")
			(roundrect_rratio 0.25)
			(net 211 "/Com Express 7 Interfaces/PCIe_{B1x4}.TX3-")
			(pinfunction "A0RX+")
			(pintype "input")
			(teardrops
				(best_length_ratio 0.2)
				(max_length 1)
				(best_width_ratio 0.9)
				(max_width 2)
				(curved_edges yes)
				(filter_ratio 0.9)
				(enabled yes)
				(allow_two_segments yes)
				(prefer_zone_connections yes)
			)
		)
		(pad "5" smd roundrect
			(at -1.688 2 270)
			(size 0.875 0.25)
			(layers "B.Cu" "B.Mask" "B.Paste")
			(roundrect_rratio 0.25)
			(net 212 "/Com Express 7 Interfaces/PCIe_{B1x4}.TX3+")
			(pinfunction "A0RX-")
			(pintype "input")
			(teardrops
				(best_length_ratio 0.2)
				(max_length 1)
				(best_width_ratio 0.9)
				(max_width 2)
				(curved_edges yes)
				(filter_ratio 0.9)
				(enabled yes)
				(allow_two_segments yes)
				(prefer_zone_connections yes)
			)
		)
		(pad "6" smd roundrect
			(at -1.688 1.5 270)
			(size 0.875 0.25)
			(layers "B.Cu" "B.Mask" "B.Paste")
			(roundrect_rratio 0.25)
			(net 2 "+3V3")
			(pinfunction "VCC")
			(pintype "passive")
			(teardrops
				(best_length_ratio 0.2)
				(max_length 1)
				(best_width_ratio 0.9)
				(max_width 2)
				(curved_edges yes)
				(filter_ratio 0.9)
				(enabled yes)
				(allow_two_segments yes)
				(prefer_zone_connections yes)
			)
		)
		(pad "7" smd roundrect
			(at -1.688 1 270)
			(size 0.875 0.25)
			(layers "B.Cu" "B.Mask" "B.Paste")
			(roundrect_rratio 0.25)
			(net 215 "/Com Express 7 Interfaces/PCIe_{B1x4}.TX2-")
			(pinfunction "A1RX+")
			(pintype "input")
			(teardrops
				(best_length_ratio 0.2)
				(max_length 1)
				(best_width_ratio 0.9)
				(max_width 2)
				(curved_edges yes)
				(filter_ratio 0.9)
				(enabled yes)
				(allow_two_segments yes)
				(prefer_zone_connections yes)
			)
		)
		(pad "8" smd roundrect
			(at -1.688 0.5 270)
			(size 0.875 0.25)
			(layers "B.Cu" "B.Mask" "B.Paste")
			(roundrect_rratio 0.25)
			(net 216 "/Com Express 7 Interfaces/PCIe_{B1x4}.TX2+")
			(pinfunction "A1RX-")
			(pintype "input")
			(teardrops
				(best_length_ratio 0.2)
				(max_length 1)
				(best_width_ratio 0.9)
				(max_width 2)
				(curved_edges yes)
				(filter_ratio 0.9)
				(enabled yes)
				(allow_two_segments yes)
				(prefer_zone_connections yes)
			)
		)
		(pad "9" smd roundrect
			(at -1.688 0 270)
			(size 0.875 0.25)
			(layers "B.Cu" "B.Mask" "B.Paste")
			(roundrect_rratio 0.25)
			(net 2 "+3V3")
			(pinfunction "VCC")
			(pintype "passive")
			(teardrops
				(best_length_ratio 0.2)
				(max_length 1)
				(best_width_ratio 0.9)
				(max_width 2)
				(curved_edges yes)
				(filter_ratio 0.9)
				(enabled yes)
				(allow_two_segments yes)
				(prefer_zone_connections yes)
			)
		)
		(pad "10" smd roundrect
			(at -1.688 -0.5 270)
			(size 0.875 0.25)
			(layers "B.Cu" "B.Mask" "B.Paste")
			(roundrect_rratio 0.25)
			(net 219 "/Com Express 7 Interfaces/PCIe_{B1x4}.TX1-")
			(pinfunction "A2RX+")
			(pintype "input")
			(teardrops
				(best_length_ratio 0.2)
				(max_length 1)
				(best_width_ratio 0.9)
				(max_width 2)
				(curved_edges yes)
				(filter_ratio 0.9)
				(enabled yes)
				(allow_two_segments yes)
				(prefer_zone_connections yes)
			)
		)
		(pad "11" smd roundrect
			(at -1.688 -1 270)
			(size 0.875 0.25)
			(layers "B.Cu" "B.Mask" "B.Paste")
			(roundrect_rratio 0.25)
			(net 220 "/Com Express 7 Interfaces/PCIe_{B1x4}.TX1+")
			(pinfunction "A2RX-")
			(pintype "input")
			(teardrops
				(best_length_ratio 0.2)
				(max_length 1)
				(best_width_ratio 0.9)
				(max_width 2)
				(curved_edges yes)
				(filter_ratio 0.9)
				(enabled yes)
				(allow_two_segments yes)
				(prefer_zone_connections yes)
			)
		)
		(pad "12" smd roundrect
			(at -1.688 -1.5 270)
			(size 0.875 0.25)
			(layers "B.Cu" "B.Mask" "B.Paste")
			(roundrect_rratio 0.25)
			(net 2 "+3V3")
			(pinfunction "VCC")
			(pintype "power_in")
			(teardrops
				(best_length_ratio 0.2)
				(max_length 1)
				(best_width_ratio 0.9)
				(max_width 2)
				(curved_edges yes)
				(filter_ratio 0.9)
				(enabled yes)
				(allow_two_segments yes)
				(prefer_zone_connections yes)
			)
		)
		(pad "13" smd roundrect
			(at -1.688 -2 270)
			(size 0.875 0.25)
			(layers "B.Cu" "B.Mask" "B.Paste")
			(roundrect_rratio 0.25)
			(net 225 "/Com Express 7 Interfaces/PCIe_{B1x4}.TX0-")
			(pinfunction "A3RX+")
			(pintype "input")
			(teardrops
				(best_length_ratio 0.2)
				(max_length 1)
				(best_width_ratio 0.9)
				(max_width 2)
				(curved_edges yes)
				(filter_ratio 0.9)
				(enabled yes)
				(allow_two_segments yes)
				(prefer_zone_connections yes)
			)
		)
		(pad "14" smd roundrect
			(at -1.688 -2.5 270)
			(size 0.875 0.25)
			(layers "B.Cu" "B.Mask" "B.Paste")
			(roundrect_rratio 0.25)
			(net 227 "/Com Express 7 Interfaces/PCIe_{B1x4}.TX0+")
			(pinfunction "A3RX-")
			(pintype "input")
			(teardrops
				(best_length_ratio 0.2)
				(max_length 1)
				(best_width_ratio 0.9)
				(max_width 2)
				(curved_edges yes)
				(filter_ratio 0.9)
				(enabled yes)
				(allow_two_segments yes)
				(prefer_zone_connections yes)
			)
		)
		(pad "15" smd roundrect
			(at -1.688 -3 270)
			(size 0.875 0.25)
			(layers "B.Cu" "B.Mask" "B.Paste")
			(roundrect_rratio 0.25)
			(net 2 "+3V3")
			(pinfunction "VCC")
			(pintype "passive")
			(teardrops
				(best_length_ratio 0.2)
				(max_length 1)
				(best_width_ratio 0.9)
				(max_width 2)
				(curved_edges yes)
				(filter_ratio 0.9)
				(enabled yes)
				(allow_two_segments yes)
				(prefer_zone_connections yes)
			)
		)
		(pad "16" smd roundrect
			(at -1.688 -3.5 270)
			(size 0.875 0.25)
			(layers "B.Cu" "B.Mask" "B.Paste")
			(roundrect_rratio 0.25)
			(net 715 "Net-(U39-~{I2C_{RESET}})")
			(pinfunction "~{I2C_{RESET}}")
			(pintype "input")
			(teardrops
				(best_length_ratio 0.2)
				(max_length 1)
				(best_width_ratio 0.9)
				(max_width 2)
				(curved_edges yes)
				(filter_ratio 0.9)
				(enabled yes)
				(allow_two_segments yes)
				(prefer_zone_connections yes)
			)
		)
		(pad "17" smd roundrect
			(at -1.688 -4 270)
			(size 0.875 0.25)
			(layers "B.Cu" "B.Mask" "B.Paste")
			(roundrect_rratio 0.25)
			(net 1 "GND")
			(pinfunction "AD1")
			(pintype "passive")
			(teardrops
				(best_length_ratio 0.2)
				(max_length 1)
				(best_width_ratio 0.9)
				(max_width 2)
				(curved_edges yes)
				(filter_ratio 0.9)
				(enabled yes)
				(allow_two_segments yes)
				(prefer_zone_connections yes)
			)
		)
		(pad "18" smd roundrect
			(at -0.75 -4.437 270)
			(size 0.25 0.875)
			(layers "B.Cu" "B.Mask" "B.Paste")
			(roundrect_rratio 0.25)
			(net 712 "Net-(U39-SDA)")
			(pinfunction "SDA")
			(pintype "open_collector")
			(teardrops
				(best_length_ratio 0.2)
				(max_length 1)
				(best_width_ratio 0.9)
				(max_width 2)
				(curved_edges yes)
				(filter_ratio 0.9)
				(enabled yes)
				(allow_two_segments yes)
				(prefer_zone_connections yes)
			)
		)
		(pad "19" smd roundrect
			(at -0.25 -4.437 270)
			(size 0.25 0.875)
			(layers "B.Cu" "B.Mask" "B.Paste")
			(roundrect_rratio 0.25)
			(net 713 "Net-(U39-SCL)")
			(pinfunction "SCL")
			(pintype "open_collector")
			(teardrops
				(best_length_ratio 0.2)
				(max_length 1)
				(best_width_ratio 0.9)
				(max_width 2)
				(curved_edges yes)
				(filter_ratio 0.9)
				(enabled yes)
				(allow_two_segments yes)
				(prefer_zone_connections yes)
			)
		)
		(pad "20" smd roundrect
			(at 0.25 -4.437 270)
			(size 0.25 0.875)
			(layers "B.Cu" "B.Mask" "B.Paste")
			(roundrect_rratio 0.25)
			(net 945 "/GPIO expander/GPIOEX5")
			(pinfunction "~{PRSNT}")
			(pintype "input")
			(teardrops
				(best_length_ratio 0.2)
				(max_length 1)
				(best_width_ratio 0.9)
				(max_width 2)
				(curved_edges yes)
				(filter_ratio 0.9)
				(enabled yes)
				(allow_two_segments yes)
				(prefer_zone_connections yes)
			)
		)
		(pad "21" smd roundrect
			(at 0.75 -4.437 270)
			(size 0.25 0.875)
			(layers "B.Cu" "B.Mask" "B.Paste")
			(roundrect_rratio 0.25)
			(net 629 "Net-(U39-EN_{I2C})")
			(pinfunction "EN_{I2C}")
			(pintype "input")
			(teardrops
				(best_length_ratio 0.2)
				(max_length 1)
				(best_width_ratio 0.9)
				(max_width 2)
				(curved_edges yes)
				(filter_ratio 0.9)
				(enabled yes)
				(allow_two_segments yes)
				(prefer_zone_connections yes)
			)
		)
		(pad "22" smd roundrect
			(at 1.687 -4 270)
			(size 0.875 0.25)
			(layers "B.Cu" "B.Mask" "B.Paste")
			(roundrect_rratio 0.25)
			(net 714 "Net-(U39-I2C_{DONE})")
			(pinfunction "I2C_{DONE}")
			(pintype "input")
			(teardrops
				(best_length_ratio 0.2)
				(max_length 1)
				(best_width_ratio 0.9)
				(max_width 2)
				(curved_edges yes)
				(filter_ratio 0.9)
				(enabled yes)
				(allow_two_segments yes)
				(prefer_zone_connections yes)
			)
		)
		(pad "23" smd roundrect
			(at 1.687 -3.5 270)
			(size 0.875 0.25)
			(layers "B.Cu" "B.Mask" "B.Paste")
			(roundrect_rratio 0.25)
			(net 631 "Net-(U39-RXDET)")
			(pinfunction "RXDET")
			(pintype "input")
			(teardrops
				(best_length_ratio 0.2)
				(max_length 1)
				(best_width_ratio 0.9)
				(max_width 2)
				(curved_edges yes)
				(filter_ratio 0.9)
				(enabled yes)
				(allow_two_segments yes)
				(prefer_zone_connections yes)
			)
		)
		(pad "24" smd roundrect
			(at 1.687 -3 270)
			(size 0.875 0.25)
			(layers "B.Cu" "B.Mask" "B.Paste")
			(roundrect_rratio 0.25)
			(net 2 "+3V3")
			(pinfunction "VCC")
			(pintype "passive")
			(teardrops
				(best_length_ratio 0.2)
				(max_length 1)
				(best_width_ratio 0.9)
				(max_width 2)
				(curved_edges yes)
				(filter_ratio 0.9)
				(enabled yes)
				(allow_two_segments yes)
				(prefer_zone_connections yes)
			)
		)
		(pad "25" smd roundrect
			(at 1.687 -2.5 270)
			(size 0.875 0.25)
			(layers "B.Cu" "B.Mask" "B.Paste")
			(roundrect_rratio 0.25)
			(net 963 "/PCIe redriver/PCIe_{O}_C.TX0+")
			(pinfunction "A3TX-")
			(pintype "output")
			(teardrops
				(best_length_ratio 0.2)
				(max_length 1)
				(best_width_ratio 0.9)
				(max_width 2)
				(curved_edges yes)
				(filter_ratio 0.9)
				(enabled yes)
				(allow_two_segments yes)
				(prefer_zone_connections yes)
			)
		)
		(pad "26" smd roundrect
			(at 1.687 -2 270)
			(size 0.875 0.25)
			(layers "B.Cu" "B.Mask" "B.Paste")
			(roundrect_rratio 0.25)
			(net 966 "/PCIe redriver/PCIe_{O}_C.TX0-")
			(pinfunction "A3TX+")
			(pintype "input")
			(teardrops
				(best_length_ratio 0.2)
				(max_length 1)
				(best_width_ratio 0.9)
				(max_width 2)
				(curved_edges yes)
				(filter_ratio 0.9)
				(enabled yes)
				(allow_two_segments yes)
				(prefer_zone_connections yes)
			)
		)
		(pad "27" smd roundrect
			(at 1.687 -1.5 270)
			(size 0.875 0.25)
			(layers "B.Cu" "B.Mask" "B.Paste")
			(roundrect_rratio 0.25)
			(net 2 "+3V3")
			(pinfunction "VCC")
			(pintype "passive")
			(teardrops
				(best_length_ratio 0.2)
				(max_length 1)
				(best_width_ratio 0.9)
				(max_width 2)
				(curved_edges yes)
				(filter_ratio 0.9)
				(enabled yes)
				(allow_two_segments yes)
				(prefer_zone_connections yes)
			)
		)
		(pad "28" smd roundrect
			(at 1.687 -1 270)
			(size 0.875 0.25)
			(layers "B.Cu" "B.Mask" "B.Paste")
			(roundrect_rratio 0.25)
			(net 962 "/PCIe redriver/PCIe_{O}_C.TX1+")
			(pinfunction "A2TX-")
			(pintype "output")
			(teardrops
				(best_length_ratio 0.2)
				(max_length 1)
				(best_width_ratio 0.9)
				(max_width 2)
				(curved_edges yes)
				(filter_ratio 0.9)
				(enabled yes)
				(allow_two_segments yes)
				(prefer_zone_connections yes)
			)
		)
		(pad "29" smd roundrect
			(at 1.687 -0.5 270)
			(size 0.875 0.25)
			(layers "B.Cu" "B.Mask" "B.Paste")
			(roundrect_rratio 0.25)
			(net 965 "/PCIe redriver/PCIe_{O}_C.TX1-")
			(pinfunction "A2TX+")
			(pintype "input")
			(teardrops
				(best_length_ratio 0.2)
				(max_length 1)
				(best_width_ratio 0.9)
				(max_width 2)
				(curved_edges yes)
				(filter_ratio 0.9)
				(enabled yes)
				(allow_two_segments yes)
				(prefer_zone_connections yes)
			)
		)
		(pad "30" smd roundrect
			(at 1.687 0 270)
			(size 0.875 0.25)
			(layers "B.Cu" "B.Mask" "B.Paste")
			(roundrect_rratio 0.25)
			(net 2 "+3V3")
			(pinfunction "VCC")
			(pintype "passive")
			(teardrops
				(best_length_ratio 0.2)
				(max_length 1)
				(best_width_ratio 0.9)
				(max_width 2)
				(curved_edges yes)
				(filter_ratio 0.9)
				(enabled yes)
				(allow_two_segments yes)
				(prefer_zone_connections yes)
			)
		)
		(pad "31" smd roundrect
			(at 1.687 0.5 270)
			(size 0.875 0.25)
			(layers "B.Cu" "B.Mask" "B.Paste")
			(roundrect_rratio 0.25)
			(net 961 "/PCIe redriver/PCIe_{O}_C.TX2+")
			(pinfunction "A1TX-")
			(pintype "output")
			(teardrops
				(best_length_ratio 0.2)
				(max_length 1)
				(best_width_ratio 0.9)
				(max_width 2)
				(curved_edges yes)
				(filter_ratio 0.9)
				(enabled yes)
				(allow_two_segments yes)
				(prefer_zone_connections yes)
			)
		)
		(pad "32" smd roundrect
			(at 1.687 1 270)
			(size 0.875 0.25)
			(layers "B.Cu" "B.Mask" "B.Paste")
			(roundrect_rratio 0.25)
			(net 964 "/PCIe redriver/PCIe_{O}_C.TX2-")
			(pinfunction "A1TX+")
			(pintype "input")
			(teardrops
				(best_length_ratio 0.2)
				(max_length 1)
				(best_width_ratio 0.9)
				(max_width 2)
				(curved_edges yes)
				(filter_ratio 0.9)
				(enabled yes)
				(allow_two_segments yes)
				(prefer_zone_connections yes)
			)
		)
		(pad "33" smd roundrect
			(at 1.687 1.5 270)
			(size 0.875 0.25)
			(layers "B.Cu" "B.Mask" "B.Paste")
			(roundrect_rratio 0.25)
			(net 2 "+3V3")
			(pinfunction "VCC")
			(pintype "passive")
			(teardrops
				(best_length_ratio 0.2)
				(max_length 1)
				(best_width_ratio 0.9)
				(max_width 2)
				(curved_edges yes)
				(filter_ratio 0.9)
				(enabled yes)
				(allow_two_segments yes)
				(prefer_zone_connections yes)
			)
		)
		(pad "34" smd roundrect
			(at 1.687 2 270)
			(size 0.875 0.25)
			(layers "B.Cu" "B.Mask" "B.Paste")
			(roundrect_rratio 0.25)
			(net 94 "/PCIe redriver/PCIe_{O}_C.TX3+")
			(pinfunction "A0TX-")
			(pintype "output")
			(teardrops
				(best_length_ratio 0.2)
				(max_length 1)
				(best_width_ratio 0.9)
				(max_width 2)
				(curved_edges yes)
				(filter_ratio 0.9)
				(enabled yes)
				(allow_two_segments yes)
				(prefer_zone_connections yes)
			)
		)
		(pad "35" smd roundrect
			(at 1.687 2.5 270)
			(size 0.875 0.25)
			(layers "B.Cu" "B.Mask" "B.Paste")
			(roundrect_rratio 0.25)
			(net 99 "/PCIe redriver/PCIe_{O}_C.TX3-")
			(pinfunction "A0TX+")
			(pintype "input")
			(teardrops
				(best_length_ratio 0.2)
				(max_length 1)
				(best_width_ratio 0.9)
				(max_width 2)
				(curved_edges yes)
				(filter_ratio 0.9)
				(enabled yes)
				(allow_two_segments yes)
				(prefer_zone_connections yes)
			)
		)
		(pad "36" smd roundrect
			(at 1.687 3 270)
			(size 0.875 0.25)
			(layers "B.Cu" "B.Mask" "B.Paste")
			(roundrect_rratio 0.25)
			(net 2 "+3V3")
			(pinfunction "VCC")
			(pintype "passive")
			(teardrops
				(best_length_ratio 0.2)
				(max_length 1)
				(best_width_ratio 0.9)
				(max_width 2)
				(curved_edges yes)
				(filter_ratio 0.9)
				(enabled yes)
				(allow_two_segments yes)
				(prefer_zone_connections yes)
			)
		)
		(pad "37" smd roundrect
			(at 1.687 3.5 270)
			(size 0.875 0.25)
			(layers "B.Cu" "B.Mask" "B.Paste")
			(roundrect_rratio 0.25)
			(net 626 "/PCIe redriver/TX_FG0")
			(pinfunction "FG0")
			(pintype "passive")
			(teardrops
				(best_length_ratio 0.2)
				(max_length 1)
				(best_width_ratio 0.9)
				(max_width 2)
				(curved_edges yes)
				(filter_ratio 0.9)
				(enabled yes)
				(allow_two_segments yes)
				(prefer_zone_connections yes)
			)
		)
		(pad "38" smd roundrect
			(at 1.687 4 270)
			(size 0.875 0.25)
			(layers "B.Cu" "B.Mask" "B.Paste")
			(roundrect_rratio 0.25)
			(net 627 "/PCIe redriver/TX_FG1")
			(pinfunction "FG1")
			(pintype "passive")
			(teardrops
				(best_length_ratio 0.2)
				(max_length 1)
				(best_width_ratio 0.9)
				(max_width 2)
				(curved_edges yes)
				(filter_ratio 0.9)
				(enabled yes)
				(allow_two_segments yes)
				(prefer_zone_connections yes)
			)
		)
		(pad "39" smd roundrect
			(at 0.75 4.438 270)
			(size 0.25 0.875)
			(layers "B.Cu" "B.Mask" "B.Paste")
			(roundrect_rratio 0.25)
			(net 623 "/PCIe redriver/TX_EQ0")
			(pinfunction "EQ0")
			(pintype "passive")
			(teardrops
				(best_length_ratio 0.2)
				(max_length 1)
				(best_width_ratio 0.9)
				(max_width 2)
				(curved_edges yes)
				(filter_ratio 0.9)
				(enabled yes)
				(allow_two_segments yes)
				(prefer_zone_connections yes)
			)
		)
		(pad "40" smd roundrect
			(at 0.25 4.438 270)
			(size 0.25 0.875)
			(layers "B.Cu" "B.Mask" "B.Paste")
			(roundrect_rratio 0.25)
			(net 624 "/PCIe redriver/TX_EQ1")
			(pinfunction "EQ1")
			(pintype "passive")
			(teardrops
				(best_length_ratio 0.2)
				(max_length 1)
				(best_width_ratio 0.9)
				(max_width 2)
				(curved_edges yes)
				(filter_ratio 0.9)
				(enabled yes)
				(allow_two_segments yes)
				(prefer_zone_connections yes)
			)
		)
		(pad "41" smd roundrect
			(at -0.25 4.438 270)
			(size 0.25 0.875)
			(layers "B.Cu" "B.Mask" "B.Paste")
			(roundrect_rratio 0.25)
			(net 1 "GND")
			(pinfunction "AD2")
			(pintype "passive")
			(teardrops
				(best_length_ratio 0.2)
				(max_length 1)
				(best_width_ratio 0.9)
				(max_width 2)
				(curved_edges yes)
				(filter_ratio 0.9)
				(enabled no)
				(allow_two_segments yes)
				(prefer_zone_connections yes)
			)
		)
		(pad "42" smd roundrect
			(at -0.75 4.438 270)
			(size 0.25 0.875)
			(layers "B.Cu" "B.Mask" "B.Paste")
			(roundrect_rratio 0.25)
			(net 1 "GND")
			(pinfunction "AD3")
			(pintype "passive")
			(teardrops
				(best_length_ratio 0.2)
				(max_length 1)
				(best_width_ratio 0.9)
				(max_width 2)
				(curved_edges yes)
				(filter_ratio 0.9)
				(enabled no)
				(allow_two_segments yes)
				(prefer_zone_connections yes)
			)
		)
		(pad "43" smd rect
			(at 0 0 270)
			(size 2.05 7.55)
			(layers "B.Cu" "B.Mask")
			(net 1 "GND")
			(pinfunction "GND")
			(pintype "power_in")
			(teardrops
				(best_length_ratio 0.2)
				(max_length 1)
				(best_width_ratio 0.9)
				(max_width 2)
				(curved_edges yes)
				(filter_ratio 0.9)
				(enabled no)
				(allow_two_segments yes)
				(prefer_zone_connections yes)
			)
		)
	)
	(footprint "antmicro-footprints:USON-10_2.5x1mm_P0.5mm"
		(layer "B.Cu")
		(at 314.75 160.91 180)
		(descr "USON-10 2.5x1mm_ Pitch 0.5mm")
		(tags "USON-10 2.5x1mm Pitch 0.5mm")
		(property "Reference" "U14"
			(at 0.85 1.1 90)
			(layer "B.SilkS")
			(effects
				(font
					(size 0.7 0.7)
					(thickness 0.15)
				)
				(justify left bottom mirror)
			)
		)
		(property "Value" "ESD204DQAR"
			(at 0.018 -2.499 0)
			(layer "B.Fab")
			(effects
				(font
					(size 0.7 0.7)
					(thickness 0.15)
				)
				(justify left bottom mirror)
			)
		)
		(property "Datasheet" "https://www.ti.com/lit/ds/symlink/esd204.pdf?ts=1706004844383&ref_url=https%253A%252F%252Fwww.ti.com%252Finterface%252Fdiodes%252Fesd-protection-diodes%252Fproducts.html"
			(at 0 0 180)
			(layer "F.Fab")
			(hide yes)
			(effects
				(font
					(size 1.27 1.27)
					(thickness 0.15)
				)
			)
		)
		(property "Author" "Antmicro"
			(at 625.5 319.02 0)
			(layer "B.Fab")
			(hide yes)
			(effects
				(font
					(size 1 1)
					(thickness 0.15)
				)
				(justify mirror)
			)
		)
		(property "License" "Apache-2.0"
			(at 625.5 319.02 0)
			(layer "B.Fab")
			(hide yes)
			(effects
				(font
					(size 1 1)
					(thickness 0.15)
				)
				(justify mirror)
			)
		)
		(property "MPN" "ESD204DQAR"
			(at 625.5 319.02 0)
			(layer "B.Fab")
			(hide yes)
			(effects
				(font
					(size 1 1)
					(thickness 0.15)
				)
				(justify mirror)
			)
		)
		(property "Manufacturer" "Texas Instruments"
			(at 625.5 319.02 0)
			(layer "B.Fab")
			(hide yes)
			(effects
				(font
					(size 1 1)
					(thickness 0.15)
				)
				(justify mirror)
			)
		)
		(sheetname "Backplane")
		(sheetfile "backplane.kicad_sch")
		(attr smd)
		(fp_line
			(start -0.5 1.401)
			(end 0.498 1.401)
			(stroke
				(width 0.15)
				(type solid)
			)
			(layer "B.SilkS")
		)
		(fp_line
			(start -0.5 -1.398)
			(end 0.498 -1.398)
			(stroke
				(width 0.15)
				(type solid)
			)
			(layer "B.SilkS")
		)
		(fp_circle
			(center -0.68 1.27)
			(end -0.63 1.27)
			(stroke
				(width 0.15)
				(type solid)
			)
			(fill yes)
			(layer "B.SilkS")
		)
		(fp_rect
			(start -0.8 1.5)
			(end 0.8 -1.499)
			(stroke
				(width 0.05)
				(type solid)
			)
			(fill no)
			(layer "B.CrtYd")
		)
		(fp_line
			(start 0.498 -1.249)
			(end 0.498 1.25)
			(stroke
				(width 0.15)
				(type solid)
			)
			(layer "B.Fab")
		)
		(fp_line
			(start 0.498 -1.249)
			(end -0.5 -1.249)
			(stroke
				(width 0.15)
				(type solid)
			)
			(layer "B.Fab")
		)
		(fp_line
			(start -0.25 1.25)
			(end 0.498 1.25)
			(stroke
				(width 0.15)
				(type solid)
			)
			(layer "B.Fab")
		)
		(fp_line
			(start -0.5 1)
			(end -0.25 1.25)
			(stroke
				(width 0.15)
				(type solid)
			)
			(layer "B.Fab")
		)
		(fp_line
			(start -0.5 -1.249)
			(end -0.5 1)
			(stroke
				(width 0.15)
				(type solid)
			)
			(layer "B.Fab")
		)
		(pad "1" smd roundrect
			(at -0.387 1 270)
			(size 0.25 0.55)
			(layers "B.Cu" "B.Mask" "B.Paste")
			(roundrect_rratio 0.25)
			(net 866 "/Backplane/PCIe_{x2}.TX0+")
			(pintype "passive")
			(teardrops
				(best_length_ratio 0.2)
				(max_length 1)
				(best_width_ratio 0.9)
				(max_width 2)
				(curved_edges yes)
				(filter_ratio 0.9)
				(enabled yes)
				(allow_two_segments yes)
				(prefer_zone_connections yes)
			)
		)
		(pad "2" smd roundrect
			(at -0.387 0.5 270)
			(size 0.25 0.55)
			(layers "B.Cu" "B.Mask" "B.Paste")
			(roundrect_rratio 0.25)
			(net 867 "/Backplane/PCIe_{x2}.TX0-")
			(pintype "passive")
			(teardrops
				(best_length_ratio 0.2)
				(max_length 1)
				(best_width_ratio 0.9)
				(max_width 2)
				(curved_edges yes)
				(filter_ratio 0.9)
				(enabled yes)
				(allow_two_segments yes)
				(prefer_zone_connections yes)
			)
		)
		(pad "3" smd roundrect
			(at -0.387 0 270)
			(size 0.4 0.55)
			(layers "B.Cu" "B.Mask" "B.Paste")
			(roundrect_rratio 0.25)
			(net 1 "GND")
			(pintype "power_in")
			(teardrops
				(best_length_ratio 0.2)
				(max_length 1)
				(best_width_ratio 0.9)
				(max_width 2)
				(curved_edges yes)
				(filter_ratio 0.9)
				(enabled yes)
				(allow_two_segments yes)
				(prefer_zone_connections yes)
			)
		)
		(pad "4" smd roundrect
			(at -0.387 -0.498 270)
			(size 0.25 0.55)
			(layers "B.Cu" "B.Mask" "B.Paste")
			(roundrect_rratio 0.25)
			(net 868 "/Backplane/PCIe_{x2}.TX1+")
			(pintype "passive")
			(teardrops
				(best_length_ratio 0.2)
				(max_length 1)
				(best_width_ratio 0.9)
				(max_width 2)
				(curved_edges yes)
				(filter_ratio 0.9)
				(enabled yes)
				(allow_two_segments yes)
				(prefer_zone_connections yes)
			)
		)
		(pad "5" smd roundrect
			(at -0.387 -0.998 270)
			(size 0.25 0.55)
			(layers "B.Cu" "B.Mask" "B.Paste")
			(roundrect_rratio 0.25)
			(net 869 "/Backplane/PCIe_{x2}.TX1-")
			(pintype "passive")
			(teardrops
				(best_length_ratio 0.2)
				(max_length 1)
				(best_width_ratio 0.9)
				(max_width 2)
				(curved_edges yes)
				(filter_ratio 0.9)
				(enabled yes)
				(allow_two_segments yes)
				(prefer_zone_connections yes)
			)
		)
		(pad "6" smd roundrect
			(at 0.385 -0.998 270)
			(size 0.25 0.55)
			(layers "B.Cu" "B.Mask" "B.Paste")
			(roundrect_rratio 0.25)
			(net 869 "/Backplane/PCIe_{x2}.TX1-")
			(pintype "passive")
			(teardrops
				(best_length_ratio 0.2)
				(max_length 1)
				(best_width_ratio 0.9)
				(max_width 2)
				(curved_edges yes)
				(filter_ratio 0.9)
				(enabled yes)
				(allow_two_segments yes)
				(prefer_zone_connections yes)
			)
		)
		(pad "7" smd roundrect
			(at 0.385 -0.498 270)
			(size 0.25 0.55)
			(layers "B.Cu" "B.Mask" "B.Paste")
			(roundrect_rratio 0.25)
			(net 868 "/Backplane/PCIe_{x2}.TX1+")
			(pintype "passive")
			(teardrops
				(best_length_ratio 0.2)
				(max_length 1)
				(best_width_ratio 0.9)
				(max_width 2)
				(curved_edges yes)
				(filter_ratio 0.9)
				(enabled yes)
				(allow_two_segments yes)
				(prefer_zone_connections yes)
			)
		)
		(pad "8" smd roundrect
			(at 0.385 0 270)
			(size 0.4 0.55)
			(layers "B.Cu" "B.Mask" "B.Paste")
			(roundrect_rratio 0.25)
			(net 1 "GND")
			(pintype "passive")
			(teardrops
				(best_length_ratio 0.2)
				(max_length 1)
				(best_width_ratio 0.9)
				(max_width 2)
				(curved_edges yes)
				(filter_ratio 0.9)
				(enabled yes)
				(allow_two_segments yes)
				(prefer_zone_connections yes)
			)
		)
		(pad "9" smd roundrect
			(at 0.385 0.5 270)
			(size 0.25 0.55)
			(layers "B.Cu" "B.Mask" "B.Paste")
			(roundrect_rratio 0.25)
			(net 867 "/Backplane/PCIe_{x2}.TX0-")
			(pintype "passive")
			(teardrops
				(best_length_ratio 0.2)
				(max_length 1)
				(best_width_ratio 0.9)
				(max_width 2)
				(curved_edges yes)
				(filter_ratio 0.9)
				(enabled yes)
				(allow_two_segments yes)
				(prefer_zone_connections yes)
			)
		)
		(pad "10" smd roundrect
			(at 0.385 1 270)
			(size 0.25 0.55)
			(layers "B.Cu" "B.Mask" "B.Paste")
			(roundrect_rratio 0.25)
			(net 866 "/Backplane/PCIe_{x2}.TX0+")
			(pintype "passive")
			(teardrops
				(best_length_ratio 0.2)
				(max_length 1)
				(best_width_ratio 0.9)
				(max_width 2)
				(curved_edges yes)
				(filter_ratio 0.9)
				(enabled yes)
				(allow_two_segments yes)
				(prefer_zone_connections yes)
			)
		)
	)
	(footprint "antmicro-footprints:C_0603_1608Metric"
		(layer "B.Cu")
		(at 104.65 168.76 180)
		(descr "Capacitor SMD 0603")
		(tags "capacitor 0603")
		(property "Reference" "C37"
			(at -3.29 -0.14 0)
			(layer "B.SilkS")
			(effects
				(font
					(size 0.7 0.7)
					(thickness 0.15)
				)
				(justify left bottom mirror)
			)
		)
		(property "Value" "C_22u_16V_0603"
			(at -1.42757 -1.770288 0)
			(layer "B.Fab")
			(effects
				(font
					(size 0.7 0.7)
					(thickness 0.15)
				)
				(justify left bottom mirror)
			)
		)
		(property "Datasheet" "https://product.samsungsem.com/mlcc/CL10A226MO7JZN.do"
			(at 0 0 180)
			(layer "F.Fab")
			(hide yes)
			(effects
				(font
					(size 1.27 1.27)
					(thickness 0.15)
				)
			)
		)
		(property "Author" "Antmicro"
			(at 209.3 337.52 0)
			(layer "B.Fab")
			(hide yes)
			(effects
				(font
					(size 1 1)
					(thickness 0.15)
				)
				(justify mirror)
			)
		)
		(property "Dielectric" ""
			(at 209.3 337.52 0)
			(layer "B.Fab")
			(hide yes)
			(effects
				(font
					(size 1 1)
					(thickness 0.15)
				)
				(justify mirror)
			)
		)
		(property "License" "Apache-2.0"
			(at 209.3 337.52 0)
			(layer "B.Fab")
			(hide yes)
			(effects
				(font
					(size 1 1)
					(thickness 0.15)
				)
				(justify mirror)
			)
		)
		(property "MPN" "CL10A226MO7JZNC"
			(at 209.3 337.52 0)
			(layer "B.Fab")
			(hide yes)
			(effects
				(font
					(size 1 1)
					(thickness 0.15)
				)
				(justify mirror)
			)
		)
		(property "Manufacturer" "Samsung Electro-Mechanics"
			(at 209.3 337.52 0)
			(layer "B.Fab")
			(hide yes)
			(effects
				(font
					(size 1 1)
					(thickness 0.15)
				)
				(justify mirror)
			)
		)
		(property "Public" "False"
			(at 209.3 337.52 0)
			(layer "B.Fab")
			(hide yes)
			(effects
				(font
					(size 1 1)
					(thickness 0.15)
				)
				(justify mirror)
			)
		)
		(property "Val" "22u"
			(at 209.3 337.52 0)
			(layer "B.Fab")
			(hide yes)
			(effects
				(font
					(size 1 1)
					(thickness 0.15)
				)
				(justify mirror)
			)
		)
		(property "Voltage" "16V"
			(at 209.3 337.52 0)
			(layer "B.Fab")
			(hide yes)
			(effects
				(font
					(size 1 1)
					(thickness 0.15)
				)
				(justify mirror)
			)
		)
		(sheetname "OCuLink")
		(sheetfile "oculink.kicad_sch")
		(attr smd)
		(fp_line
			(start 0.15 0.4)
			(end -0.15 0.4)
			(stroke
				(width 0.15)
				(type solid)
			)
			(layer "B.SilkS")
		)
		(fp_line
			(start 0.15 -0.4)
			(end -0.15 -0.4)
			(stroke
				(width 0.15)
				(type solid)
			)
			(layer "B.SilkS")
		)
		(fp_rect
			(start -1.25 0.65)
			(end 1.25 -0.65)
			(stroke
				(width 0.05)
				(type solid)
			)
			(fill no)
			(layer "B.CrtYd")
		)
		(fp_rect
			(start -0.8 0.4)
			(end 0.8 -0.4)
			(stroke
				(width 0.15)
				(type solid)
			)
			(fill no)
			(layer "B.Fab")
		)
		(pad "1" smd roundrect
			(at -0.7 0 180)
			(size 0.8 1)
			(layers "B.Cu" "B.Mask" "B.Paste")
			(roundrect_rratio 0.2)
			(net 1 "GND")
			(pintype "passive")
			(teardrops
				(best_length_ratio 0.2)
				(max_length 1)
				(best_width_ratio 0.9)
				(max_width 2)
				(curved_edges yes)
				(filter_ratio 0.9)
				(enabled yes)
				(allow_two_segments yes)
				(prefer_zone_connections yes)
			)
		)
		(pad "2" smd roundrect
			(at 0.7 0 180)
			(size 0.8 1)
			(layers "B.Cu" "B.Mask" "B.Paste")
			(roundrect_rratio 0.2)
			(net 60 "/OCuLink/V_{ACT_RX}0")
			(pintype "passive")
			(teardrops
				(best_length_ratio 0.2)
				(max_length 1)
				(best_width_ratio 0.9)
				(max_width 2)
				(curved_edges yes)
				(filter_ratio 0.9)
				(enabled yes)
				(allow_two_segments yes)
				(prefer_zone_connections yes)
			)
		)
	)
	(footprint "antmicro-footprints:TP_SMD_0.75mm"
		(layer "B.Cu")
		(at 139.95 167.21 180)
		(property "Reference" "TP6"
			(at 0.4 -0.5 0)
			(layer "B.SilkS")
			(effects
				(font
					(size 0.7 0.7)
					(thickness 0.15)
				)
				(justify left bottom mirror)
			)
		)
		(property "Value" "TP_0.75mm_SMD"
			(at 0 -1.2 0)
			(layer "B.Fab")
			(effects
				(font
					(size 0.7 0.7)
					(thickness 0.15)
				)
				(justify left bottom mirror)
			)
		)
		(property "Author" "Antmicro"
			(at 279.9 334.42 0)
			(layer "B.Fab")
			(hide yes)
			(effects
				(font
					(size 1 1)
					(thickness 0.15)
				)
				(justify mirror)
			)
		)
		(property "License" "Apache-2.0"
			(at 279.9 334.42 0)
			(layer "B.Fab")
			(hide yes)
			(effects
				(font
					(size 1 1)
					(thickness 0.15)
				)
				(justify mirror)
			)
		)
		(property "MPN" ""
			(at 279.9 334.42 0)
			(layer "B.Fab")
			(hide yes)
			(effects
				(font
					(size 1 1)
					(thickness 0.15)
				)
				(justify mirror)
			)
		)
		(property "Manufacturer" ""
			(at 279.9 334.42 0)
			(layer "B.Fab")
			(hide yes)
			(effects
				(font
					(size 1 1)
					(thickness 0.15)
				)
				(justify mirror)
			)
		)
		(property "Public" "False"
			(at 279.9 334.42 0)
			(layer "B.Fab")
			(hide yes)
			(effects
				(font
					(size 1 1)
					(thickness 0.15)
				)
				(justify mirror)
			)
		)
		(sheetname "2xSFP+")
		(sheetfile "2xSFP+.kicad_sch")
		(attr exclude_from_pos_files exclude_from_bom)
		(fp_circle
			(center 0 0)
			(end 0.475 0)
			(stroke
				(width 0.05)
				(type default)
			)
			(fill no)
			(layer "B.CrtYd")
		)
		(pad "1" smd circle
			(at 0 0 180)
			(size 0.75 0.75)
			(layers "B.Cu" "B.Mask")
			(net 896 "Net-(J2B-RX_{LOS})")
			(pinfunction "1")
			(pintype "passive")
			(teardrops
				(best_length_ratio 0.4)
				(max_length 1)
				(best_width_ratio 0.9)
				(max_width 2)
				(curved_edges yes)
				(filter_ratio 0.9)
				(enabled yes)
				(allow_two_segments yes)
				(prefer_zone_connections yes)
			)
		)
	)
	(footprint "antmicro-footprints:C_0402_1005Metric"
		(layer "B.Cu")
		(at 104.28 82.42 -90)
		(descr "Capacitor SMD 0402")
		(tags "capacitor SMD 0402")
		(property "Reference" "C29"
			(at -1.11 0.48 90)
			(layer "B.SilkS")
			(effects
				(font
					(size 0.7 0.7)
					(thickness 0.15)
				)
				(justify left bottom mirror)
			)
		)
		(property "Value" "C_100n_0402"
			(at -1.022927 -2.155213 90)
			(layer "B.Fab")
			(effects
				(font
					(size 0.7 0.7)
					(thickness 0.15)
				)
				(justify left bottom mirror)
			)
		)
		(property "Datasheet" "https://www.murata.com/products/productdetail?partno=GRM155R61H104KE14%23"
			(at 0 0 270)
			(layer "F.Fab")
			(hide yes)
			(effects
				(font
					(size 1.27 1.27)
					(thickness 0.15)
				)
			)
		)
		(property "Author" "Antmicro"
			(at 21.86 186.7 0)
			(layer "B.Fab")
			(hide yes)
			(effects
				(font
					(size 1 1)
					(thickness 0.15)
				)
				(justify mirror)
			)
		)
		(property "Dielectric" "X5R"
			(at 21.86 186.7 0)
			(layer "B.Fab")
			(hide yes)
			(effects
				(font
					(size 1 1)
					(thickness 0.15)
				)
				(justify mirror)
			)
		)
		(property "License" "Apache-2.0"
			(at 21.86 186.7 0)
			(layer "B.Fab")
			(hide yes)
			(effects
				(font
					(size 1 1)
					(thickness 0.15)
				)
				(justify mirror)
			)
		)
		(property "MPN" "GRM155R61H104KE14D"
			(at 21.86 186.7 0)
			(layer "B.Fab")
			(hide yes)
			(effects
				(font
					(size 1 1)
					(thickness 0.15)
				)
				(justify mirror)
			)
		)
		(property "Manufacturer" "Murata"
			(at 21.86 186.7 0)
			(layer "B.Fab")
			(hide yes)
			(effects
				(font
					(size 1 1)
					(thickness 0.15)
				)
				(justify mirror)
			)
		)
		(property "Public" "False"
			(at 21.86 186.7 0)
			(layer "B.Fab")
			(hide yes)
			(effects
				(font
					(size 1 1)
					(thickness 0.15)
				)
				(justify mirror)
			)
		)
		(property "Val" "100n"
			(at 21.86 186.7 0)
			(layer "B.Fab")
			(hide yes)
			(effects
				(font
					(size 1 1)
					(thickness 0.15)
				)
				(justify mirror)
			)
		)
		(property "Voltage" "50V"
			(at 21.86 186.7 0)
			(layer "B.Fab")
			(hide yes)
			(effects
				(font
					(size 1 1)
					(thickness 0.15)
				)
				(justify mirror)
			)
		)
		(sheetname "USB-C console")
		(sheetfile "usb-c_console.kicad_sch")
		(attr smd)
		(fp_rect
			(start -0.925 0.47)
			(end 0.925 -0.47)
			(stroke
				(width 0.05)
				(type default)
			)
			(fill no)
			(layer "B.CrtYd")
		)
		(fp_line
			(start -0.494 0.25)
			(end -0.494 -0.248)
			(stroke
				(width 0.15)
				(type solid)
			)
			(layer "B.Fab")
		)
		(fp_line
			(start 0.504 0.25)
			(end -0.494 0.25)
			(stroke
				(width 0.15)
				(type solid)
			)
			(layer "B.Fab")
		)
		(fp_line
			(start -0.494 -0.248)
			(end 0.504 -0.248)
			(stroke
				(width 0.15)
				(type solid)
			)
			(layer "B.Fab")
		)
		(fp_line
			(start 0.504 -0.248)
			(end 0.504 0.25)
			(stroke
				(width 0.15)
				(type solid)
			)
			(layer "B.Fab")
		)
		(pad "1" smd roundrect
			(at -0.48 0 270)
			(size 0.59 0.64)
			(layers "B.Cu" "B.Mask" "B.Paste")
			(roundrect_rratio 0.25)
			(net 54 "/USB-C console/SH")
			(pintype "passive")
			(teardrops
				(best_length_ratio 0.2)
				(max_length 1)
				(best_width_ratio 0.9)
				(max_width 2)
				(curved_edges yes)
				(filter_ratio 0.9)
				(enabled yes)
				(allow_two_segments yes)
				(prefer_zone_connections yes)
			)
		)
		(pad "2" smd roundrect
			(at 0.48 0 270)
			(size 0.59 0.64)
			(layers "B.Cu" "B.Mask" "B.Paste")
			(roundrect_rratio 0.25)
			(net 1 "GND")
			(pintype "passive")
			(teardrops
				(best_length_ratio 0.2)
				(max_length 1)
				(best_width_ratio 0.9)
				(max_width 2)
				(curved_edges yes)
				(filter_ratio 0.9)
				(enabled yes)
				(allow_two_segments yes)
				(prefer_zone_connections yes)
			)
		)
	)
	(footprint "antmicro-footprints:C_0402_1005Metric"
		(layer "B.Cu")
		(at 137 163.76)
		(descr "Capacitor SMD 0402")
		(tags "capacitor SMD 0402")
		(property "Reference" "C27"
			(at -3.05 0.45 0)
			(layer "B.SilkS")
			(effects
				(font
					(size 0.7 0.7)
					(thickness 0.15)
				)
				(justify right bottom mirror)
			)
		)
		(property "Value" "C_100n_0402"
			(at -1.022927 -2.155213 0)
			(layer "B.Fab")
			(effects
				(font
					(size 0.7 0.7)
					(thickness 0.15)
				)
				(justify right bottom mirror)
			)
		)
		(property "Datasheet" "https://www.murata.com/products/productdetail?partno=GRM155R61H104KE14%23"
			(at 0 0 0)
			(layer "F.Fab")
			(hide yes)
			(effects
				(font
					(size 1.27 1.27)
					(thickness 0.15)
				)
			)
		)
		(property "Author" "Antmicro"
			(at 0 0 0)
			(layer "B.Fab")
			(hide yes)
			(effects
				(font
					(size 1 1)
					(thickness 0.15)
				)
				(justify mirror)
			)
		)
		(property "Dielectric" "X5R"
			(at 0 0 0)
			(layer "B.Fab")
			(hide yes)
			(effects
				(font
					(size 1 1)
					(thickness 0.15)
				)
				(justify mirror)
			)
		)
		(property "License" "Apache-2.0"
			(at 0 0 0)
			(layer "B.Fab")
			(hide yes)
			(effects
				(font
					(size 1 1)
					(thickness 0.15)
				)
				(justify mirror)
			)
		)
		(property "MPN" "GRM155R61H104KE14D"
			(at 0 0 0)
			(layer "B.Fab")
			(hide yes)
			(effects
				(font
					(size 1 1)
					(thickness 0.15)
				)
				(justify mirror)
			)
		)
		(property "Manufacturer" "Murata"
			(at 0 0 0)
			(layer "B.Fab")
			(hide yes)
			(effects
				(font
					(size 1 1)
					(thickness 0.15)
				)
				(justify mirror)
			)
		)
		(property "Public" "False"
			(at 0 0 0)
			(layer "B.Fab")
			(hide yes)
			(effects
				(font
					(size 1 1)
					(thickness 0.15)
				)
				(justify mirror)
			)
		)
		(property "Val" "100n"
			(at 0 0 0)
			(layer "B.Fab")
			(hide yes)
			(effects
				(font
					(size 1 1)
					(thickness 0.15)
				)
				(justify mirror)
			)
		)
		(property "Voltage" "50V"
			(at 0 0 0)
			(layer "B.Fab")
			(hide yes)
			(effects
				(font
					(size 1 1)
					(thickness 0.15)
				)
				(justify mirror)
			)
		)
		(sheetname "2xSFP+")
		(sheetfile "2xSFP+.kicad_sch")
		(attr smd)
		(fp_rect
			(start -0.925 0.47)
			(end 0.925 -0.47)
			(stroke
				(width 0.05)
				(type default)
			)
			(fill no)
			(layer "B.CrtYd")
		)
		(fp_line
			(start -0.494 -0.248)
			(end 0.504 -0.248)
			(stroke
				(width 0.15)
				(type solid)
			)
			(layer "B.Fab")
		)
		(fp_line
			(start -0.494 0.25)
			(end -0.494 -0.248)
			(stroke
				(width 0.15)
				(type solid)
			)
			(layer "B.Fab")
		)
		(fp_line
			(start 0.504 -0.248)
			(end 0.504 0.25)
			(stroke
				(width 0.15)
				(type solid)
			)
			(layer "B.Fab")
		)
		(fp_line
			(start 0.504 0.25)
			(end -0.494 0.25)
			(stroke
				(width 0.15)
				(type solid)
			)
			(layer "B.Fab")
		)
		(pad "1" smd roundrect
			(at -0.48 0)
			(size 0.59 0.64)
			(layers "B.Cu" "B.Mask" "B.Paste")
			(roundrect_rratio 0.25)
			(net 1 "GND")
			(pintype "passive")
			(teardrops
				(best_length_ratio 0.2)
				(max_length 1)
				(best_width_ratio 0.9)
				(max_width 2)
				(curved_edges yes)
				(filter_ratio 0.9)
				(enabled yes)
				(allow_two_segments yes)
				(prefer_zone_connections yes)
			)
		)
		(pad "2" smd roundrect
			(at 0.48 0)
			(size 0.59 0.64)
			(layers "B.Cu" "B.Mask" "B.Paste")
			(roundrect_rratio 0.25)
			(net 2 "+3V3")
			(pintype "passive")
			(teardrops
				(best_length_ratio 0.2)
				(max_length 1)
				(best_width_ratio 0.9)
				(max_width 2)
				(curved_edges yes)
				(filter_ratio 0.9)
				(enabled yes)
				(allow_two_segments yes)
				(prefer_zone_connections yes)
			)
		)
	)
	(footprint "antmicro-footprints:C_0402_1005Metric"
		(layer "B.Cu")
		(at 215.986207 126.054416 90)
		(descr "Capacitor SMD 0402")
		(tags "capacitor SMD 0402")
		(property "Reference" "C104"
			(at -3.655584 0.413793 90)
			(layer "B.SilkS")
			(effects
				(font
					(size 0.7 0.7)
					(thickness 0.15)
				)
				(justify right bottom mirror)
			)
		)
		(property "Value" "C_100n_0402"
			(at -1.022927 -2.155213 90)
			(layer "B.Fab")
			(effects
				(font
					(size 0.7 0.7)
					(thickness 0.15)
				)
				(justify right bottom mirror)
			)
		)
		(property "Datasheet" "https://www.murata.com/products/productdetail?partno=GRM155R61H104KE14%23"
			(at 0 0 90)
			(layer "F.Fab")
			(hide yes)
			(effects
				(font
					(size 1.27 1.27)
					(thickness 0.15)
				)
			)
		)
		(property "Author" "Antmicro"
			(at 342.040623 -89.931791 0)
			(layer "B.Fab")
			(hide yes)
			(effects
				(font
					(size 1 1)
					(thickness 0.15)
				)
				(justify mirror)
			)
		)
		(property "Dielectric" "X5R"
			(at 342.040623 -89.931791 0)
			(layer "B.Fab")
			(hide yes)
			(effects
				(font
					(size 1 1)
					(thickness 0.15)
				)
				(justify mirror)
			)
		)
		(property "License" "Apache-2.0"
			(at 342.040623 -89.931791 0)
			(layer "B.Fab")
			(hide yes)
			(effects
				(font
					(size 1 1)
					(thickness 0.15)
				)
				(justify mirror)
			)
		)
		(property "MPN" "GRM155R61H104KE14D"
			(at 342.040623 -89.931791 0)
			(layer "B.Fab")
			(hide yes)
			(effects
				(font
					(size 1 1)
					(thickness 0.15)
				)
				(justify mirror)
			)
		)
		(property "Manufacturer" "Murata"
			(at 342.040623 -89.931791 0)
			(layer "B.Fab")
			(hide yes)
			(effects
				(font
					(size 1 1)
					(thickness 0.15)
				)
				(justify mirror)
			)
		)
		(property "Public" "False"
			(at 342.040623 -89.931791 0)
			(layer "B.Fab")
			(hide yes)
			(effects
				(font
					(size 1 1)
					(thickness 0.15)
				)
				(justify mirror)
			)
		)
		(property "Val" "100n"
			(at 342.040623 -89.931791 0)
			(layer "B.Fab")
			(hide yes)
			(effects
				(font
					(size 1 1)
					(thickness 0.15)
				)
				(justify mirror)
			)
		)
		(property "Voltage" "50V"
			(at 342.040623 -89.931791 0)
			(layer "B.Fab")
			(hide yes)
			(effects
				(font
					(size 1 1)
					(thickness 0.15)
				)
				(justify mirror)
			)
		)
		(sheetname "PCIe misc")
		(sheetfile "pcie_misc.kicad_sch")
		(attr smd)
		(fp_rect
			(start -0.925 0.47)
			(end 0.925 -0.47)
			(stroke
				(width 0.05)
				(type default)
			)
			(fill no)
			(layer "B.CrtYd")
		)
		(fp_line
			(start 0.504 -0.248)
			(end 0.504 0.25)
			(stroke
				(width 0.15)
				(type solid)
			)
			(layer "B.Fab")
		)
		(fp_line
			(start -0.494 -0.248)
			(end 0.504 -0.248)
			(stroke
				(width 0.15)
				(type solid)
			)
			(layer "B.Fab")
		)
		(fp_line
			(start 0.504 0.25)
			(end -0.494 0.25)
			(stroke
				(width 0.15)
				(type solid)
			)
			(layer "B.Fab")
		)
		(fp_line
			(start -0.494 0.25)
			(end -0.494 -0.248)
			(stroke
				(width 0.15)
				(type solid)
			)
			(layer "B.Fab")
		)
		(pad "1" smd roundrect
			(at -0.48 0 90)
			(size 0.59 0.64)
			(layers "B.Cu" "B.Mask" "B.Paste")
			(roundrect_rratio 0.25)
			(net 1 "GND")
			(pintype "passive")
			(teardrops
				(best_length_ratio 0.2)
				(max_length 1)
				(best_width_ratio 0.9)
				(max_width 2)
				(curved_edges yes)
				(filter_ratio 0.9)
				(enabled yes)
				(allow_two_segments yes)
				(prefer_zone_connections yes)
			)
		)
		(pad "2" smd roundrect
			(at 0.48 0 90)
			(size 0.59 0.64)
			(layers "B.Cu" "B.Mask" "B.Paste")
			(roundrect_rratio 0.25)
			(net 2 "+3V3")
			(pintype "passive")
			(teardrops
				(best_length_ratio 0.2)
				(max_length 1)
				(best_width_ratio 0.9)
				(max_width 2)
				(curved_edges yes)
				(filter_ratio 0.9)
				(enabled yes)
				(allow_two_segments yes)
				(prefer_zone_connections yes)
			)
		)
	)
	(footprint "antmicro-footprints:R_0402_1005Metric"
		(layer "B.Cu")
		(at 100.25 95.51 180)
		(descr "Resistor SMD 0402")
		(tags "resistor SMD 0402")
		(property "Reference" "R11"
			(at -1.075 0.49 0)
			(layer "B.SilkS")
			(effects
				(font
					(size 0.7 0.7)
					(thickness 0.15)
				)
				(justify left bottom mirror)
			)
		)
		(property "Value" "R_330R_0402"
			(at -1.011843 -1.772047 0)
			(layer "B.Fab")
			(effects
				(font
					(size 0.7 0.7)
					(thickness 0.15)
				)
				(justify left bottom mirror)
			)
		)
		(property "Datasheet" "https://www.bourns.com/docs/product-datasheets/cr.pdf"
			(at 0 0 180)
			(layer "F.Fab")
			(hide yes)
			(effects
				(font
					(size 1.27 1.27)
					(thickness 0.15)
				)
			)
		)
		(property "Author" "Antmicro"
			(at 200.5 191.02 0)
			(layer "B.Fab")
			(hide yes)
			(effects
				(font
					(size 1 1)
					(thickness 0.15)
				)
				(justify mirror)
			)
		)
		(property "License" "Apache-2.0"
			(at 200.5 191.02 0)
			(layer "B.Fab")
			(hide yes)
			(effects
				(font
					(size 1 1)
					(thickness 0.15)
				)
				(justify mirror)
			)
		)
		(property "MPN" "CR0402-FX-3300GLF"
			(at 200.5 191.02 0)
			(layer "B.Fab")
			(hide yes)
			(effects
				(font
					(size 1 1)
					(thickness 0.15)
				)
				(justify mirror)
			)
		)
		(property "Manufacturer" "Bourns"
			(at 200.5 191.02 0)
			(layer "B.Fab")
			(hide yes)
			(effects
				(font
					(size 1 1)
					(thickness 0.15)
				)
				(justify mirror)
			)
		)
		(property "Public" "False"
			(at 200.5 191.02 0)
			(layer "B.Fab")
			(hide yes)
			(effects
				(font
					(size 1 1)
					(thickness 0.15)
				)
				(justify mirror)
			)
		)
		(property "Tolerance" "1%"
			(at 200.5 191.02 0)
			(layer "B.Fab")
			(hide yes)
			(effects
				(font
					(size 1 1)
					(thickness 0.15)
				)
				(justify mirror)
			)
		)
		(property "Val" "330R"
			(at 200.5 191.02 0)
			(layer "B.Fab")
			(hide yes)
			(effects
				(font
					(size 1 1)
					(thickness 0.15)
				)
				(justify mirror)
			)
		)
		(sheetname "2xUSB3.0+RJ45")
		(sheetfile "usb3+rj45.kicad_sch")
		(attr smd)
		(fp_rect
			(start -0.925 0.47)
			(end 0.925 -0.47)
			(stroke
				(width 0.05)
				(type default)
			)
			(fill no)
			(layer "B.CrtYd")
		)
		(fp_rect
			(start -0.5 0.25)
			(end 0.5 -0.25)
			(stroke
				(width 0.15)
				(type solid)
			)
			(fill no)
			(layer "B.Fab")
		)
		(pad "1" smd roundrect
			(at -0.48 0 180)
			(size 0.59 0.64)
			(layers "B.Cu" "B.Mask" "B.Paste")
			(roundrect_rratio 0.25)
			(net 579 "/2xUSB3.0+RJ45/SH")
			(pintype "passive")
			(teardrops
				(best_length_ratio 0.2)
				(max_length 1)
				(best_width_ratio 0.9)
				(max_width 2)
				(curved_edges yes)
				(filter_ratio 0.9)
				(enabled yes)
				(allow_two_segments yes)
				(prefer_zone_connections yes)
			)
		)
		(pad "2" smd roundrect
			(at 0.48 0 180)
			(size 0.59 0.64)
			(layers "B.Cu" "B.Mask" "B.Paste")
			(roundrect_rratio 0.25)
			(net 1 "GND")
			(pintype "passive")
			(teardrops
				(best_length_ratio 0.2)
				(max_length 1)
				(best_width_ratio 0.9)
				(max_width 2)
				(curved_edges yes)
				(filter_ratio 0.9)
				(enabled yes)
				(allow_two_segments yes)
				(prefer_zone_connections yes)
			)
		)
	)
	(footprint "antmicro-footprints:R_0402_1005Metric"
		(layer "B.Cu")
		(at 128.79 136.06)
		(descr "Resistor SMD 0402")
		(tags "resistor SMD 0402")
		(property "Reference" "R300"
			(at -1.49 -0.5 0)
			(layer "B.SilkS")
			(effects
				(font
					(size 0.7 0.7)
					(thickness 0.15)
				)
				(justify right bottom mirror)
			)
		)
		(property "Value" "R_10k_0402"
			(at -1.011843 -1.772047 0)
			(layer "B.Fab")
			(effects
				(font
					(size 0.7 0.7)
					(thickness 0.15)
				)
				(justify right bottom mirror)
			)
		)
		(property "Datasheet" "https://www.bourns.com/docs/product-datasheets/cr.pdf"
			(at 0 0 0)
			(layer "F.Fab")
			(hide yes)
			(effects
				(font
					(size 1.27 1.27)
					(thickness 0.15)
				)
			)
		)
		(property "Author" "Antmicro"
			(at 0 0 0)
			(layer "B.Fab")
			(hide yes)
			(effects
				(font
					(size 1 1)
					(thickness 0.15)
				)
				(justify mirror)
			)
		)
		(property "License" "Apache-2.0"
			(at 0 0 0)
			(layer "B.Fab")
			(hide yes)
			(effects
				(font
					(size 1 1)
					(thickness 0.15)
				)
				(justify mirror)
			)
		)
		(property "MPN" "CR0402-FX-1002GLF"
			(at 0 0 0)
			(layer "B.Fab")
			(hide yes)
			(effects
				(font
					(size 1 1)
					(thickness 0.15)
				)
				(justify mirror)
			)
		)
		(property "Manufacturer" "Bourns"
			(at 0 0 0)
			(layer "B.Fab")
			(hide yes)
			(effects
				(font
					(size 1 1)
					(thickness 0.15)
				)
				(justify mirror)
			)
		)
		(property "Public" "False"
			(at 0 0 0)
			(layer "B.Fab")
			(hide yes)
			(effects
				(font
					(size 1 1)
					(thickness 0.15)
				)
				(justify mirror)
			)
		)
		(property "Tolerance" "1%"
			(at 0 0 0)
			(layer "B.Fab")
			(hide yes)
			(effects
				(font
					(size 1 1)
					(thickness 0.15)
				)
				(justify mirror)
			)
		)
		(property "Val" "10k"
			(at 0 0 0)
			(layer "B.Fab")
			(hide yes)
			(effects
				(font
					(size 1 1)
					(thickness 0.15)
				)
				(justify mirror)
			)
		)
		(sheetname "KR to SFI #2")
		(sheetfile "kr_sfi.kicad_sch")
		(attr smd)
		(fp_rect
			(start -0.925 0.47)
			(end 0.925 -0.47)
			(stroke
				(width 0.05)
				(type default)
			)
			(fill no)
			(layer "B.CrtYd")
		)
		(fp_rect
			(start -0.5 0.25)
			(end 0.5 -0.25)
			(stroke
				(width 0.15)
				(type solid)
			)
			(fill no)
			(layer "B.Fab")
		)
		(pad "1" smd roundrect
			(at -0.48 0)
			(size 0.59 0.64)
			(layers "B.Cu" "B.Mask" "B.Paste")
			(roundrect_rratio 0.25)
			(net 1 "GND")
			(pintype "passive")
			(teardrops
				(best_length_ratio 0.2)
				(max_length 1)
				(best_width_ratio 0.9)
				(max_width 2)
				(curved_edges yes)
				(filter_ratio 0.9)
				(enabled yes)
				(allow_two_segments yes)
				(prefer_zone_connections yes)
			)
		)
		(pad "2" smd roundrect
			(at 0.48 0)
			(size 0.59 0.64)
			(layers "B.Cu" "B.Mask" "B.Paste")
			(roundrect_rratio 0.25)
			(net 680 "Net-(U45C-PRTAD3)")
			(pintype "passive")
			(teardrops
				(best_length_ratio 0.2)
				(max_length 1)
				(best_width_ratio 0.9)
				(max_width 2)
				(curved_edges yes)
				(filter_ratio 0.9)
				(enabled yes)
				(allow_two_segments yes)
				(prefer_zone_connections yes)
			)
		)
	)
	(footprint "antmicro-footprints:R_0402_1005Metric"
		(layer "B.Cu")
		(at 138.05 169.16 -90)
		(descr "Resistor SMD 0402")
		(tags "resistor SMD 0402")
		(property "Reference" "R59"
			(at -3.9 13.5 90)
			(layer "B.SilkS")
			(effects
				(font
					(size 0.7 0.7)
					(thickness 0.15)
				)
				(justify left bottom mirror)
			)
		)
		(property "Value" "R_0R_0402"
			(at -1.011843 -1.772047 90)
			(layer "B.Fab")
			(effects
				(font
					(size 0.7 0.7)
					(thickness 0.15)
				)
				(justify left bottom mirror)
			)
		)
		(property "Datasheet" "https://industrial.panasonic.com/cdbs/www-data/pdf/RDA0000/AOA0000C301.pdf"
			(at 0 0 270)
			(layer "F.Fab")
			(hide yes)
			(effects
				(font
					(size 1.27 1.27)
					(thickness 0.15)
				)
			)
		)
		(property "Author" "Antmicro"
			(at -31.11 307.21 0)
			(layer "B.Fab")
			(hide yes)
			(effects
				(font
					(size 1 1)
					(thickness 0.15)
				)
				(justify mirror)
			)
		)
		(property "Current" "1A"
			(at -31.11 307.21 0)
			(layer "B.Fab")
			(hide yes)
			(effects
				(font
					(size 1 1)
					(thickness 0.15)
				)
				(justify mirror)
			)
		)
		(property "License" "Apache-2.0"
			(at -31.11 307.21 0)
			(layer "B.Fab")
			(hide yes)
			(effects
				(font
					(size 1 1)
					(thickness 0.15)
				)
				(justify mirror)
			)
		)
		(property "MPN" "ERJ2GE0R00X"
			(at -31.11 307.21 0)
			(layer "B.Fab")
			(hide yes)
			(effects
				(font
					(size 1 1)
					(thickness 0.15)
				)
				(justify mirror)
			)
		)
		(property "Manufacturer" "Panasonic"
			(at -31.11 307.21 0)
			(layer "B.Fab")
			(hide yes)
			(effects
				(font
					(size 1 1)
					(thickness 0.15)
				)
				(justify mirror)
			)
		)
		(property "Public" "False"
			(at -31.11 307.21 0)
			(layer "B.Fab")
			(hide yes)
			(effects
				(font
					(size 1 1)
					(thickness 0.15)
				)
				(justify mirror)
			)
		)
		(property "Tolerance" ""
			(at -31.11 307.21 0)
			(layer "B.Fab")
			(hide yes)
			(effects
				(font
					(size 1 1)
					(thickness 0.15)
				)
				(justify mirror)
			)
		)
		(property "Val" "0R"
			(at -31.11 307.21 0)
			(layer "B.Fab")
			(hide yes)
			(effects
				(font
					(size 1 1)
					(thickness 0.15)
				)
				(justify mirror)
			)
		)
		(sheetname "2xSFP+")
		(sheetfile "2xSFP+.kicad_sch")
		(attr smd)
		(fp_rect
			(start -0.925 0.47)
			(end 0.925 -0.47)
			(stroke
				(width 0.05)
				(type default)
			)
			(fill no)
			(layer "B.CrtYd")
		)
		(fp_rect
			(start -0.5 0.25)
			(end 0.5 -0.25)
			(stroke
				(width 0.15)
				(type solid)
			)
			(fill no)
			(layer "B.Fab")
		)
		(pad "1" smd roundrect
			(at -0.48 0 270)
			(size 0.59 0.64)
			(layers "B.Cu" "B.Mask" "B.Paste")
			(roundrect_rratio 0.25)
			(net 893 "Net-(J2B-TX_{DISABLE})")
			(pintype "passive")
			(teardrops
				(best_length_ratio 0.2)
				(max_length 1)
				(best_width_ratio 0.9)
				(max_width 2)
				(curved_edges yes)
				(filter_ratio 0.9)
				(enabled yes)
				(allow_two_segments yes)
				(prefer_zone_connections yes)
			)
		)
		(pad "2" smd roundrect
			(at 0.48 0 270)
			(size 0.59 0.64)
			(layers "B.Cu" "B.Mask" "B.Paste")
			(roundrect_rratio 0.25)
			(net 1 "GND")
			(pintype "passive")
			(teardrops
				(best_length_ratio 0.2)
				(max_length 1)
				(best_width_ratio 0.9)
				(max_width 2)
				(curved_edges yes)
				(filter_ratio 0.9)
				(enabled yes)
				(allow_two_segments yes)
				(prefer_zone_connections yes)
			)
		)
	)
	(footprint "antmicro-footprints:TP_SMD_0.75mm"
		(layer "B.Cu")
		(at 221.18 127.15)
		(property "Reference" "TP48"
			(at 0.37 0.46 0)
			(layer "B.SilkS")
			(effects
				(font
					(size 0.7 0.7)
					(thickness 0.15)
				)
				(justify right bottom mirror)
			)
		)
		(property "Value" "TP_0.75mm_SMD"
			(at 0 -1.2 0)
			(layer "B.Fab")
			(effects
				(font
					(size 0.7 0.7)
					(thickness 0.15)
				)
				(justify right bottom mirror)
			)
		)
		(property "Author" "Antmicro"
			(at 0 0 0)
			(layer "B.Fab")
			(hide yes)
			(effects
				(font
					(size 1 1)
					(thickness 0.15)
				)
				(justify mirror)
			)
		)
		(property "License" "Apache-2.0"
			(at 0 0 0)
			(layer "B.Fab")
			(hide yes)
			(effects
				(font
					(size 1 1)
					(thickness 0.15)
				)
				(justify mirror)
			)
		)
		(property "MPN" ""
			(at 0 0 0)
			(layer "B.Fab")
			(hide yes)
			(effects
				(font
					(size 1 1)
					(thickness 0.15)
				)
				(justify mirror)
			)
		)
		(property "Manufacturer" ""
			(at 0 0 0)
			(layer "B.Fab")
			(hide yes)
			(effects
				(font
					(size 1 1)
					(thickness 0.15)
				)
				(justify mirror)
			)
		)
		(property "Public" "False"
			(at 0 0 0)
			(layer "B.Fab")
			(hide yes)
			(effects
				(font
					(size 1 1)
					(thickness 0.15)
				)
				(justify mirror)
			)
		)
		(sheetname "PCIe misc")
		(sheetfile "pcie_misc.kicad_sch")
		(attr exclude_from_pos_files exclude_from_bom)
		(fp_circle
			(center 0 0)
			(end 0.475 0)
			(stroke
				(width 0.05)
				(type default)
			)
			(fill no)
			(layer "B.CrtYd")
		)
		(pad "1" smd circle
			(at 0 0)
			(size 0.75 0.75)
			(layers "B.Cu" "B.Mask")
			(net 622 "/PCIe misc/DIF5-")
			(pinfunction "1")
			(pintype "passive")
			(teardrops
				(best_length_ratio 0.4)
				(max_length 1)
				(best_width_ratio 0.9)
				(max_width 2)
				(curved_edges yes)
				(filter_ratio 0.9)
				(enabled yes)
				(allow_two_segments yes)
				(prefer_zone_connections yes)
			)
		)
	)
	(footprint "antmicro-footprints:C_0402_1005Metric"
		(layer "B.Cu")
		(at 141.9 138.01)
		(descr "Capacitor SMD 0402")
		(tags "capacitor SMD 0402")
		(property "Reference" "C148"
			(at -1.25 1.4 0)
			(layer "B.SilkS")
			(effects
				(font
					(size 0.7 0.7)
					(thickness 0.15)
				)
				(justify right bottom mirror)
			)
		)
		(property "Value" "C_100n_0402"
			(at -1.022927 -2.155213 0)
			(layer "B.Fab")
			(effects
				(font
					(size 0.7 0.7)
					(thickness 0.15)
				)
				(justify right bottom mirror)
			)
		)
		(property "Datasheet" "https://www.murata.com/products/productdetail?partno=GRM155R61H104KE14%23"
			(at 0 0 0)
			(layer "F.Fab")
			(hide yes)
			(effects
				(font
					(size 1.27 1.27)
					(thickness 0.15)
				)
			)
		)
		(property "Author" "Antmicro"
			(at 0 0 0)
			(layer "B.Fab")
			(hide yes)
			(effects
				(font
					(size 1 1)
					(thickness 0.15)
				)
				(justify mirror)
			)
		)
		(property "Dielectric" "X5R"
			(at 0 0 0)
			(layer "B.Fab")
			(hide yes)
			(effects
				(font
					(size 1 1)
					(thickness 0.15)
				)
				(justify mirror)
			)
		)
		(property "License" "Apache-2.0"
			(at 0 0 0)
			(layer "B.Fab")
			(hide yes)
			(effects
				(font
					(size 1 1)
					(thickness 0.15)
				)
				(justify mirror)
			)
		)
		(property "MPN" "GRM155R61H104KE14D"
			(at 0 0 0)
			(layer "B.Fab")
			(hide yes)
			(effects
				(font
					(size 1 1)
					(thickness 0.15)
				)
				(justify mirror)
			)
		)
		(property "Manufacturer" "Murata"
			(at 0 0 0)
			(layer "B.Fab")
			(hide yes)
			(effects
				(font
					(size 1 1)
					(thickness 0.15)
				)
				(justify mirror)
			)
		)
		(property "Public" "False"
			(at 0 0 0)
			(layer "B.Fab")
			(hide yes)
			(effects
				(font
					(size 1 1)
					(thickness 0.15)
				)
				(justify mirror)
			)
		)
		(property "Val" "100n"
			(at 0 0 0)
			(layer "B.Fab")
			(hide yes)
			(effects
				(font
					(size 1 1)
					(thickness 0.15)
				)
				(justify mirror)
			)
		)
		(property "Voltage" "50V"
			(at 0 0 0)
			(layer "B.Fab")
			(hide yes)
			(effects
				(font
					(size 1 1)
					(thickness 0.15)
				)
				(justify mirror)
			)
		)
		(sheetname "KR to SFI #1")
		(sheetfile "kr_sfi.kicad_sch")
		(attr smd)
		(fp_rect
			(start -0.925 0.47)
			(end 0.925 -0.47)
			(stroke
				(width 0.05)
				(type default)
			)
			(fill no)
			(layer "B.CrtYd")
		)
		(fp_line
			(start -0.494 -0.248)
			(end 0.504 -0.248)
			(stroke
				(width 0.15)
				(type solid)
			)
			(layer "B.Fab")
		)
		(fp_line
			(start -0.494 0.25)
			(end -0.494 -0.248)
			(stroke
				(width 0.15)
				(type solid)
			)
			(layer "B.Fab")
		)
		(fp_line
			(start 0.504 -0.248)
			(end 0.504 0.25)
			(stroke
				(width 0.15)
				(type solid)
			)
			(layer "B.Fab")
		)
		(fp_line
			(start 0.504 0.25)
			(end -0.494 0.25)
			(stroke
				(width 0.15)
				(type solid)
			)
			(layer "B.Fab")
		)
		(pad "1" smd roundrect
			(at -0.48 0)
			(size 0.59 0.64)
			(layers "B.Cu" "B.Mask" "B.Paste")
			(roundrect_rratio 0.25)
			(net 1 "GND")
			(pintype "passive")
			(teardrops
				(best_length_ratio 0.2)
				(max_length 1)
				(best_width_ratio 0.9)
				(max_width 2)
				(curved_edges yes)
				(filter_ratio 0.9)
				(enabled yes)
				(allow_two_segments yes)
				(prefer_zone_connections yes)
			)
		)
		(pad "2" smd roundrect
			(at 0.48 0)
			(size 0.59 0.64)
			(layers "B.Cu" "B.Mask" "B.Paste")
			(roundrect_rratio 0.25)
			(net 2 "+3V3")
			(pintype "passive")
			(teardrops
				(best_length_ratio 0.2)
				(max_length 1)
				(best_width_ratio 0.9)
				(max_width 2)
				(curved_edges yes)
				(filter_ratio 0.9)
				(enabled yes)
				(allow_two_segments yes)
				(prefer_zone_connections yes)
			)
		)
	)
	(footprint "antmicro-footprints:R_0402_1005Metric"
		(layer "B.Cu")
		(at 139.74 142.36 180)
		(descr "Resistor SMD 0402")
		(tags "resistor SMD 0402")
		(property "Reference" "R295"
			(at 0.79 -0.7 0)
			(layer "B.SilkS")
			(effects
				(font
					(size 0.7 0.7)
					(thickness 0.15)
				)
				(justify left bottom mirror)
			)
		)
		(property "Value" "R_10k_0402"
			(at -1.011843 -1.772047 0)
			(layer "B.Fab")
			(effects
				(font
					(size 0.7 0.7)
					(thickness 0.15)
				)
				(justify left bottom mirror)
			)
		)
		(property "Datasheet" "https://www.bourns.com/docs/product-datasheets/cr.pdf"
			(at 0 0 180)
			(layer "F.Fab")
			(hide yes)
			(effects
				(font
					(size 1.27 1.27)
					(thickness 0.15)
				)
			)
		)
		(property "Author" "Antmicro"
			(at 279.48 284.72 0)
			(layer "B.Fab")
			(hide yes)
			(effects
				(font
					(size 1 1)
					(thickness 0.15)
				)
				(justify mirror)
			)
		)
		(property "License" "Apache-2.0"
			(at 279.48 284.72 0)
			(layer "B.Fab")
			(hide yes)
			(effects
				(font
					(size 1 1)
					(thickness 0.15)
				)
				(justify mirror)
			)
		)
		(property "MPN" "CR0402-FX-1002GLF"
			(at 279.48 284.72 0)
			(layer "B.Fab")
			(hide yes)
			(effects
				(font
					(size 1 1)
					(thickness 0.15)
				)
				(justify mirror)
			)
		)
		(property "Manufacturer" "Bourns"
			(at 279.48 284.72 0)
			(layer "B.Fab")
			(hide yes)
			(effects
				(font
					(size 1 1)
					(thickness 0.15)
				)
				(justify mirror)
			)
		)
		(property "Public" "False"
			(at 279.48 284.72 0)
			(layer "B.Fab")
			(hide yes)
			(effects
				(font
					(size 1 1)
					(thickness 0.15)
				)
				(justify mirror)
			)
		)
		(property "Tolerance" "1%"
			(at 279.48 284.72 0)
			(layer "B.Fab")
			(hide yes)
			(effects
				(font
					(size 1 1)
					(thickness 0.15)
				)
				(justify mirror)
			)
		)
		(property "Val" "10k"
			(at 279.48 284.72 0)
			(layer "B.Fab")
			(hide yes)
			(effects
				(font
					(size 1 1)
					(thickness 0.15)
				)
				(justify mirror)
			)
		)
		(sheetname "KR to SFI #2")
		(sheetfile "kr_sfi.kicad_sch")
		(attr smd)
		(fp_rect
			(start -0.925 0.47)
			(end 0.925 -0.47)
			(stroke
				(width 0.05)
				(type default)
			)
			(fill no)
			(layer "B.CrtYd")
		)
		(fp_rect
			(start -0.5 0.25)
			(end 0.5 -0.25)
			(stroke
				(width 0.15)
				(type solid)
			)
			(fill no)
			(layer "B.Fab")
		)
		(pad "1" smd roundrect
			(at -0.48 0 180)
			(size 0.59 0.64)
			(layers "B.Cu" "B.Mask" "B.Paste")
			(roundrect_rratio 0.25)
			(net 1 "GND")
			(pintype "passive")
			(teardrops
				(best_length_ratio 0.2)
				(max_length 1)
				(best_width_ratio 0.9)
				(max_width 2)
				(curved_edges yes)
				(filter_ratio 0.9)
				(enabled yes)
				(allow_two_segments yes)
				(prefer_zone_connections yes)
			)
		)
		(pad "2" smd roundrect
			(at 0.48 0 180)
			(size 0.59 0.64)
			(layers "B.Cu" "B.Mask" "B.Paste")
			(roundrect_rratio 0.25)
			(net 676 "Net-(U45C-PRTAD0)")
			(pintype "passive")
			(teardrops
				(best_length_ratio 0.2)
				(max_length 1)
				(best_width_ratio 0.9)
				(max_width 2)
				(curved_edges yes)
				(filter_ratio 0.9)
				(enabled yes)
				(allow_two_segments yes)
				(prefer_zone_connections yes)
			)
		)
	)
	(footprint "antmicro-footprints:TP_SMD_0.75mm"
		(layer "B.Cu")
		(at 224.4 165.25)
		(property "Reference" "TP38"
			(at -0.499999 -0.45 90)
			(layer "B.SilkS")
			(effects
				(font
					(size 0.7 0.7)
					(thickness 0.15)
				)
				(justify right top mirror)
			)
		)
		(property "Value" "TP_0.75mm_SMD"
			(at 0 -1.2 0)
			(layer "B.Fab")
			(effects
				(font
					(size 0.7 0.7)
					(thickness 0.15)
				)
				(justify right top mirror)
			)
		)
		(property "Author" "Antmicro"
			(at 361.8 295.32 0)
			(layer "B.Fab")
			(hide yes)
			(effects
				(font
					(size 1 1)
					(thickness 0.15)
				)
				(justify mirror)
			)
		)
		(property "License" "Apache-2.0"
			(at 361.8 295.32 0)
			(layer "B.Fab")
			(hide yes)
			(effects
				(font
					(size 1 1)
					(thickness 0.15)
				)
				(justify mirror)
			)
		)
		(property "MPN" ""
			(at 361.8 295.32 0)
			(layer "B.Fab")
			(hide yes)
			(effects
				(font
					(size 1 1)
					(thickness 0.15)
				)
				(justify mirror)
			)
		)
		(property "Manufacturer" ""
			(at 361.8 295.32 0)
			(layer "B.Fab")
			(hide yes)
			(effects
				(font
					(size 1 1)
					(thickness 0.15)
				)
				(justify mirror)
			)
		)
		(property "Public" "False"
			(at 361.8 295.32 0)
			(layer "B.Fab")
			(hide yes)
			(effects
				(font
					(size 1 1)
					(thickness 0.15)
				)
				(justify mirror)
			)
		)
		(sheetname "Com Express 7 MGMT")
		(sheetfile "com_express_7_mgmt.kicad_sch")
		(attr exclude_from_pos_files exclude_from_bom)
		(fp_circle
			(center 0 0)
			(end 0.475 0)
			(stroke
				(width 0.05)
				(type default)
			)
			(fill no)
			(layer "B.CrtYd")
		)
		(pad "1" smd circle
			(at 0 0)
			(size 0.75 0.75)
			(layers "B.Cu" "B.Mask")
			(net 343 "Net-(J12D-~{TYPE10})")
			(pinfunction "1")
			(pintype "passive")
			(teardrops
				(best_length_ratio 0.4)
				(max_length 1)
				(best_width_ratio 0.9)
				(max_width 2)
				(curved_edges yes)
				(filter_ratio 0.9)
				(enabled yes)
				(allow_two_segments yes)
				(prefer_zone_connections yes)
			)
		)
	)
	(footprint "antmicro-footprints:C_0402_1005Metric"
		(layer "B.Cu")
		(at 133.79 134.86 180)
		(descr "Capacitor SMD 0402")
		(tags "capacitor SMD 0402")
		(property "Reference" "C184"
			(at -3.61 -0.45 0)
			(layer "B.SilkS")
			(effects
				(font
					(size 0.7 0.7)
					(thickness 0.15)
				)
				(justify left bottom mirror)
			)
		)
		(property "Value" "C_100n_0402"
			(at -1.022927 -2.155213 0)
			(layer "B.Fab")
			(effects
				(font
					(size 0.7 0.7)
					(thickness 0.15)
				)
				(justify left bottom mirror)
			)
		)
		(property "Datasheet" "https://www.murata.com/products/productdetail?partno=GRM155R61H104KE14%23"
			(at 0 0 180)
			(layer "F.Fab")
			(hide yes)
			(effects
				(font
					(size 1.27 1.27)
					(thickness 0.15)
				)
			)
		)
		(property "Author" "Antmicro"
			(at 267.58 269.72 0)
			(layer "B.Fab")
			(hide yes)
			(effects
				(font
					(size 1 1)
					(thickness 0.15)
				)
				(justify mirror)
			)
		)
		(property "Dielectric" "X5R"
			(at 267.58 269.72 0)
			(layer "B.Fab")
			(hide yes)
			(effects
				(font
					(size 1 1)
					(thickness 0.15)
				)
				(justify mirror)
			)
		)
		(property "License" "Apache-2.0"
			(at 267.58 269.72 0)
			(layer "B.Fab")
			(hide yes)
			(effects
				(font
					(size 1 1)
					(thickness 0.15)
				)
				(justify mirror)
			)
		)
		(property "MPN" "GRM155R61H104KE14D"
			(at 267.58 269.72 0)
			(layer "B.Fab")
			(hide yes)
			(effects
				(font
					(size 1 1)
					(thickness 0.15)
				)
				(justify mirror)
			)
		)
		(property "Manufacturer" "Murata"
			(at 267.58 269.72 0)
			(layer "B.Fab")
			(hide yes)
			(effects
				(font
					(size 1 1)
					(thickness 0.15)
				)
				(justify mirror)
			)
		)
		(property "Public" "False"
			(at 267.58 269.72 0)
			(layer "B.Fab")
			(hide yes)
			(effects
				(font
					(size 1 1)
					(thickness 0.15)
				)
				(justify mirror)
			)
		)
		(property "Val" "100n"
			(at 267.58 269.72 0)
			(layer "B.Fab")
			(hide yes)
			(effects
				(font
					(size 1 1)
					(thickness 0.15)
				)
				(justify mirror)
			)
		)
		(property "Voltage" "50V"
			(at 267.58 269.72 0)
			(layer "B.Fab")
			(hide yes)
			(effects
				(font
					(size 1 1)
					(thickness 0.15)
				)
				(justify mirror)
			)
		)
		(sheetname "KR to SFI #2")
		(sheetfile "kr_sfi.kicad_sch")
		(attr smd)
		(fp_rect
			(start -0.925 0.47)
			(end 0.925 -0.47)
			(stroke
				(width 0.05)
				(type default)
			)
			(fill no)
			(layer "B.CrtYd")
		)
		(fp_line
			(start 0.504 0.25)
			(end -0.494 0.25)
			(stroke
				(width 0.15)
				(type solid)
			)
			(layer "B.Fab")
		)
		(fp_line
			(start 0.504 -0.248)
			(end 0.504 0.25)
			(stroke
				(width 0.15)
				(type solid)
			)
			(layer "B.Fab")
		)
		(fp_line
			(start -0.494 0.25)
			(end -0.494 -0.248)
			(stroke
				(width 0.15)
				(type solid)
			)
			(layer "B.Fab")
		)
		(fp_line
			(start -0.494 -0.248)
			(end 0.504 -0.248)
			(stroke
				(width 0.15)
				(type solid)
			)
			(layer "B.Fab")
		)
		(pad "1" smd roundrect
			(at -0.48 0 180)
			(size 0.59 0.64)
			(layers "B.Cu" "B.Mask" "B.Paste")
			(roundrect_rratio 0.25)
			(net 1 "GND")
			(pintype "passive")
			(teardrops
				(best_length_ratio 0.2)
				(max_length 1)
				(best_width_ratio 0.9)
				(max_width 2)
				(curved_edges yes)
				(filter_ratio 0.9)
				(enabled yes)
				(allow_two_segments yes)
				(prefer_zone_connections yes)
			)
		)
		(pad "2" smd roundrect
			(at 0.48 0 180)
			(size 0.59 0.64)
			(layers "B.Cu" "B.Mask" "B.Paste")
			(roundrect_rratio 0.25)
			(net 74 "+1V0")
			(pintype "passive")
			(teardrops
				(best_length_ratio 0.2)
				(max_length 1)
				(best_width_ratio 0.9)
				(max_width 2)
				(curved_edges yes)
				(filter_ratio 0.9)
				(enabled yes)
				(allow_two_segments yes)
				(prefer_zone_connections yes)
			)
		)
	)
	(footprint "antmicro-footprints:C_0402_1005Metric"
		(layer "B.Cu")
		(at 107.893 159.355571 180)
		(descr "Capacitor SMD 0402")
		(tags "capacitor SMD 0402")
		(property "Reference" "C139"
			(at -3.707 -0.004429 0)
			(layer "B.SilkS")
			(effects
				(font
					(size 0.7 0.7)
					(thickness 0.15)
				)
				(justify left bottom mirror)
			)
		)
		(property "Value" "C_220n_0402"
			(at -1.022927 -2.155213 0)
			(layer "B.Fab")
			(effects
				(font
					(size 0.7 0.7)
					(thickness 0.15)
				)
				(justify left bottom mirror)
			)
		)
		(property "Datasheet" "https://www.yageo.com/en/Chart/Download/pdf/CC0402KRX5R6BB224"
			(at 0 0 180)
			(layer "F.Fab")
			(hide yes)
			(effects
				(font
					(size 1.27 1.27)
					(thickness 0.15)
				)
			)
		)
		(property "Author" "Antmicro"
			(at 215.786 318.711142 0)
			(layer "B.Fab")
			(hide yes)
			(effects
				(font
					(size 1 1)
					(thickness 0.15)
				)
				(justify mirror)
			)
		)
		(property "Dielectric" ""
			(at 215.786 318.711142 0)
			(layer "B.Fab")
			(hide yes)
			(effects
				(font
					(size 1 1)
					(thickness 0.15)
				)
				(justify mirror)
			)
		)
		(property "License" "Apache-2.0"
			(at 215.786 318.711142 0)
			(layer "B.Fab")
			(hide yes)
			(effects
				(font
					(size 1 1)
					(thickness 0.15)
				)
				(justify mirror)
			)
		)
		(property "MPN" "CC0402KRX5R6BB224"
			(at 215.786 318.711142 0)
			(layer "B.Fab")
			(hide yes)
			(effects
				(font
					(size 1 1)
					(thickness 0.15)
				)
				(justify mirror)
			)
		)
		(property "Manufacturer" "YAGEO"
			(at 215.786 318.711142 0)
			(layer "B.Fab")
			(hide yes)
			(effects
				(font
					(size 1 1)
					(thickness 0.15)
				)
				(justify mirror)
			)
		)
		(property "Public" "False"
			(at 215.786 318.711142 0)
			(layer "B.Fab")
			(hide yes)
			(effects
				(font
					(size 1 1)
					(thickness 0.15)
				)
				(justify mirror)
			)
		)
		(property "Val" "220n"
			(at 215.786 318.711142 0)
			(layer "B.Fab")
			(hide yes)
			(effects
				(font
					(size 1 1)
					(thickness 0.15)
				)
				(justify mirror)
			)
		)
		(property "Voltage" ""
			(at 215.786 318.711142 0)
			(layer "B.Fab")
			(hide yes)
			(effects
				(font
					(size 1 1)
					(thickness 0.15)
				)
				(justify mirror)
			)
		)
		(sheetname "PCIe redriver")
		(sheetfile "pcie_redriver.kicad_sch")
		(attr smd)
		(fp_rect
			(start -0.925 0.47)
			(end 0.925 -0.47)
			(stroke
				(width 0.05)
				(type default)
			)
			(fill no)
			(layer "B.CrtYd")
		)
		(fp_line
			(start 0.504 0.25)
			(end -0.494 0.25)
			(stroke
				(width 0.15)
				(type solid)
			)
			(layer "B.Fab")
		)
		(fp_line
			(start 0.504 -0.248)
			(end 0.504 0.25)
			(stroke
				(width 0.15)
				(type solid)
			)
			(layer "B.Fab")
		)
		(fp_line
			(start -0.494 0.25)
			(end -0.494 -0.248)
			(stroke
				(width 0.15)
				(type solid)
			)
			(layer "B.Fab")
		)
		(fp_line
			(start -0.494 -0.248)
			(end 0.504 -0.248)
			(stroke
				(width 0.15)
				(type solid)
			)
			(layer "B.Fab")
		)
		(pad "1" smd roundrect
			(at -0.48 0 180)
			(size 0.59 0.64)
			(layers "B.Cu" "B.Mask" "B.Paste")
			(roundrect_rratio 0.25)
			(net 94 "/PCIe redriver/PCIe_{O}_C.TX3+")
			(pintype "passive")
			(teardrops
				(best_length_ratio 0.2)
				(max_length 1)
				(best_width_ratio 0.9)
				(max_width 2)
				(curved_edges yes)
				(filter_ratio 0.9)
				(enabled yes)
				(allow_two_segments yes)
				(prefer_zone_connections yes)
			)
		)
		(pad "2" smd roundrect
			(at 0.48 0 180)
			(size 0.59 0.64)
			(layers "B.Cu" "B.Mask" "B.Paste")
			(roundrect_rratio 0.25)
			(net 106 "/OCuLink/PCIe_{x4}.TX3+")
			(pintype "passive")
			(teardrops
				(best_length_ratio 0.2)
				(max_length 1)
				(best_width_ratio 0.9)
				(max_width 2)
				(curved_edges yes)
				(filter_ratio 0.9)
				(enabled yes)
				(allow_two_segments yes)
				(prefer_zone_connections yes)
			)
		)
	)
	(footprint "antmicro-footprints:C_0402_1005Metric"
		(layer "B.Cu")
		(at 142.377 149.258 90)
		(descr "Capacitor SMD 0402")
		(tags "capacitor SMD 0402")
		(property "Reference" "C150"
			(at -1.452 2.323 90)
			(layer "B.SilkS")
			(effects
				(font
					(size 0.7 0.7)
					(thickness 0.15)
				)
				(justify right bottom mirror)
			)
		)
		(property "Value" "C_100n_0402"
			(at -1.022927 -2.155213 90)
			(layer "B.Fab")
			(effects
				(font
					(size 0.7 0.7)
					(thickness 0.15)
				)
				(justify right bottom mirror)
			)
		)
		(property "Datasheet" "https://www.murata.com/products/productdetail?partno=GRM155R61H104KE14%23"
			(at 0 0 90)
			(layer "F.Fab")
			(hide yes)
			(effects
				(font
					(size 1.27 1.27)
					(thickness 0.15)
				)
			)
		)
		(property "Author" "Antmicro"
			(at 291.635 6.881 0)
			(layer "B.Fab")
			(hide yes)
			(effects
				(font
					(size 1 1)
					(thickness 0.15)
				)
				(justify mirror)
			)
		)
		(property "Dielectric" "X5R"
			(at 291.635 6.881 0)
			(layer "B.Fab")
			(hide yes)
			(effects
				(font
					(size 1 1)
					(thickness 0.15)
				)
				(justify mirror)
			)
		)
		(property "License" "Apache-2.0"
			(at 291.635 6.881 0)
			(layer "B.Fab")
			(hide yes)
			(effects
				(font
					(size 1 1)
					(thickness 0.15)
				)
				(justify mirror)
			)
		)
		(property "MPN" "GRM155R61H104KE14D"
			(at 291.635 6.881 0)
			(layer "B.Fab")
			(hide yes)
			(effects
				(font
					(size 1 1)
					(thickness 0.15)
				)
				(justify mirror)
			)
		)
		(property "Manufacturer" "Murata"
			(at 291.635 6.881 0)
			(layer "B.Fab")
			(hide yes)
			(effects
				(font
					(size 1 1)
					(thickness 0.15)
				)
				(justify mirror)
			)
		)
		(property "Public" "False"
			(at 291.635 6.881 0)
			(layer "B.Fab")
			(hide yes)
			(effects
				(font
					(size 1 1)
					(thickness 0.15)
				)
				(justify mirror)
			)
		)
		(property "Val" "100n"
			(at 291.635 6.881 0)
			(layer "B.Fab")
			(hide yes)
			(effects
				(font
					(size 1 1)
					(thickness 0.15)
				)
				(justify mirror)
			)
		)
		(property "Voltage" "50V"
			(at 291.635 6.881 0)
			(layer "B.Fab")
			(hide yes)
			(effects
				(font
					(size 1 1)
					(thickness 0.15)
				)
				(justify mirror)
			)
		)
		(sheetname "KR to SFI #1")
		(sheetfile "kr_sfi.kicad_sch")
		(attr smd)
		(fp_rect
			(start -0.925 0.47)
			(end 0.925 -0.47)
			(stroke
				(width 0.05)
				(type default)
			)
			(fill no)
			(layer "B.CrtYd")
		)
		(fp_line
			(start 0.504 -0.248)
			(end 0.504 0.25)
			(stroke
				(width 0.15)
				(type solid)
			)
			(layer "B.Fab")
		)
		(fp_line
			(start -0.494 -0.248)
			(end 0.504 -0.248)
			(stroke
				(width 0.15)
				(type solid)
			)
			(layer "B.Fab")
		)
		(fp_line
			(start 0.504 0.25)
			(end -0.494 0.25)
			(stroke
				(width 0.15)
				(type solid)
			)
			(layer "B.Fab")
		)
		(fp_line
			(start -0.494 0.25)
			(end -0.494 -0.248)
			(stroke
				(width 0.15)
				(type solid)
			)
			(layer "B.Fab")
		)
		(pad "1" smd roundrect
			(at -0.48 0 90)
			(size 0.59 0.64)
			(layers "B.Cu" "B.Mask" "B.Paste")
			(roundrect_rratio 0.25)
			(net 1 "GND")
			(pintype "passive")
			(teardrops
				(best_length_ratio 0.2)
				(max_length 1)
				(best_width_ratio 0.9)
				(max_width 2)
				(curved_edges yes)
				(filter_ratio 0.9)
				(enabled yes)
				(allow_two_segments yes)
				(prefer_zone_connections yes)
			)
		)
		(pad "2" smd roundrect
			(at 0.48 0 90)
			(size 0.59 0.64)
			(layers "B.Cu" "B.Mask" "B.Paste")
			(roundrect_rratio 0.25)
			(net 78 "+1V8")
			(pintype "passive")
			(teardrops
				(best_length_ratio 0.2)
				(max_length 1)
				(best_width_ratio 0.9)
				(max_width 2)
				(curved_edges yes)
				(filter_ratio 0.9)
				(enabled yes)
				(allow_two_segments yes)
				(prefer_zone_connections yes)
			)
		)
	)
	(footprint "antmicro-footprints:C_0603_1608Metric"
		(layer "B.Cu")
		(at 264.955709 74.06 180)
		(descr "Capacitor SMD 0603")
		(tags "capacitor 0603")
		(property "Reference" "C89"
			(at -1.064999 -1.55 0)
			(layer "B.SilkS")
			(effects
				(font
					(size 0.7 0.7)
					(thickness 0.15)
				)
				(justify left bottom mirror)
			)
		)
		(property "Value" "C_22u_16V_0603"
			(at -1.42757 -1.770288 0)
			(layer "B.Fab")
			(effects
				(font
					(size 0.7 0.7)
					(thickness 0.15)
				)
				(justify left bottom mirror)
			)
		)
		(property "Datasheet" "https://product.samsungsem.com/mlcc/CL10A226MO7JZN.do"
			(at 0 0 180)
			(layer "F.Fab")
			(hide yes)
			(effects
				(font
					(size 1.27 1.27)
					(thickness 0.15)
				)
			)
		)
		(property "Author" "Antmicro"
			(at 529.911418 148.12 0)
			(layer "B.Fab")
			(hide yes)
			(effects
				(font
					(size 1 1)
					(thickness 0.15)
				)
				(justify mirror)
			)
		)
		(property "Dielectric" ""
			(at 529.911418 148.12 0)
			(layer "B.Fab")
			(hide yes)
			(effects
				(font
					(size 1 1)
					(thickness 0.15)
				)
				(justify mirror)
			)
		)
		(property "License" "Apache-2.0"
			(at 529.911418 148.12 0)
			(layer "B.Fab")
			(hide yes)
			(effects
				(font
					(size 1 1)
					(thickness 0.15)
				)
				(justify mirror)
			)
		)
		(property "MPN" "CL10A226MO7JZNC"
			(at 529.911418 148.12 0)
			(layer "B.Fab")
			(hide yes)
			(effects
				(font
					(size 1 1)
					(thickness 0.15)
				)
				(justify mirror)
			)
		)
		(property "Manufacturer" "Samsung Electro-Mechanics"
			(at 529.911418 148.12 0)
			(layer "B.Fab")
			(hide yes)
			(effects
				(font
					(size 1 1)
					(thickness 0.15)
				)
				(justify mirror)
			)
		)
		(property "Public" "False"
			(at 529.911418 148.12 0)
			(layer "B.Fab")
			(hide yes)
			(effects
				(font
					(size 1 1)
					(thickness 0.15)
				)
				(justify mirror)
			)
		)
		(property "Val" "22u"
			(at 529.911418 148.12 0)
			(layer "B.Fab")
			(hide yes)
			(effects
				(font
					(size 1 1)
					(thickness 0.15)
				)
				(justify mirror)
			)
		)
		(property "Voltage" "16V"
			(at 529.911418 148.12 0)
			(layer "B.Fab")
			(hide yes)
			(effects
				(font
					(size 1 1)
					(thickness 0.15)
				)
				(justify mirror)
			)
		)
		(sheetname "Misc")
		(sheetfile "misc.kicad_sch")
		(attr smd)
		(fp_line
			(start 0.15 0.4)
			(end -0.15 0.4)
			(stroke
				(width 0.15)
				(type solid)
			)
			(layer "B.SilkS")
		)
		(fp_line
			(start 0.15 -0.4)
			(end -0.15 -0.4)
			(stroke
				(width 0.15)
				(type solid)
			)
			(layer "B.SilkS")
		)
		(fp_rect
			(start -1.25 0.65)
			(end 1.25 -0.65)
			(stroke
				(width 0.05)
				(type solid)
			)
			(fill no)
			(layer "B.CrtYd")
		)
		(fp_rect
			(start -0.8 0.4)
			(end 0.8 -0.4)
			(stroke
				(width 0.15)
				(type solid)
			)
			(fill no)
			(layer "B.Fab")
		)
		(pad "1" smd roundrect
			(at -0.7 0 180)
			(size 0.8 1)
			(layers "B.Cu" "B.Mask" "B.Paste")
			(roundrect_rratio 0.2)
			(net 1 "GND")
			(pintype "passive")
			(teardrops
				(best_length_ratio 0.2)
				(max_length 1)
				(best_width_ratio 0.9)
				(max_width 2)
				(curved_edges yes)
				(filter_ratio 0.9)
				(enabled yes)
				(allow_two_segments yes)
				(prefer_zone_connections yes)
			)
		)
		(pad "2" smd roundrect
			(at 0.7 0 180)
			(size 0.8 1)
			(layers "B.Cu" "B.Mask" "B.Paste")
			(roundrect_rratio 0.2)
			(net 81 "/Misc/FAN_12V")
			(pintype "passive")
			(teardrops
				(best_length_ratio 0.2)
				(max_length 1)
				(best_width_ratio 0.9)
				(max_width 2)
				(curved_edges yes)
				(filter_ratio 0.9)
				(enabled yes)
				(allow_two_segments yes)
				(prefer_zone_connections yes)
			)
		)
	)
	(footprint "antmicro-footprints:C_0402_1005Metric"
		(layer "B.Cu")
		(at 215.677 131.293 -90)
		(descr "Capacitor SMD 0402")
		(tags "capacitor SMD 0402")
		(property "Reference" "C11"
			(at -1.083 0.477 90)
			(layer "B.SilkS")
			(effects
				(font
					(size 0.7 0.7)
					(thickness 0.15)
				)
				(justify left bottom mirror)
			)
		)
		(property "Value" "C_100n_0402"
			(at -1.022927 -2.155213 90)
			(layer "B.Fab")
			(effects
				(font
					(size 0.7 0.7)
					(thickness 0.15)
				)
				(justify left bottom mirror)
			)
		)
		(property "Datasheet" "https://www.murata.com/products/productdetail?partno=GRM155R61H104KE14%23"
			(at 0 0 270)
			(layer "F.Fab")
			(hide yes)
			(effects
				(font
					(size 1.27 1.27)
					(thickness 0.15)
				)
			)
		)
		(property "Author" "Antmicro"
			(at 84.384 346.97 0)
			(layer "B.Fab")
			(hide yes)
			(effects
				(font
					(size 1 1)
					(thickness 0.15)
				)
				(justify mirror)
			)
		)
		(property "Dielectric" "X5R"
			(at 84.384 346.97 0)
			(layer "B.Fab")
			(hide yes)
			(effects
				(font
					(size 1 1)
					(thickness 0.15)
				)
				(justify mirror)
			)
		)
		(property "License" "Apache-2.0"
			(at 84.384 346.97 0)
			(layer "B.Fab")
			(hide yes)
			(effects
				(font
					(size 1 1)
					(thickness 0.15)
				)
				(justify mirror)
			)
		)
		(property "MPN" "GRM155R61H104KE14D"
			(at 84.384 346.97 0)
			(layer "B.Fab")
			(hide yes)
			(effects
				(font
					(size 1 1)
					(thickness 0.15)
				)
				(justify mirror)
			)
		)
		(property "Manufacturer" "Murata"
			(at 84.384 346.97 0)
			(layer "B.Fab")
			(hide yes)
			(effects
				(font
					(size 1 1)
					(thickness 0.15)
				)
				(justify mirror)
			)
		)
		(property "Public" "False"
			(at 84.384 346.97 0)
			(layer "B.Fab")
			(hide yes)
			(effects
				(font
					(size 1 1)
					(thickness 0.15)
				)
				(justify mirror)
			)
		)
		(property "Val" "100n"
			(at 84.384 346.97 0)
			(layer "B.Fab")
			(hide yes)
			(effects
				(font
					(size 1 1)
					(thickness 0.15)
				)
				(justify mirror)
			)
		)
		(property "Voltage" "50V"
			(at 84.384 346.97 0)
			(layer "B.Fab")
			(hide yes)
			(effects
				(font
					(size 1 1)
					(thickness 0.15)
				)
				(justify mirror)
			)
		)
		(sheetname "PCIe misc")
		(sheetfile "pcie_misc.kicad_sch")
		(attr smd)
		(fp_rect
			(start -0.925 0.47)
			(end 0.925 -0.47)
			(stroke
				(width 0.05)
				(type default)
			)
			(fill no)
			(layer "B.CrtYd")
		)
		(fp_line
			(start -0.494 0.25)
			(end -0.494 -0.248)
			(stroke
				(width 0.15)
				(type solid)
			)
			(layer "B.Fab")
		)
		(fp_line
			(start 0.504 0.25)
			(end -0.494 0.25)
			(stroke
				(width 0.15)
				(type solid)
			)
			(layer "B.Fab")
		)
		(fp_line
			(start -0.494 -0.248)
			(end 0.504 -0.248)
			(stroke
				(width 0.15)
				(type solid)
			)
			(layer "B.Fab")
		)
		(fp_line
			(start 0.504 -0.248)
			(end 0.504 0.25)
			(stroke
				(width 0.15)
				(type solid)
			)
			(layer "B.Fab")
		)
		(pad "1" smd roundrect
			(at -0.48 0 270)
			(size 0.59 0.64)
			(layers "B.Cu" "B.Mask" "B.Paste")
			(roundrect_rratio 0.25)
			(net 1 "GND")
			(pintype "passive")
			(teardrops
				(best_length_ratio 0.2)
				(max_length 1)
				(best_width_ratio 0.9)
				(max_width 2)
				(curved_edges yes)
				(filter_ratio 0.9)
				(enabled yes)
				(allow_two_segments yes)
				(prefer_zone_connections yes)
			)
		)
		(pad "2" smd roundrect
			(at 0.48 0 270)
			(size 0.59 0.64)
			(layers "B.Cu" "B.Mask" "B.Paste")
			(roundrect_rratio 0.25)
			(net 2 "+3V3")
			(pintype "passive")
			(teardrops
				(best_length_ratio 0.2)
				(max_length 1)
				(best_width_ratio 0.9)
				(max_width 2)
				(curved_edges yes)
				(filter_ratio 0.9)
				(enabled yes)
				(allow_two_segments yes)
				(prefer_zone_connections yes)
			)
		)
	)
	(footprint "antmicro-footprints:TP_SMD_0.75mm"
		(layer "B.Cu")
		(at 182.5 170.8 180)
		(property "Reference" "TP35"
			(at 0.45 0.45 0)
			(layer "B.SilkS")
			(effects
				(font
					(size 0.7 0.7)
					(thickness 0.15)
				)
				(justify left top mirror)
			)
		)
		(property "Value" "TP_0.75mm_SMD"
			(at 0 -1.2 0)
			(layer "B.Fab")
			(effects
				(font
					(size 0.7 0.7)
					(thickness 0.15)
				)
				(justify left top mirror)
			)
		)
		(property "Author" "Antmicro"
			(at 372.21 -73.39 90)
			(layer "B.Fab")
			(hide yes)
			(effects
				(font
					(size 1 1)
					(thickness 0.15)
				)
				(justify mirror)
			)
		)
		(property "License" "Apache-2.0"
			(at 372.21 -73.39 90)
			(layer "B.Fab")
			(hide yes)
			(effects
				(font
					(size 1 1)
					(thickness 0.15)
				)
				(justify mirror)
			)
		)
		(property "MPN" ""
			(at 372.21 -73.39 90)
			(layer "B.Fab")
			(hide yes)
			(effects
				(font
					(size 1 1)
					(thickness 0.15)
				)
				(justify mirror)
			)
		)
		(property "Manufacturer" ""
			(at 372.21 -73.39 90)
			(layer "B.Fab")
			(hide yes)
			(effects
				(font
					(size 1 1)
					(thickness 0.15)
				)
				(justify mirror)
			)
		)
		(property "Public" "False"
			(at 372.21 -73.39 90)
			(layer "B.Fab")
			(hide yes)
			(effects
				(font
					(size 1 1)
					(thickness 0.15)
				)
				(justify mirror)
			)
		)
		(sheetname "Com Express 7 MGMT")
		(sheetfile "com_express_7_mgmt.kicad_sch")
		(attr exclude_from_pos_files exclude_from_bom)
		(fp_circle
			(center 0 0)
			(end 0.475 0)
			(stroke
				(width 0.05)
				(type default)
			)
			(fill no)
			(layer "B.CrtYd")
		)
		(pad "1" smd circle
			(at 0 0 180)
			(size 0.75 0.75)
			(layers "B.Cu" "B.Mask")
			(net 297 "Net-(J12D-~{SUS_S3})")
			(pinfunction "1")
			(pintype "passive")
			(teardrops
				(best_length_ratio 0.4)
				(max_length 1)
				(best_width_ratio 0.9)
				(max_width 2)
				(curved_edges yes)
				(filter_ratio 0.9)
				(enabled yes)
				(allow_two_segments yes)
				(prefer_zone_connections yes)
			)
		)
	)
	(footprint "antmicro-footprints:R_0402_1005Metric"
		(layer "B.Cu")
		(at 308.824999 106.15 -90)
		(descr "Resistor SMD 0402")
		(tags "resistor SMD 0402")
		(property "Reference" "R92"
			(at 0.76 -0.475001 90)
			(layer "B.SilkS")
			(effects
				(font
					(size 0.7 0.7)
					(thickness 0.15)
				)
				(justify left bottom mirror)
			)
		)
		(property "Value" "R_10k_0402"
			(at -1.011843 -1.772047 90)
			(layer "B.Fab")
			(effects
				(font
					(size 0.7 0.7)
					(thickness 0.15)
				)
				(justify left bottom mirror)
			)
		)
		(property "Datasheet" "https://www.bourns.com/docs/product-datasheets/cr.pdf"
			(at 0 0 270)
			(layer "F.Fab")
			(hide yes)
			(effects
				(font
					(size 1.27 1.27)
					(thickness 0.15)
				)
			)
		)
		(property "Author" "Antmicro"
			(at 202.674999 414.974999 0)
			(layer "B.Fab")
			(hide yes)
			(effects
				(font
					(size 1 1)
					(thickness 0.15)
				)
				(justify mirror)
			)
		)
		(property "License" "Apache-2.0"
			(at 202.674999 414.974999 0)
			(layer "B.Fab")
			(hide yes)
			(effects
				(font
					(size 1 1)
					(thickness 0.15)
				)
				(justify mirror)
			)
		)
		(property "MPN" "CR0402-FX-1002GLF"
			(at 202.674999 414.974999 0)
			(layer "B.Fab")
			(hide yes)
			(effects
				(font
					(size 1 1)
					(thickness 0.15)
				)
				(justify mirror)
			)
		)
		(property "Manufacturer" "Bourns"
			(at 202.674999 414.974999 0)
			(layer "B.Fab")
			(hide yes)
			(effects
				(font
					(size 1 1)
					(thickness 0.15)
				)
				(justify mirror)
			)
		)
		(property "Public" "False"
			(at 202.674999 414.974999 0)
			(layer "B.Fab")
			(hide yes)
			(effects
				(font
					(size 1 1)
					(thickness 0.15)
				)
				(justify mirror)
			)
		)
		(property "Tolerance" "1%"
			(at 202.674999 414.974999 0)
			(layer "B.Fab")
			(hide yes)
			(effects
				(font
					(size 1 1)
					(thickness 0.15)
				)
				(justify mirror)
			)
		)
		(property "Val" "10k"
			(at 202.674999 414.974999 0)
			(layer "B.Fab")
			(hide yes)
			(effects
				(font
					(size 1 1)
					(thickness 0.15)
				)
				(justify mirror)
			)
		)
		(sheetname "Power")
		(sheetfile "power.kicad_sch")
		(attr smd)
		(fp_rect
			(start -0.925 0.47)
			(end 0.925 -0.47)
			(stroke
				(width 0.05)
				(type default)
			)
			(fill no)
			(layer "B.CrtYd")
		)
		(fp_rect
			(start -0.5 0.25)
			(end 0.5 -0.25)
			(stroke
				(width 0.15)
				(type solid)
			)
			(fill no)
			(layer "B.Fab")
		)
		(pad "1" smd roundrect
			(at -0.48 0 270)
			(size 0.59 0.64)
			(layers "B.Cu" "B.Mask" "B.Paste")
			(roundrect_rratio 0.25)
			(net 1 "GND")
			(pintype "passive")
			(teardrops
				(best_length_ratio 0.2)
				(max_length 1)
				(best_width_ratio 0.9)
				(max_width 2)
				(curved_edges yes)
				(filter_ratio 0.9)
				(enabled yes)
				(allow_two_segments yes)
				(prefer_zone_connections yes)
			)
		)
		(pad "2" smd roundrect
			(at 0.48 0 270)
			(size 0.59 0.64)
			(layers "B.Cu" "B.Mask" "B.Paste")
			(roundrect_rratio 0.25)
			(net 576 "Net-(U19-MODE)")
			(pintype "passive")
			(teardrops
				(best_length_ratio 0.2)
				(max_length 1)
				(best_width_ratio 0.9)
				(max_width 2)
				(curved_edges yes)
				(filter_ratio 0.9)
				(enabled yes)
				(allow_two_segments yes)
				(prefer_zone_connections yes)
			)
		)
	)
	(footprint "antmicro-footprints:Mech_M2_2280_H2.5mm"
		(layer "B.Cu")
		(at 261.75 102.11 90)
		(property "Reference" "A2"
			(at 0 -8.89 90)
			(layer "B.SilkS")
			(hide yes)
			(effects
				(font
					(size 0.7 0.7)
					(thickness 0.15)
				)
				(justify left bottom mirror)
			)
		)
		(property "Value" "Mech_M2_2280_H2.5mm"
			(at 0 -6.857 90)
			(layer "B.Fab")
			(effects
				(font
					(size 0.7 0.7)
					(thickness 0.15)
				)
				(justify left bottom mirror)
			)
		)
		(property "Author" "Antmicro"
			(at 363.86 -159.64 0)
			(layer "B.Fab")
			(hide yes)
			(effects
				(font
					(size 1 1)
					(thickness 0.15)
				)
				(justify mirror)
			)
		)
		(property "License" "Apache-2.0"
			(at 363.86 -159.64 0)
			(layer "B.Fab")
			(hide yes)
			(effects
				(font
					(size 1 1)
					(thickness 0.15)
				)
				(justify mirror)
			)
		)
		(property "MPN" ""
			(at 363.86 -159.64 0)
			(layer "B.Fab")
			(hide yes)
			(effects
				(font
					(size 1 1)
					(thickness 0.15)
				)
				(justify mirror)
			)
		)
		(property "Manufacturer" ""
			(at 363.86 -159.64 0)
			(layer "B.Fab")
			(hide yes)
			(effects
				(font
					(size 1 1)
					(thickness 0.15)
				)
				(justify mirror)
			)
		)
		(property "Public" "False"
			(at 363.86 -159.64 0)
			(layer "B.Fab")
			(hide yes)
			(effects
				(font
					(size 1 1)
					(thickness 0.15)
				)
				(justify mirror)
			)
		)
		(sheetname "M.2 key M #1")
		(sheetfile "m2keym_low.kicad_sch")
		(attr exclude_from_pos_files exclude_from_bom allow_missing_courtyard)
		(fp_rect
			(start -10.922 -0.0508)
			(end 11.0236 -80.0608)
			(stroke
				(width 0.15)
				(type solid)
			)
			(fill no)
			(layer "B.Fab")
		)
	)
	(footprint "antmicro-footprints:C_0603_1608Metric"
		(layer "B.Cu")
		(at 290.64 79.12 -90)
		(descr "Capacitor SMD 0603")
		(tags "capacitor 0603")
		(property "Reference" "C77"
			(at -3.31 -0.46 90)
			(layer "B.SilkS")
			(effects
				(font
					(size 0.7 0.7)
					(thickness 0.15)
				)
				(justify left bottom mirror)
			)
		)
		(property "Value" "C_22u_16V_0603"
			(at -1.42757 -1.770288 90)
			(layer "B.Fab")
			(effects
				(font
					(size 0.7 0.7)
					(thickness 0.15)
				)
				(justify left bottom mirror)
			)
		)
		(property "Datasheet" "https://product.samsungsem.com/mlcc/CL10A226MO7JZN.do"
			(at 0 0 270)
			(layer "F.Fab")
			(hide yes)
			(effects
				(font
					(size 1.27 1.27)
					(thickness 0.15)
				)
			)
		)
		(property "Author" "Antmicro"
			(at 211.52 369.76 0)
			(layer "B.Fab")
			(hide yes)
			(effects
				(font
					(size 1 1)
					(thickness 0.15)
				)
				(justify mirror)
			)
		)
		(property "Dielectric" ""
			(at 211.52 369.76 0)
			(layer "B.Fab")
			(hide yes)
			(effects
				(font
					(size 1 1)
					(thickness 0.15)
				)
				(justify mirror)
			)
		)
		(property "License" "Apache-2.0"
			(at 211.52 369.76 0)
			(layer "B.Fab")
			(hide yes)
			(effects
				(font
					(size 1 1)
					(thickness 0.15)
				)
				(justify mirror)
			)
		)
		(property "MPN" "CL10A226MO7JZNC"
			(at 211.52 369.76 0)
			(layer "B.Fab")
			(hide yes)
			(effects
				(font
					(size 1 1)
					(thickness 0.15)
				)
				(justify mirror)
			)
		)
		(property "Manufacturer" "Samsung Electro-Mechanics"
			(at 211.52 369.76 0)
			(layer "B.Fab")
			(hide yes)
			(effects
				(font
					(size 1 1)
					(thickness 0.15)
				)
				(justify mirror)
			)
		)
		(property "Public" "False"
			(at 211.52 369.76 0)
			(layer "B.Fab")
			(hide yes)
			(effects
				(font
					(size 1 1)
					(thickness 0.15)
				)
				(justify mirror)
			)
		)
		(property "Val" "22u"
			(at 211.52 369.76 0)
			(layer "B.Fab")
			(hide yes)
			(effects
				(font
					(size 1 1)
					(thickness 0.15)
				)
				(justify mirror)
			)
		)
		(property "Voltage" "16V"
			(at 211.52 369.76 0)
			(layer "B.Fab")
			(hide yes)
			(effects
				(font
					(size 1 1)
					(thickness 0.15)
				)
				(justify mirror)
			)
		)
		(sheetname "M.2 key M #2")
		(sheetfile "m2keym.kicad_sch")
		(attr smd)
		(fp_line
			(start 0.15 0.4)
			(end -0.15 0.4)
			(stroke
				(width 0.15)
				(type solid)
			)
			(layer "B.SilkS")
		)
		(fp_line
			(start 0.15 -0.4)
			(end -0.15 -0.4)
			(stroke
				(width 0.15)
				(type solid)
			)
			(layer "B.SilkS")
		)
		(fp_rect
			(start -1.25 0.65)
			(end 1.25 -0.65)
			(stroke
				(width 0.05)
				(type solid)
			)
			(fill no)
			(layer "B.CrtYd")
		)
		(fp_rect
			(start -0.8 0.4)
			(end 0.8 -0.4)
			(stroke
				(width 0.15)
				(type solid)
			)
			(fill no)
			(layer "B.Fab")
		)
		(pad "1" smd roundrect
			(at -0.7 0 270)
			(size 0.8 1)
			(layers "B.Cu" "B.Mask" "B.Paste")
			(roundrect_rratio 0.2)
			(net 1 "GND")
			(pintype "passive")
			(teardrops
				(best_length_ratio 0.2)
				(max_length 1)
				(best_width_ratio 0.9)
				(max_width 2)
				(curved_edges yes)
				(filter_ratio 0.9)
				(enabled yes)
				(allow_two_segments yes)
				(prefer_zone_connections yes)
			)
		)
		(pad "2" smd roundrect
			(at 0.7 0 270)
			(size 0.8 1)
			(layers "B.Cu" "B.Mask" "B.Paste")
			(roundrect_rratio 0.2)
			(net 970 "/M.2 key M #2/M2_3V3")
			(pintype "passive")
			(teardrops
				(best_length_ratio 0.2)
				(max_length 1)
				(best_width_ratio 0.9)
				(max_width 2)
				(curved_edges yes)
				(filter_ratio 0.9)
				(enabled yes)
				(allow_two_segments yes)
				(prefer_zone_connections yes)
			)
		)
	)
	(footprint "antmicro-footprints:C_0402_1005Metric"
		(layer "B.Cu")
		(at 198.836467 139.42053 135)
		(descr "Capacitor SMD 0402")
		(tags "capacitor SMD 0402")
		(property "Reference" "C125"
			(at -3.530586 -0.359976 135)
			(layer "B.SilkS")
			(effects
				(font
					(size 0.7 0.7)
					(thickness 0.15)
				)
				(justify right bottom mirror)
			)
		)
		(property "Value" "C_220n_0402"
			(at -1.022927 -2.155213 135)
			(layer "B.Fab")
			(effects
				(font
					(size 0.7 0.7)
					(thickness 0.15)
				)
				(justify right bottom mirror)
			)
		)
		(property "Datasheet" "https://www.yageo.com/en/Chart/Download/pdf/CC0402KRX5R6BB224"
			(at 0 0 135)
			(layer "F.Fab")
			(hide yes)
			(effects
				(font
					(size 1.27 1.27)
					(thickness 0.15)
				)
			)
		)
		(property "Author" "Antmicro"
			(at 336.3 -39.499999 45)
			(layer "B.Fab")
			(hide yes)
			(effects
				(font
					(size 1 1)
					(thickness 0.15)
				)
				(justify mirror)
			)
		)
		(property "Dielectric" ""
			(at 336.3 -39.499999 45)
			(layer "B.Fab")
			(hide yes)
			(effects
				(font
					(size 1 1)
					(thickness 0.15)
				)
				(justify mirror)
			)
		)
		(property "License" "Apache-2.0"
			(at 336.3 -39.499999 45)
			(layer "B.Fab")
			(hide yes)
			(effects
				(font
					(size 1 1)
					(thickness 0.15)
				)
				(justify mirror)
			)
		)
		(property "MPN" "CC0402KRX5R6BB224"
			(at 336.3 -39.499999 45)
			(layer "B.Fab")
			(hide yes)
			(effects
				(font
					(size 1 1)
					(thickness 0.15)
				)
				(justify mirror)
			)
		)
		(property "Manufacturer" "YAGEO"
			(at 336.3 -39.499999 45)
			(layer "B.Fab")
			(hide yes)
			(effects
				(font
					(size 1 1)
					(thickness 0.15)
				)
				(justify mirror)
			)
		)
		(property "Public" "False"
			(at 336.3 -39.499999 45)
			(layer "B.Fab")
			(hide yes)
			(effects
				(font
					(size 1 1)
					(thickness 0.15)
				)
				(justify mirror)
			)
		)
		(property "Val" "220n"
			(at 336.3 -39.499999 45)
			(layer "B.Fab")
			(hide yes)
			(effects
				(font
					(size 1 1)
					(thickness 0.15)
				)
				(justify mirror)
			)
		)
		(property "Voltage" ""
			(at 336.3 -39.499999 45)
			(layer "B.Fab")
			(hide yes)
			(effects
				(font
					(size 1 1)
					(thickness 0.15)
				)
				(justify mirror)
			)
		)
		(sheetname "PCIe redriver")
		(sheetfile "pcie_redriver.kicad_sch")
		(attr smd)
		(fp_poly
			(pts
				(xy -0.925 0.47) (xy 0.925 0.47) (xy 0.925 -0.47) (xy -0.925 -0.47)
			)
			(stroke
				(width 0.05)
				(type default)
			)
			(fill no)
			(layer "B.CrtYd")
		)
		(fp_line
			(start 0.504 -0.248)
			(end 0.504 0.25)
			(stroke
				(width 0.15)
				(type solid)
			)
			(layer "B.Fab")
		)
		(fp_line
			(start 0.504 0.25)
			(end -0.494 0.25)
			(stroke
				(width 0.15)
				(type solid)
			)
			(layer "B.Fab")
		)
		(fp_line
			(start -0.494 -0.248)
			(end 0.504 -0.248)
			(stroke
				(width 0.15)
				(type solid)
			)
			(layer "B.Fab")
		)
		(fp_line
			(start -0.494 0.25)
			(end -0.494 -0.248)
			(stroke
				(width 0.15)
				(type solid)
			)
			(layer "B.Fab")
		)
		(pad "1" smd roundrect
			(at -0.48 0 135)
			(size 0.59 0.64)
			(layers "B.Cu" "B.Mask" "B.Paste")
			(roundrect_rratio 0.25)
			(net 217 "/Com Express 7 Interfaces/PCIe_{B1x4}.RX1-")
			(pintype "passive")
			(teardrops
				(best_length_ratio 0.2)
				(max_length 1)
				(best_width_ratio 0.9)
				(max_width 2)
				(curved_edges yes)
				(filter_ratio 0.9)
				(enabled yes)
				(allow_two_segments yes)
				(prefer_zone_connections yes)
			)
		)
		(pad "2" smd roundrect
			(at 0.48 0 135)
			(size 0.59 0.64)
			(layers "B.Cu" "B.Mask" "B.Paste")
			(roundrect_rratio 0.25)
			(net 103 "/PCIe redriver/PCIe_{I}_C.RX1-")
			(pintype "passive")
			(teardrops
				(best_length_ratio 0.2)
				(max_length 1)
				(best_width_ratio 0.9)
				(max_width 2)
				(curved_edges yes)
				(filter_ratio 0.9)
				(enabled yes)
				(allow_two_segments yes)
				(prefer_zone_connections yes)
			)
		)
	)
	(footprint "antmicro-footprints:R_0402_1005Metric"
		(layer "B.Cu")
		(at 309.824999 121.96 -90)
		(descr "Resistor SMD 0402")
		(tags "resistor SMD 0402")
		(property "Reference" "R88"
			(at 0.8 -0.475001 90)
			(layer "B.SilkS")
			(effects
				(font
					(size 0.7 0.7)
					(thickness 0.15)
				)
				(justify left bottom mirror)
			)
		)
		(property "Value" "R_68k_0402"
			(at -1.011843 -1.772047 90)
			(layer "B.Fab")
			(effects
				(font
					(size 0.7 0.7)
					(thickness 0.15)
				)
				(justify left bottom mirror)
			)
		)
		(property "Datasheet" "https://www.bourns.com/docs/product-datasheets/cr.pdf"
			(at 0 0 270)
			(layer "F.Fab")
			(hide yes)
			(effects
				(font
					(size 1.27 1.27)
					(thickness 0.15)
				)
			)
		)
		(property "Author" "Antmicro"
			(at 187.864999 431.784999 0)
			(layer "B.Fab")
			(hide yes)
			(effects
				(font
					(size 1 1)
					(thickness 0.15)
				)
				(justify mirror)
			)
		)
		(property "License" "Apache-2.0"
			(at 187.864999 431.784999 0)
			(layer "B.Fab")
			(hide yes)
			(effects
				(font
					(size 1 1)
					(thickness 0.15)
				)
				(justify mirror)
			)
		)
		(property "MPN" "CR0402-FX-6802GLF"
			(at 187.864999 431.784999 0)
			(layer "B.Fab")
			(hide yes)
			(effects
				(font
					(size 1 1)
					(thickness 0.15)
				)
				(justify mirror)
			)
		)
		(property "Manufacturer" "Bourns"
			(at 187.864999 431.784999 0)
			(layer "B.Fab")
			(hide yes)
			(effects
				(font
					(size 1 1)
					(thickness 0.15)
				)
				(justify mirror)
			)
		)
		(property "Public" "False"
			(at 187.864999 431.784999 0)
			(layer "B.Fab")
			(hide yes)
			(effects
				(font
					(size 1 1)
					(thickness 0.15)
				)
				(justify mirror)
			)
		)
		(property "Tolerance" "1%"
			(at 187.864999 431.784999 0)
			(layer "B.Fab")
			(hide yes)
			(effects
				(font
					(size 1 1)
					(thickness 0.15)
				)
				(justify mirror)
			)
		)
		(property "Val" "68k"
			(at 187.864999 431.784999 0)
			(layer "B.Fab")
			(hide yes)
			(effects
				(font
					(size 1 1)
					(thickness 0.15)
				)
				(justify mirror)
			)
		)
		(sheetname "Power")
		(sheetfile "power.kicad_sch")
		(attr smd dnp)
		(fp_rect
			(start -0.925 0.47)
			(end 0.925 -0.47)
			(stroke
				(width 0.05)
				(type default)
			)
			(fill no)
			(layer "B.CrtYd")
		)
		(fp_rect
			(start -0.5 0.25)
			(end 0.5 -0.25)
			(stroke
				(width 0.15)
				(type solid)
			)
			(fill no)
			(layer "B.Fab")
		)
		(pad "1" smd roundrect
			(at -0.48 0 270)
			(size 0.59 0.64)
			(layers "B.Cu" "B.Mask" "B.Paste")
			(roundrect_rratio 0.25)
			(net 575 "Net-(U18-MODE)")
			(pintype "passive")
			(teardrops
				(best_length_ratio 0.2)
				(max_length 1)
				(best_width_ratio 0.9)
				(max_width 2)
				(curved_edges yes)
				(filter_ratio 0.9)
				(enabled yes)
				(allow_two_segments yes)
				(prefer_zone_connections yes)
			)
		)
		(pad "2" smd roundrect
			(at 0.48 0 270)
			(size 0.59 0.64)
			(layers "B.Cu" "B.Mask" "B.Paste")
			(roundrect_rratio 0.25)
			(net 63 "Net-(U18-V_{CC})")
			(pintype "passive")
			(teardrops
				(best_length_ratio 0.2)
				(max_length 1)
				(best_width_ratio 0.9)
				(max_width 2)
				(curved_edges yes)
				(filter_ratio 0.9)
				(enabled yes)
				(allow_two_segments yes)
				(prefer_zone_connections yes)
			)
		)
	)
	(footprint "antmicro-footprints:TP_SMD_0.75mm"
		(layer "B.Cu")
		(at 145.35 167.21 180)
		(property "Reference" "TP5"
			(at -2.45 -0.4 0)
			(layer "B.SilkS")
			(effects
				(font
					(size 0.7 0.7)
					(thickness 0.15)
				)
				(justify left bottom mirror)
			)
		)
		(property "Value" "TP_0.75mm_SMD"
			(at 0 -1.2 0)
			(layer "B.Fab")
			(effects
				(font
					(size 0.7 0.7)
					(thickness 0.15)
				)
				(justify left bottom mirror)
			)
		)
		(property "Author" "Antmicro"
			(at 290.7 334.42 0)
			(layer "B.Fab")
			(hide yes)
			(effects
				(font
					(size 1 1)
					(thickness 0.15)
				)
				(justify mirror)
			)
		)
		(property "License" "Apache-2.0"
			(at 290.7 334.42 0)
			(layer "B.Fab")
			(hide yes)
			(effects
				(font
					(size 1 1)
					(thickness 0.15)
				)
				(justify mirror)
			)
		)
		(property "MPN" ""
			(at 290.7 334.42 0)
			(layer "B.Fab")
			(hide yes)
			(effects
				(font
					(size 1 1)
					(thickness 0.15)
				)
				(justify mirror)
			)
		)
		(property "Manufacturer" ""
			(at 290.7 334.42 0)
			(layer "B.Fab")
			(hide yes)
			(effects
				(font
					(size 1 1)
					(thickness 0.15)
				)
				(justify mirror)
			)
		)
		(property "Public" "False"
			(at 290.7 334.42 0)
			(layer "B.Fab")
			(hide yes)
			(effects
				(font
					(size 1 1)
					(thickness 0.15)
				)
				(justify mirror)
			)
		)
		(sheetname "2xSFP+")
		(sheetfile "2xSFP+.kicad_sch")
		(attr exclude_from_pos_files exclude_from_bom)
		(fp_circle
			(center 0 0)
			(end 0.475 0)
			(stroke
				(width 0.05)
				(type default)
			)
			(fill no)
			(layer "B.CrtYd")
		)
		(pad "1" smd circle
			(at 0 0 180)
			(size 0.75 0.75)
			(layers "B.Cu" "B.Mask")
			(net 168 "Net-(J2A-RX_{LOS})")
			(pinfunction "1")
			(pintype "passive")
			(teardrops
				(best_length_ratio 0.4)
				(max_length 1)
				(best_width_ratio 0.9)
				(max_width 2)
				(curved_edges yes)
				(filter_ratio 0.9)
				(enabled yes)
				(allow_two_segments yes)
				(prefer_zone_connections yes)
			)
		)
	)
	(footprint "antmicro-footprints:C_0402_1005Metric"
		(layer "B.Cu")
		(at 151.45 132.36 -90)
		(descr "Capacitor SMD 0402")
		(tags "capacitor SMD 0402")
		(property "Reference" "C165"
			(at -3.65 -0.45 90)
			(layer "B.SilkS")
			(effects
				(font
					(size 0.7 0.7)
					(thickness 0.15)
				)
				(justify left bottom mirror)
			)
		)
		(property "Value" "C_100n_0402"
			(at -1.022927 -2.155213 90)
			(layer "B.Fab")
			(effects
				(font
					(size 0.7 0.7)
					(thickness 0.15)
				)
				(justify left bottom mirror)
			)
		)
		(property "Datasheet" "https://www.murata.com/products/productdetail?partno=GRM155R61H104KE14%23"
			(at 0 0 270)
			(layer "F.Fab")
			(hide yes)
			(effects
				(font
					(size 1.27 1.27)
					(thickness 0.15)
				)
			)
		)
		(property "Author" "Antmicro"
			(at 19.09 283.81 0)
			(layer "B.Fab")
			(hide yes)
			(effects
				(font
					(size 1 1)
					(thickness 0.15)
				)
				(justify mirror)
			)
		)
		(property "Dielectric" "X5R"
			(at 19.09 283.81 0)
			(layer "B.Fab")
			(hide yes)
			(effects
				(font
					(size 1 1)
					(thickness 0.15)
				)
				(justify mirror)
			)
		)
		(property "License" "Apache-2.0"
			(at 19.09 283.81 0)
			(layer "B.Fab")
			(hide yes)
			(effects
				(font
					(size 1 1)
					(thickness 0.15)
				)
				(justify mirror)
			)
		)
		(property "MPN" "GRM155R61H104KE14D"
			(at 19.09 283.81 0)
			(layer "B.Fab")
			(hide yes)
			(effects
				(font
					(size 1 1)
					(thickness 0.15)
				)
				(justify mirror)
			)
		)
		(property "Manufacturer" "Murata"
			(at 19.09 283.81 0)
			(layer "B.Fab")
			(hide yes)
			(effects
				(font
					(size 1 1)
					(thickness 0.15)
				)
				(justify mirror)
			)
		)
		(property "Public" "False"
			(at 19.09 283.81 0)
			(layer "B.Fab")
			(hide yes)
			(effects
				(font
					(size 1 1)
					(thickness 0.15)
				)
				(justify mirror)
			)
		)
		(property "Val" "100n"
			(at 19.09 283.81 0)
			(layer "B.Fab")
			(hide yes)
			(effects
				(font
					(size 1 1)
					(thickness 0.15)
				)
				(justify mirror)
			)
		)
		(property "Voltage" "50V"
			(at 19.09 283.81 0)
			(layer "B.Fab")
			(hide yes)
			(effects
				(font
					(size 1 1)
					(thickness 0.15)
				)
				(justify mirror)
			)
		)
		(sheetname "KR to SFI #1")
		(sheetfile "kr_sfi.kicad_sch")
		(attr smd)
		(fp_rect
			(start -0.925 0.47)
			(end 0.925 -0.47)
			(stroke
				(width 0.05)
				(type default)
			)
			(fill no)
			(layer "B.CrtYd")
		)
		(fp_line
			(start -0.494 0.25)
			(end -0.494 -0.248)
			(stroke
				(width 0.15)
				(type solid)
			)
			(layer "B.Fab")
		)
		(fp_line
			(start 0.504 0.25)
			(end -0.494 0.25)
			(stroke
				(width 0.15)
				(type solid)
			)
			(layer "B.Fab")
		)
		(fp_line
			(start -0.494 -0.248)
			(end 0.504 -0.248)
			(stroke
				(width 0.15)
				(type solid)
			)
			(layer "B.Fab")
		)
		(fp_line
			(start 0.504 -0.248)
			(end 0.504 0.25)
			(stroke
				(width 0.15)
				(type solid)
			)
			(layer "B.Fab")
		)
		(pad "1" smd roundrect
			(at -0.48 0 270)
			(size 0.59 0.64)
			(layers "B.Cu" "B.Mask" "B.Paste")
			(roundrect_rratio 0.25)
			(net 1 "GND")
			(pintype "passive")
			(teardrops
				(best_length_ratio 0.2)
				(max_length 1)
				(best_width_ratio 0.9)
				(max_width 2)
				(curved_edges yes)
				(filter_ratio 0.9)
				(enabled yes)
				(allow_two_segments yes)
				(prefer_zone_connections yes)
			)
		)
		(pad "2" smd roundrect
			(at 0.48 0 270)
			(size 0.59 0.64)
			(layers "B.Cu" "B.Mask" "B.Paste")
			(roundrect_rratio 0.25)
			(net 74 "+1V0")
			(pintype "passive")
			(teardrops
				(best_length_ratio 0.2)
				(max_length 1)
				(best_width_ratio 0.9)
				(max_width 2)
				(curved_edges yes)
				(filter_ratio 0.9)
				(enabled yes)
				(allow_two_segments yes)
				(prefer_zone_connections yes)
			)
		)
	)
	(footprint "antmicro-footprints:C_0603_1608Metric"
		(layer "B.Cu")
		(at 218.15 128.85)
		(descr "Capacitor SMD 0603")
		(tags "capacitor 0603")
		(property "Reference" "C106"
			(at 1.15 0.81 0)
			(layer "B.SilkS")
			(effects
				(font
					(size 0.7 0.7)
					(thickness 0.15)
				)
				(justify right bottom mirror)
			)
		)
		(property "Value" "C_22u_16V_0603"
			(at -1.42757 -1.770288 0)
			(layer "B.Fab")
			(effects
				(font
					(size 0.7 0.7)
					(thickness 0.15)
				)
				(justify right bottom mirror)
			)
		)
		(property "Datasheet" "https://product.samsungsem.com/mlcc/CL10A226MO7JZN.do"
			(at 0 0 0)
			(layer "F.Fab")
			(hide yes)
			(effects
				(font
					(size 1.27 1.27)
					(thickness 0.15)
				)
			)
		)
		(property "Author" "Antmicro"
			(at 0 0 0)
			(layer "B.Fab")
			(hide yes)
			(effects
				(font
					(size 1 1)
					(thickness 0.15)
				)
				(justify mirror)
			)
		)
		(property "Dielectric" ""
			(at 0 0 0)
			(layer "B.Fab")
			(hide yes)
			(effects
				(font
					(size 1 1)
					(thickness 0.15)
				)
				(justify mirror)
			)
		)
		(property "License" "Apache-2.0"
			(at 0 0 0)
			(layer "B.Fab")
			(hide yes)
			(effects
				(font
					(size 1 1)
					(thickness 0.15)
				)
				(justify mirror)
			)
		)
		(property "MPN" "CL10A226MO7JZNC"
			(at 0 0 0)
			(layer "B.Fab")
			(hide yes)
			(effects
				(font
					(size 1 1)
					(thickness 0.15)
				)
				(justify mirror)
			)
		)
		(property "Manufacturer" "Samsung Electro-Mechanics"
			(at 0 0 0)
			(layer "B.Fab")
			(hide yes)
			(effects
				(font
					(size 1 1)
					(thickness 0.15)
				)
				(justify mirror)
			)
		)
		(property "Public" "False"
			(at 0 0 0)
			(layer "B.Fab")
			(hide yes)
			(effects
				(font
					(size 1 1)
					(thickness 0.15)
				)
				(justify mirror)
			)
		)
		(property "Val" "22u"
			(at 0 0 0)
			(layer "B.Fab")
			(hide yes)
			(effects
				(font
					(size 1 1)
					(thickness 0.15)
				)
				(justify mirror)
			)
		)
		(property "Voltage" "16V"
			(at 0 0 0)
			(layer "B.Fab")
			(hide yes)
			(effects
				(font
					(size 1 1)
					(thickness 0.15)
				)
				(justify mirror)
			)
		)
		(sheetname "PCIe misc")
		(sheetfile "pcie_misc.kicad_sch")
		(attr smd)
		(fp_line
			(start 0.15 -0.4)
			(end -0.15 -0.4)
			(stroke
				(width 0.15)
				(type solid)
			)
			(layer "B.SilkS")
		)
		(fp_line
			(start 0.15 0.4)
			(end -0.15 0.4)
			(stroke
				(width 0.15)
				(type solid)
			)
			(layer "B.SilkS")
		)
		(fp_rect
			(start -1.25 0.65)
			(end 1.25 -0.65)
			(stroke
				(width 0.05)
				(type solid)
			)
			(fill no)
			(layer "B.CrtYd")
		)
		(fp_rect
			(start -0.8 0.4)
			(end 0.8 -0.4)
			(stroke
				(width 0.15)
				(type solid)
			)
			(fill no)
			(layer "B.Fab")
		)
		(pad "1" smd roundrect
			(at -0.7 0)
			(size 0.8 1)
			(layers "B.Cu" "B.Mask" "B.Paste")
			(roundrect_rratio 0.2)
			(net 1 "GND")
			(pintype "passive")
			(teardrops
				(best_length_ratio 0.2)
				(max_length 1)
				(best_width_ratio 0.9)
				(max_width 2)
				(curved_edges yes)
				(filter_ratio 0.9)
				(enabled yes)
				(allow_two_segments yes)
				(prefer_zone_connections yes)
			)
		)
		(pad "2" smd roundrect
			(at 0.7 0)
			(size 0.8 1)
			(layers "B.Cu" "B.Mask" "B.Paste")
			(roundrect_rratio 0.2)
			(net 2 "+3V3")
			(pintype "passive")
			(teardrops
				(best_length_ratio 0.2)
				(max_length 1)
				(best_width_ratio 0.9)
				(max_width 2)
				(curved_edges yes)
				(filter_ratio 0.9)
				(enabled yes)
				(allow_two_segments yes)
				(prefer_zone_connections yes)
			)
		)
	)
	(footprint "antmicro-footprints:Amphenol_G14A421211112HR"
		(layer "B.Cu")
		(at 98.16 162.355 90)
		(property "Reference" "J4"
			(at 8.5 -1.885 0)
			(unlocked yes)
			(layer "B.SilkS")
			(effects
				(font
					(size 0.7 0.7)
					(thickness 0.15)
				)
				(justify left bottom mirror)
			)
		)
		(property "Value" "OCuLink_x4_Amphenol_G14A421211112HR"
			(at 0 -6.385 270)
			(unlocked yes)
			(layer "B.Fab")
			(effects
				(font
					(size 0.7 0.7)
					(thickness 0.15)
				)
				(justify left bottom mirror)
			)
		)
		(property "Datasheet" "https://cdn.amphenol-cs.com/media/wysiwyg/files/drawing/g14a421x1bxxxhr.pdf"
			(at 0 0 90)
			(layer "F.Fab")
			(hide yes)
			(effects
				(font
					(size 1.27 1.27)
					(thickness 0.15)
				)
			)
		)
		(property "Author" "Antmicro"
			(at 260.515 64.195 0)
			(layer "B.Fab")
			(hide yes)
			(effects
				(font
					(size 1 1)
					(thickness 0.15)
				)
				(justify mirror)
			)
		)
		(property "License" "Apache-2.0"
			(at 260.515 64.195 0)
			(layer "B.Fab")
			(hide yes)
			(effects
				(font
					(size 1 1)
					(thickness 0.15)
				)
				(justify mirror)
			)
		)
		(property "MPN" "G14A421211112HR"
			(at 260.515 64.195 0)
			(layer "B.Fab")
			(hide yes)
			(effects
				(font
					(size 1 1)
					(thickness 0.15)
				)
				(justify mirror)
			)
		)
		(property "Manufacturer" "Amphenol"
			(at 260.515 64.195 0)
			(layer "B.Fab")
			(hide yes)
			(effects
				(font
					(size 1 1)
					(thickness 0.15)
				)
				(justify mirror)
			)
		)
		(sheetname "OCuLink")
		(sheetfile "oculink.kicad_sch")
		(solder_paste_margin -0.06)
		(attr smd)
		(fp_line
			(start 6.8 0.4)
			(end 6.8 3)
			(stroke
				(width 0.1)
				(type default)
			)
			(layer "B.SilkS")
		)
		(fp_line
			(start -6.8 3)
			(end -6.8 0.4)
			(stroke
				(width 0.1)
				(type default)
			)
			(layer "B.SilkS")
		)
		(fp_circle
			(center -5.3 5.52)
			(end -5.25 5.52)
			(stroke
				(width 0.15)
				(type solid)
			)
			(fill yes)
			(layer "B.SilkS")
		)
		(fp_rect
			(start -8.22 5.22)
			(end 8.22 -4.94)
			(stroke
				(width 0.05)
				(type solid)
			)
			(fill no)
			(layer "B.CrtYd")
		)
		(fp_line
			(start -7 -3.065)
			(end 7 -3.065)
			(stroke
				(width 0.1)
				(type default)
			)
			(layer "B.Fab")
		)
		(fp_text user "PCB EDGE"
			(at 2.8 -2.95 270)
			(unlocked yes)
			(layer "B.Fab")
			(effects
				(font
					(size 0.5 0.5)
					(thickness 0.125)
				)
				(justify left bottom mirror)
			)
		)
		(pad "" np_thru_hole circle
			(at -5.42 1.395 180)
			(size 0.95 0.91)
			(drill 0.95)
			(layers "F&B.Cu" "*.Mask")
		)
		(pad "" np_thru_hole circle
			(at 5.95 1.395)
			(size 0.95 1)
			(drill 0.95)
			(layers "F&B.Cu" "*.Mask")
		)
		(pad "A1" smd roundrect
			(at -4.75 2.115)
			(size 0.875 0.3)
			(layers "B.Cu" "B.Mask" "B.Paste")
			(roundrect_rratio 0.5)
			(chamfer_ratio 0.5)
			(chamfer bottom_left)
			(net 60 "/OCuLink/V_{ACT_RX}0")
			(pinfunction "V_{ACT}_RX_3V3")
			(pintype "power_in")
		)
		(pad "A2" smd roundrect
			(at -4.25 2.115)
			(size 0.91 0.31)
			(layers "B.Cu" "B.Mask" "B.Paste")
			(roundrect_rratio 0.5)
			(net 1 "GND")
			(pinfunction "GND")
			(pintype "passive")
		)
		(pad "A3" smd roundrect
			(at -3.75 2.115)
			(size 0.91 0.31)
			(layers "B.Cu" "B.Mask" "B.Paste")
			(roundrect_rratio 0.5)
			(net 186 "/OCuLink/PCIe_{x4}.RX0+")
			(pinfunction "PER0+")
			(pintype "output")
		)
		(pad "A4" smd roundrect
			(at -3.25 2.115)
			(size 0.91 0.31)
			(layers "B.Cu" "B.Mask" "B.Paste")
			(roundrect_rratio 0.5)
			(net 187 "/OCuLink/PCIe_{x4}.RX0-")
			(pinfunction "PER0-")
			(pintype "output")
		)
		(pad "A5" smd roundrect
			(at -2.75 2.115)
			(size 0.91 0.31)
			(layers "B.Cu" "B.Mask" "B.Paste")
			(roundrect_rratio 0.5)
			(net 1 "GND")
			(pinfunction "GND")
			(pintype "passive")
		)
		(pad "A6" smd roundrect
			(at -2.25 2.115)
			(size 0.91 0.31)
			(layers "B.Cu" "B.Mask" "B.Paste")
			(roundrect_rratio 0.5)
			(net 188 "/OCuLink/PCIe_{x4}.RX1+")
			(pinfunction "PER1+")
			(pintype "output")
		)
		(pad "A7" smd roundrect
			(at -1.75 2.115)
			(size 0.91 0.31)
			(layers "B.Cu" "B.Mask" "B.Paste")
			(roundrect_rratio 0.5)
			(net 189 "/OCuLink/PCIe_{x4}.RX1-")
			(pinfunction "PER1-")
			(pintype "output")
		)
		(pad "A8" smd roundrect
			(at -1.25 2.115)
			(size 0.91 0.31)
			(layers "B.Cu" "B.Mask" "B.Paste")
			(roundrect_rratio 0.5)
			(net 1 "GND")
			(pinfunction "GND")
			(pintype "passive")
		)
		(pad "A9" smd roundrect
			(at -0.75 2.115)
			(size 0.91 0.31)
			(layers "B.Cu" "B.Mask" "B.Paste")
			(roundrect_rratio 0.5)
			(net 190 "unconnected-(J4-NC-PadA9)")
			(pinfunction "NC")
			(pintype "no_connect")
		)
		(pad "A10" smd roundrect
			(at -0.25 2.115)
			(size 0.91 0.31)
			(layers "B.Cu" "B.Mask" "B.Paste")
			(roundrect_rratio 0.5)
			(net 191 "unconnected-(J4-~{CWAKE}-PadA10)")
			(pinfunction "~{CWAKE}")
			(pintype "bidirectional+no_connect")
		)
		(pad "A11" smd roundrect
			(at 0.25 2.115)
			(size 0.91 0.31)
			(layers "B.Cu" "B.Mask" "B.Paste")
			(roundrect_rratio 0.5)
			(net 1 "GND")
			(pinfunction "GND")
			(pintype "passive")
		)
		(pad "A12" smd roundrect
			(at 0.75 2.115)
			(size 0.91 0.31)
			(layers "B.Cu" "B.Mask" "B.Paste")
			(roundrect_rratio 0.5)
			(net 192 "/OCuLink/PCIe_{REF0}.CK+")
			(pinfunction "VSP1")
			(pintype "bidirectional")
		)
		(pad "A13" smd roundrect
			(at 1.25 2.115)
			(size 0.91 0.31)
			(layers "B.Cu" "B.Mask" "B.Paste")
			(roundrect_rratio 0.5)
			(net 193 "/OCuLink/PCIe_{REF0}.CK-")
			(pinfunction "VSP2")
			(pintype "bidirectional")
		)
		(pad "A14" smd roundrect
			(at 1.75 2.115)
			(size 0.91 0.31)
			(layers "B.Cu" "B.Mask" "B.Paste")
			(roundrect_rratio 0.5)
			(net 1 "GND")
			(pinfunction "GND")
			(pintype "passive")
		)
		(pad "A15" smd roundrect
			(at 2.25 2.115)
			(size 0.91 0.31)
			(layers "B.Cu" "B.Mask" "B.Paste")
			(roundrect_rratio 0.5)
			(net 194 "/OCuLink/PCIe_{x4}.RX2+")
			(pinfunction "PER2+")
			(pintype "output")
		)
		(pad "A16" smd roundrect
			(at 2.75 2.115)
			(size 0.91 0.31)
			(layers "B.Cu" "B.Mask" "B.Paste")
			(roundrect_rratio 0.5)
			(net 195 "/OCuLink/PCIe_{x4}.RX2-")
			(pinfunction "PER2-")
			(pintype "output")
		)
		(pad "A17" smd roundrect
			(at 3.25 2.115)
			(size 0.91 0.31)
			(layers "B.Cu" "B.Mask" "B.Paste")
			(roundrect_rratio 0.5)
			(net 1 "GND")
			(pinfunction "GND")
			(pintype "passive")
		)
		(pad "A18" smd roundrect
			(at 3.75 2.115)
			(size 0.91 0.31)
			(layers "B.Cu" "B.Mask" "B.Paste")
			(roundrect_rratio 0.5)
			(net 196 "/OCuLink/PCIe_{x4}.RX3+")
			(pinfunction "PER3+")
			(pintype "output")
		)
		(pad "A19" smd roundrect
			(at 4.25 2.115)
			(size 0.91 0.31)
			(layers "B.Cu" "B.Mask" "B.Paste")
			(roundrect_rratio 0.5)
			(net 197 "/OCuLink/PCIe_{x4}.RX3-")
			(pinfunction "PER3-")
			(pintype "output")
		)
		(pad "A20" smd roundrect
			(at 4.75 2.115)
			(size 0.91 0.31)
			(layers "B.Cu" "B.Mask" "B.Paste")
			(roundrect_rratio 0.5)
			(net 1 "GND")
			(pinfunction "GND")
			(pintype "passive")
		)
		(pad "A21" smd roundrect
			(at 5.25 2.115)
			(size 0.91 0.31)
			(layers "B.Cu" "B.Mask" "B.Paste")
			(roundrect_rratio 0.5)
			(chamfer_ratio 0.5)
			(chamfer top_left)
			(net 61 "/OCuLink/5V_CONN0")
			(pinfunction "5V")
			(pintype "passive")
		)
		(pad "B1" smd roundrect
			(at -5.25 4.305)
			(size 0.91 0.31)
			(layers "B.Cu" "B.Mask" "B.Paste")
			(roundrect_rratio 0.5)
			(net 61 "/OCuLink/5V_CONN0")
			(pinfunction "5V")
			(pintype "passive")
		)
		(pad "B2" smd roundrect
			(at -4.75 4.305)
			(size 0.91 0.31)
			(layers "B.Cu" "B.Mask" "B.Paste")
			(roundrect_rratio 0.5)
			(net 1 "GND")
			(pinfunction "GND")
			(pintype "passive")
		)
		(pad "B3" smd roundrect
			(at -4.25 4.305)
			(size 0.91 0.31)
			(layers "B.Cu" "B.Mask" "B.Paste")
			(roundrect_rratio 0.5)
			(net 100 "/OCuLink/PCIe_{x4}.TX0+")
			(pinfunction "PET0+")
			(pintype "input")
		)
		(pad "B4" smd roundrect
			(at -3.75 4.305)
			(size 0.91 0.31)
			(layers "B.Cu" "B.Mask" "B.Paste")
			(roundrect_rratio 0.5)
			(net 95 "/OCuLink/PCIe_{x4}.TX0-")
			(pinfunction "PET0-")
			(pintype "input")
		)
		(pad "B5" smd roundrect
			(at -3.25 4.305)
			(size 0.91 0.31)
			(layers "B.Cu" "B.Mask" "B.Paste")
			(roundrect_rratio 0.5)
			(net 1 "GND")
			(pinfunction "GND")
			(pintype "passive")
		)
		(pad "B6" smd roundrect
			(at -2.75 4.305)
			(size 0.91 0.31)
			(layers "B.Cu" "B.Mask" "B.Paste")
			(roundrect_rratio 0.5)
			(net 102 "/OCuLink/PCIe_{x4}.TX1+")
			(pinfunction "PET1+")
			(pintype "input")
		)
		(pad "B7" smd roundrect
			(at -2.25 4.305)
			(size 0.91 0.31)
			(layers "B.Cu" "B.Mask" "B.Paste")
			(roundrect_rratio 0.5)
			(net 96 "/OCuLink/PCIe_{x4}.TX1-")
			(pinfunction "PET1-")
			(pintype "input")
		)
		(pad "B8" smd roundrect
			(at -1.75 4.305)
			(size 0.91 0.31)
			(layers "B.Cu" "B.Mask" "B.Paste")
			(roundrect_rratio 0.5)
			(net 1 "GND")
			(pinfunction "GND")
			(pintype "passive")
		)
		(pad "B9" smd roundrect
			(at -1.25 4.305)
			(size 0.91 0.31)
			(layers "B.Cu" "B.Mask" "B.Paste")
			(roundrect_rratio 0.5)
			(net 198 "/OCuLink/SCL")
			(pinfunction "SCL")
			(pintype "bidirectional")
		)
		(pad "B10" smd roundrect
			(at -0.75 4.305)
			(size 0.91 0.31)
			(layers "B.Cu" "B.Mask" "B.Paste")
			(roundrect_rratio 0.5)
			(net 199 "/OCuLink/SDA")
			(pinfunction "SDA")
			(pintype "bidirectional")
		)
		(pad "B11" smd roundrect
			(at -0.25 4.305)
			(size 0.91 0.31)
			(layers "B.Cu" "B.Mask" "B.Paste")
			(roundrect_rratio 0.5)
			(net 1 "GND")
			(pinfunction "GND")
			(pintype "passive")
		)
		(pad "B12" smd roundrect
			(at 0.25 4.305)
			(size 0.91 0.31)
			(layers "B.Cu" "B.Mask" "B.Paste")
			(roundrect_rratio 0.5)
			(net 200 "/OCuLink/~{PERST_D0}")
			(pinfunction "~{PERST}")
			(pintype "bidirectional")
		)
		(pad "B13" smd roundrect
			(at 0.75 4.305)
			(size 0.91 0.31)
			(layers "B.Cu" "B.Mask" "B.Paste")
			(roundrect_rratio 0.5)
			(net 201 "/OCuLink/~{CPRSNT_D0}")
			(pinfunction "~{CPRSNT}")
			(pintype "bidirectional")
		)
		(pad "B14" smd roundrect
			(at 1.25 4.305)
			(size 0.91 0.31)
			(layers "B.Cu" "B.Mask" "B.Paste")
			(roundrect_rratio 0.5)
			(net 1 "GND")
			(pinfunction "GND")
			(pintype "passive")
		)
		(pad "B15" smd roundrect
			(at 1.75 4.305)
			(size 0.91 0.31)
			(layers "B.Cu" "B.Mask" "B.Paste")
			(roundrect_rratio 0.5)
			(net 104 "/OCuLink/PCIe_{x4}.TX2+")
			(pinfunction "PET2+")
			(pintype "input")
		)
		(pad "B16" smd roundrect
			(at 2.25 4.305)
			(size 0.91 0.31)
			(layers "B.Cu" "B.Mask" "B.Paste")
			(roundrect_rratio 0.5)
			(net 97 "/OCuLink/PCIe_{x4}.TX2-")
			(pinfunction "PET2-")
			(pintype "input")
		)
		(pad "B17" smd roundrect
			(at 2.75 4.305)
			(size 0.91 0.31)
			(layers "B.Cu" "B.Mask" "B.Paste")
			(roundrect_rratio 0.5)
			(net 1 "GND")
			(pinfunction "GND")
			(pintype "passive")
		)
		(pad "B18" smd roundrect
			(at 3.25 4.305)
			(size 0.91 0.31)
			(layers "B.Cu" "B.Mask" "B.Paste")
			(roundrect_rratio 0.5)
			(net 106 "/OCuLink/PCIe_{x4}.TX3+")
			(pinfunction "PET3+")
			(pintype "input")
		)
		(pad "B19" smd roundrect
			(at 3.75 4.305)
			(size 0.91 0.31)
			(layers "B.Cu" "B.Mask" "B.Paste")
			(roundrect_rratio 0.5)
			(net 98 "/OCuLink/PCIe_{x4}.TX3-")
			(pinfunction "PET3-")
			(pintype "input")
		)
		(pad "B20" smd roundrect
			(at 4.25 4.305)
			(size 0.91 0.31)
			(layers "B.Cu" "B.Mask" "B.Paste")
			(roundrect_rratio 0.5)
			(net 1 "GND")
			(pinfunction "GND")
			(pintype "passive")
		)
		(pad "B21" smd roundrect
			(at 4.75 4.305)
			(size 0.91 0.31)
			(layers "B.Cu" "B.Mask" "B.Paste")
			(roundrect_rratio 0.5)
			(net 59 "/OCuLink/V_{ACT_TX}0")
			(pinfunction "V_{ACT}_TX_3V3")
			(pintype "power_in")
		)
		(pad "SH" smd roundrect
			(at -6.91 -0.805)
			(size 1.81 1.8)
			(layers "B.Cu" "B.Mask" "B.Paste")
			(roundrect_rratio 0.1)
			(net 1 "GND")
			(pinfunction "SH")
			(pintype "passive")
		)
		(pad "SH" smd roundrect
			(at -6.91 3.915)
			(size 1.38 1.81)
			(layers "B.Cu" "B.Mask" "B.Paste")
			(roundrect_rratio 0.1)
			(net 1 "GND")
			(pinfunction "SH")
			(pintype "passive")
		)
		(pad "SH" smd roundrect
			(at 6.91 -0.805)
			(size 1.81 1.8)
			(layers "B.Cu" "B.Mask" "B.Paste")
			(roundrect_rratio 0.1)
			(net 1 "GND")
			(pinfunction "SH")
			(pintype "passive")
		)
		(pad "SH" smd roundrect
			(at 6.91 3.915)
			(size 1.38 1.81)
			(layers "B.Cu" "B.Mask" "B.Paste")
			(roundrect_rratio 0.1)
			(net 1 "GND")
			(pinfunction "SH")
			(pintype "passive")
		)
	)
	(footprint "antmicro-footprints:R_0402_1005Metric"
		(layer "B.Cu")
		(at 139.74 139.36)
		(descr "Resistor SMD 0402")
		(tags "resistor SMD 0402")
		(property "Reference" "R298"
			(at -3.64 0.75 0)
			(layer "B.SilkS")
			(effects
				(font
					(size 0.7 0.7)
					(thickness 0.15)
				)
				(justify right bottom mirror)
			)
		)
		(property "Value" "R_10k_0402"
			(at -1.011843 -1.772047 0)
			(layer "B.Fab")
			(effects
				(font
					(size 0.7 0.7)
					(thickness 0.15)
				)
				(justify right bottom mirror)
			)
		)
		(property "Datasheet" "https://www.bourns.com/docs/product-datasheets/cr.pdf"
			(at 0 0 0)
			(layer "F.Fab")
			(hide yes)
			(effects
				(font
					(size 1.27 1.27)
					(thickness 0.15)
				)
			)
		)
		(property "Author" "Antmicro"
			(at 0 0 0)
			(layer "B.Fab")
			(hide yes)
			(effects
				(font
					(size 1 1)
					(thickness 0.15)
				)
				(justify mirror)
			)
		)
		(property "License" "Apache-2.0"
			(at 0 0 0)
			(layer "B.Fab")
			(hide yes)
			(effects
				(font
					(size 1 1)
					(thickness 0.15)
				)
				(justify mirror)
			)
		)
		(property "MPN" "CR0402-FX-1002GLF"
			(at 0 0 0)
			(layer "B.Fab")
			(hide yes)
			(effects
				(font
					(size 1 1)
					(thickness 0.15)
				)
				(justify mirror)
			)
		)
		(property "Manufacturer" "Bourns"
			(at 0 0 0)
			(layer "B.Fab")
			(hide yes)
			(effects
				(font
					(size 1 1)
					(thickness 0.15)
				)
				(justify mirror)
			)
		)
		(property "Public" "False"
			(at 0 0 0)
			(layer "B.Fab")
			(hide yes)
			(effects
				(font
					(size 1 1)
					(thickness 0.15)
				)
				(justify mirror)
			)
		)
		(property "Tolerance" "1%"
			(at 0 0 0)
			(layer "B.Fab")
			(hide yes)
			(effects
				(font
					(size 1 1)
					(thickness 0.15)
				)
				(justify mirror)
			)
		)
		(property "Val" "10k"
			(at 0 0 0)
			(layer "B.Fab")
			(hide yes)
			(effects
				(font
					(size 1 1)
					(thickness 0.15)
				)
				(justify mirror)
			)
		)
		(sheetname "KR to SFI #2")
		(sheetfile "kr_sfi.kicad_sch")
		(attr smd)
		(fp_rect
			(start -0.925 0.47)
			(end 0.925 -0.47)
			(stroke
				(width 0.05)
				(type default)
			)
			(fill no)
			(layer "B.CrtYd")
		)
		(fp_rect
			(start -0.5 0.25)
			(end 0.5 -0.25)
			(stroke
				(width 0.15)
				(type solid)
			)
			(fill no)
			(layer "B.Fab")
		)
		(pad "1" smd roundrect
			(at -0.48 0)
			(size 0.59 0.64)
			(layers "B.Cu" "B.Mask" "B.Paste")
			(roundrect_rratio 0.25)
			(net 678 "Net-(U45A-~{PDTRXA})")
			(pintype "passive")
			(teardrops
				(best_length_ratio 0.2)
				(max_length 1)
				(best_width_ratio 0.9)
				(max_width 2)
				(curved_edges yes)
				(filter_ratio 0.9)
				(enabled yes)
				(allow_two_segments yes)
				(prefer_zone_connections yes)
			)
		)
		(pad "2" smd roundrect
			(at 0.48 0)
			(size 0.59 0.64)
			(layers "B.Cu" "B.Mask" "B.Paste")
			(roundrect_rratio 0.25)
			(net 78 "+1V8")
			(pintype "passive")
			(teardrops
				(best_length_ratio 0.2)
				(max_length 1)
				(best_width_ratio 0.9)
				(max_width 2)
				(curved_edges yes)
				(filter_ratio 0.9)
				(enabled yes)
				(allow_two_segments yes)
				(prefer_zone_connections yes)
			)
		)
	)
	(footprint "antmicro-footprints:R_0402_1005Metric"
		(layer "B.Cu")
		(at 123.4 110.81 180)
		(descr "Resistor SMD 0402")
		(tags "resistor SMD 0402")
		(property "Reference" "R6"
			(at -2.35 -0.45 0)
			(layer "B.SilkS")
			(effects
				(font
					(size 0.7 0.7)
					(thickness 0.15)
				)
				(justify left bottom mirror)
			)
		)
		(property "Value" "R_0R_0402"
			(at -1.011843 -1.772047 0)
			(layer "B.Fab")
			(effects
				(font
					(size 0.7 0.7)
					(thickness 0.15)
				)
				(justify left bottom mirror)
			)
		)
		(property "Datasheet" "https://industrial.panasonic.com/cdbs/www-data/pdf/RDA0000/AOA0000C301.pdf"
			(at 0 0 180)
			(layer "F.Fab")
			(hide yes)
			(effects
				(font
					(size 1.27 1.27)
					(thickness 0.15)
				)
			)
		)
		(property "Author" "Antmicro"
			(at 246.8 221.62 0)
			(layer "B.Fab")
			(hide yes)
			(effects
				(font
					(size 1 1)
					(thickness 0.15)
				)
				(justify mirror)
			)
		)
		(property "Current" "1A"
			(at 246.8 221.62 0)
			(layer "B.Fab")
			(hide yes)
			(effects
				(font
					(size 1 1)
					(thickness 0.15)
				)
				(justify mirror)
			)
		)
		(property "License" "Apache-2.0"
			(at 246.8 221.62 0)
			(layer "B.Fab")
			(hide yes)
			(effects
				(font
					(size 1 1)
					(thickness 0.15)
				)
				(justify mirror)
			)
		)
		(property "MPN" "ERJ2GE0R00X"
			(at 246.8 221.62 0)
			(layer "B.Fab")
			(hide yes)
			(effects
				(font
					(size 1 1)
					(thickness 0.15)
				)
				(justify mirror)
			)
		)
		(property "Manufacturer" "Panasonic"
			(at 246.8 221.62 0)
			(layer "B.Fab")
			(hide yes)
			(effects
				(font
					(size 1 1)
					(thickness 0.15)
				)
				(justify mirror)
			)
		)
		(property "Public" "False"
			(at 246.8 221.62 0)
			(layer "B.Fab")
			(hide yes)
			(effects
				(font
					(size 1 1)
					(thickness 0.15)
				)
				(justify mirror)
			)
		)
		(property "Tolerance" ""
			(at 246.8 221.62 0)
			(layer "B.Fab")
			(hide yes)
			(effects
				(font
					(size 1 1)
					(thickness 0.15)
				)
				(justify mirror)
			)
		)
		(property "Val" "0R"
			(at 246.8 221.62 0)
			(layer "B.Fab")
			(hide yes)
			(effects
				(font
					(size 1 1)
					(thickness 0.15)
				)
				(justify mirror)
			)
		)
		(sheetname "2xUSB3.0+RJ45")
		(sheetfile "usb3+rj45.kicad_sch")
		(attr smd dnp)
		(fp_rect
			(start -0.925 0.47)
			(end 0.925 -0.47)
			(stroke
				(width 0.05)
				(type default)
			)
			(fill no)
			(layer "B.CrtYd")
		)
		(fp_rect
			(start -0.5 0.25)
			(end 0.5 -0.25)
			(stroke
				(width 0.15)
				(type solid)
			)
			(fill no)
			(layer "B.Fab")
		)
		(pad "1" smd roundrect
			(at -0.48 0 180)
			(size 0.59 0.64)
			(layers "B.Cu" "B.Mask" "B.Paste")
			(roundrect_rratio 0.25)
			(net 291 "/2xUSB3.0+RJ45/~{GBE0_LINK}")
			(pintype "passive")
			(teardrops
				(best_length_ratio 0.2)
				(max_length 1)
				(best_width_ratio 0.9)
				(max_width 2)
				(curved_edges yes)
				(filter_ratio 0.9)
				(enabled yes)
				(allow_two_segments yes)
				(prefer_zone_connections yes)
			)
		)
		(pad "2" smd roundrect
			(at 0.48 0 180)
			(size 0.59 0.64)
			(layers "B.Cu" "B.Mask" "B.Paste")
			(roundrect_rratio 0.25)
			(net 156 "Net-(J1A-LED_D3)")
			(pintype "passive")
			(teardrops
				(best_length_ratio 0.2)
				(max_length 1)
				(best_width_ratio 0.9)
				(max_width 2)
				(curved_edges yes)
				(filter_ratio 0.9)
				(enabled yes)
				(allow_two_segments yes)
				(prefer_zone_connections yes)
			)
		)
	)
	(footprint "antmicro-footprints:R_0402_1005Metric"
		(layer "B.Cu")
		(at 157.9 140.36)
		(descr "Resistor SMD 0402")
		(tags "resistor SMD 0402")
		(property "Reference" "R252"
			(at 0.85 0.45 0)
			(layer "B.SilkS")
			(effects
				(font
					(size 0.7 0.7)
					(thickness 0.15)
				)
				(justify right bottom mirror)
			)
		)
		(property "Value" "R_10k_0402"
			(at -1.011843 -1.772047 0)
			(layer "B.Fab")
			(effects
				(font
					(size 0.7 0.7)
					(thickness 0.15)
				)
				(justify right bottom mirror)
			)
		)
		(property "Datasheet" "https://www.bourns.com/docs/product-datasheets/cr.pdf"
			(at 0 0 0)
			(layer "F.Fab")
			(hide yes)
			(effects
				(font
					(size 1.27 1.27)
					(thickness 0.15)
				)
			)
		)
		(property "Author" "Antmicro"
			(at 0 0 0)
			(layer "B.Fab")
			(hide yes)
			(effects
				(font
					(size 1 1)
					(thickness 0.15)
				)
				(justify mirror)
			)
		)
		(property "License" "Apache-2.0"
			(at 0 0 0)
			(layer "B.Fab")
			(hide yes)
			(effects
				(font
					(size 1 1)
					(thickness 0.15)
				)
				(justify mirror)
			)
		)
		(property "MPN" "CR0402-FX-1002GLF"
			(at 0 0 0)
			(layer "B.Fab")
			(hide yes)
			(effects
				(font
					(size 1 1)
					(thickness 0.15)
				)
				(justify mirror)
			)
		)
		(property "Manufacturer" "Bourns"
			(at 0 0 0)
			(layer "B.Fab")
			(hide yes)
			(effects
				(font
					(size 1 1)
					(thickness 0.15)
				)
				(justify mirror)
			)
		)
		(property "Public" "False"
			(at 0 0 0)
			(layer "B.Fab")
			(hide yes)
			(effects
				(font
					(size 1 1)
					(thickness 0.15)
				)
				(justify mirror)
			)
		)
		(property "Tolerance" "1%"
			(at 0 0 0)
			(layer "B.Fab")
			(hide yes)
			(effects
				(font
					(size 1 1)
					(thickness 0.15)
				)
				(justify mirror)
			)
		)
		(property "Val" "10k"
			(at 0 0 0)
			(layer "B.Fab")
			(hide yes)
			(effects
				(font
					(size 1 1)
					(thickness 0.15)
				)
				(justify mirror)
			)
		)
		(sheetname "KR to SFI #1")
		(sheetfile "kr_sfi.kicad_sch")
		(attr smd dnp)
		(fp_rect
			(start -0.925 0.47)
			(end 0.925 -0.47)
			(stroke
				(width 0.05)
				(type default)
			)
			(fill no)
			(layer "B.CrtYd")
		)
		(fp_rect
			(start -0.5 0.25)
			(end 0.5 -0.25)
			(stroke
				(width 0.15)
				(type solid)
			)
			(fill no)
			(layer "B.Fab")
		)
		(pad "1" smd roundrect
			(at -0.48 0)
			(size 0.59 0.64)
			(layers "B.Cu" "B.Mask" "B.Paste")
			(roundrect_rratio 0.25)
			(net 652 "/2xSFP+/KR to SFI #1/PRBSEN")
			(pintype "passive")
			(teardrops
				(best_length_ratio 0.2)
				(max_length 1)
				(best_width_ratio 0.9)
				(max_width 2)
				(curved_edges yes)
				(filter_ratio 0.9)
				(enabled yes)
				(allow_two_segments yes)
				(prefer_zone_connections yes)
			)
		)
		(pad "2" smd roundrect
			(at 0.48 0)
			(size 0.59 0.64)
			(layers "B.Cu" "B.Mask" "B.Paste")
			(roundrect_rratio 0.25)
			(net 78 "+1V8")
			(pintype "passive")
			(teardrops
				(best_length_ratio 0.2)
				(max_length 1)
				(best_width_ratio 0.9)
				(max_width 2)
				(curved_edges yes)
				(filter_ratio 0.9)
				(enabled yes)
				(allow_two_segments yes)
				(prefer_zone_connections yes)
			)
		)
	)
	(footprint "antmicro-footprints:TP_SMD_0.75mm"
		(layer "B.Cu")
		(at 194.25 163.325)
		(property "Reference" "TP16"
			(at -0.25 -0.825 90)
			(layer "B.SilkS")
			(effects
				(font
					(size 0.7 0.7)
					(thickness 0.15)
				)
				(justify right top mirror)
			)
		)
		(property "Value" "TP_0.75mm_SMD"
			(at 3.225 -53.865 0)
			(layer "B.Fab")
			(hide yes)
			(effects
				(font
					(size 0.7 0.7)
					(thickness 0.15)
				)
				(justify right top mirror)
			)
		)
		(property "Author" "Antmicro"
			(at 418.6 313.02 0)
			(layer "B.Fab")
			(hide yes)
			(effects
				(font
					(size 1 1)
					(thickness 0.15)
				)
				(justify mirror)
			)
		)
		(property "License" "Apache-2.0"
			(at 418.6 313.02 0)
			(layer "B.Fab")
			(hide yes)
			(effects
				(font
					(size 1 1)
					(thickness 0.15)
				)
				(justify mirror)
			)
		)
		(property "MPN" ""
			(at 418.6 313.02 0)
			(layer "B.Fab")
			(hide yes)
			(effects
				(font
					(size 1 1)
					(thickness 0.15)
				)
				(justify mirror)
			)
		)
		(property "Manufacturer" ""
			(at 418.6 313.02 0)
			(layer "B.Fab")
			(hide yes)
			(effects
				(font
					(size 1 1)
					(thickness 0.15)
				)
				(justify mirror)
			)
		)
		(property "Public" "False"
			(at 418.6 313.02 0)
			(layer "B.Fab")
			(hide yes)
			(effects
				(font
					(size 1 1)
					(thickness 0.15)
				)
				(justify mirror)
			)
		)
		(sheetname "Com Express 7 Interfaces")
		(sheetfile "com_express_7_interfaces.kicad_sch")
		(attr exclude_from_pos_files exclude_from_bom)
		(fp_circle
			(center 0 0)
			(end 0.475 0)
			(stroke
				(width 0.05)
				(type default)
			)
			(fill no)
			(layer "B.CrtYd")
		)
		(pad "1" smd circle
			(at 0 0)
			(size 0.75 0.75)
			(layers "B.Cu" "B.Mask")
			(net 380 "Net-(J12G-USB0_HOST_PRSNT)")
			(pinfunction "1")
			(pintype "passive")
			(teardrops
				(best_length_ratio 0.4)
				(max_length 1)
				(best_width_ratio 0.9)
				(max_width 2)
				(curved_edges yes)
				(filter_ratio 0.9)
				(enabled yes)
				(allow_two_segments yes)
				(prefer_zone_connections yes)
			)
		)
	)
	(footprint "antmicro-footprints:TP_SMD_0.75mm"
		(layer "B.Cu")
		(at 174 163.85)
		(property "Reference" "TP25"
			(at -0.5 -0.65 90)
			(layer "B.SilkS")
			(effects
				(font
					(size 0.7 0.7)
					(thickness 0.15)
				)
				(justify right top mirror)
			)
		)
		(property "Value" "TP_0.75mm_SMD"
			(at 3.225 -53.865 0)
			(layer "B.Fab")
			(hide yes)
			(effects
				(font
					(size 0.7 0.7)
					(thickness 0.15)
				)
				(justify right top mirror)
			)
		)
		(property "Author" "Antmicro"
			(at 458.4 306.119999 0)
			(layer "B.Fab")
			(hide yes)
			(effects
				(font
					(size 1 1)
					(thickness 0.15)
				)
				(justify mirror)
			)
		)
		(property "License" "Apache-2.0"
			(at 458.4 306.119999 0)
			(layer "B.Fab")
			(hide yes)
			(effects
				(font
					(size 1 1)
					(thickness 0.15)
				)
				(justify mirror)
			)
		)
		(property "MPN" ""
			(at 458.4 306.119999 0)
			(layer "B.Fab")
			(hide yes)
			(effects
				(font
					(size 1 1)
					(thickness 0.15)
				)
				(justify mirror)
			)
		)
		(property "Manufacturer" ""
			(at 458.4 306.119999 0)
			(layer "B.Fab")
			(hide yes)
			(effects
				(font
					(size 1 1)
					(thickness 0.15)
				)
				(justify mirror)
			)
		)
		(property "Public" "False"
			(at 458.4 306.119999 0)
			(layer "B.Fab")
			(hide yes)
			(effects
				(font
					(size 1 1)
					(thickness 0.15)
				)
				(justify mirror)
			)
		)
		(sheetname "Com Express 7 MGMT")
		(sheetfile "com_express_7_mgmt.kicad_sch")
		(attr exclude_from_pos_files exclude_from_bom)
		(fp_circle
			(center 0 0)
			(end 0.475 0)
			(stroke
				(width 0.05)
				(type default)
			)
			(fill no)
			(layer "B.CrtYd")
		)
		(pad "1" smd circle
			(at 0 0)
			(size 0.75 0.75)
			(layers "B.Cu" "B.Mask")
			(net 349 "Net-(J12D-LPC_AD0{slash}ESPI_IO_0)")
			(pinfunction "1")
			(pintype "passive")
			(teardrops
				(best_length_ratio 0.4)
				(max_length 1)
				(best_width_ratio 0.9)
				(max_width 2)
				(curved_edges yes)
				(filter_ratio 0.9)
				(enabled yes)
				(allow_two_segments yes)
				(prefer_zone_connections yes)
			)
		)
	)
	(footprint "antmicro-footprints:C_0402_1005Metric"
		(layer "B.Cu")
		(at 311.274999 106.15 -90)
		(descr "Capacitor SMD 0402")
		(tags "capacitor SMD 0402")
		(property "Reference" "C45"
			(at 0.81 -0.475001 90)
			(layer "B.SilkS")
			(effects
				(font
					(size 0.7 0.7)
					(thickness 0.15)
				)
				(justify left bottom mirror)
			)
		)
		(property "Value" "C_1u_0402"
			(at -1.022927 -2.155213 90)
			(layer "B.Fab")
			(effects
				(font
					(size 0.7 0.7)
					(thickness 0.15)
				)
				(justify left bottom mirror)
			)
		)
		(property "Datasheet" "https://product.tdk.com/en/search/capacitor/ceramic/mlcc/info?part_no=C1005X6S1A105K050BC"
			(at 0 0 270)
			(layer "F.Fab")
			(hide yes)
			(effects
				(font
					(size 1.27 1.27)
					(thickness 0.15)
				)
			)
		)
		(property "Author" "Antmicro"
			(at 205.124999 417.424999 0)
			(layer "B.Fab")
			(hide yes)
			(effects
				(font
					(size 1 1)
					(thickness 0.15)
				)
				(justify mirror)
			)
		)
		(property "Dielectric" ""
			(at 205.124999 417.424999 0)
			(layer "B.Fab")
			(hide yes)
			(effects
				(font
					(size 1 1)
					(thickness 0.15)
				)
				(justify mirror)
			)
		)
		(property "License" "Apache-2.0"
			(at 205.124999 417.424999 0)
			(layer "B.Fab")
			(hide yes)
			(effects
				(font
					(size 1 1)
					(thickness 0.15)
				)
				(justify mirror)
			)
		)
		(property "MPN" "C1005X6S1A105K050BC"
			(at 205.124999 417.424999 0)
			(layer "B.Fab")
			(hide yes)
			(effects
				(font
					(size 1 1)
					(thickness 0.15)
				)
				(justify mirror)
			)
		)
		(property "Manufacturer" "TDK"
			(at 205.124999 417.424999 0)
			(layer "B.Fab")
			(hide yes)
			(effects
				(font
					(size 1 1)
					(thickness 0.15)
				)
				(justify mirror)
			)
		)
		(property "Public" "False"
			(at 205.124999 417.424999 0)
			(layer "B.Fab")
			(hide yes)
			(effects
				(font
					(size 1 1)
					(thickness 0.15)
				)
				(justify mirror)
			)
		)
		(property "Val" "1u"
			(at 205.124999 417.424999 0)
			(layer "B.Fab")
			(hide yes)
			(effects
				(font
					(size 1 1)
					(thickness 0.15)
				)
				(justify mirror)
			)
		)
		(property "Voltage" ""
			(at 205.124999 417.424999 0)
			(layer "B.Fab")
			(hide yes)
			(effects
				(font
					(size 1 1)
					(thickness 0.15)
				)
				(justify mirror)
			)
		)
		(sheetname "Power")
		(sheetfile "power.kicad_sch")
		(attr smd)
		(fp_rect
			(start -0.925 0.47)
			(end 0.925 -0.47)
			(stroke
				(width 0.05)
				(type default)
			)
			(fill no)
			(layer "B.CrtYd")
		)
		(fp_line
			(start -0.494 0.25)
			(end -0.494 -0.248)
			(stroke
				(width 0.15)
				(type solid)
			)
			(layer "B.Fab")
		)
		(fp_line
			(start 0.504 0.25)
			(end -0.494 0.25)
			(stroke
				(width 0.15)
				(type solid)
			)
			(layer "B.Fab")
		)
		(fp_line
			(start -0.494 -0.248)
			(end 0.504 -0.248)
			(stroke
				(width 0.15)
				(type solid)
			)
			(layer "B.Fab")
		)
		(fp_line
			(start 0.504 -0.248)
			(end 0.504 0.25)
			(stroke
				(width 0.15)
				(type solid)
			)
			(layer "B.Fab")
		)
		(pad "1" smd roundrect
			(at -0.48 0 270)
			(size 0.59 0.64)
			(layers "B.Cu" "B.Mask" "B.Paste")
			(roundrect_rratio 0.25)
			(net 1 "GND")
			(pintype "passive")
			(teardrops
				(best_length_ratio 0.2)
				(max_length 1)
				(best_width_ratio 0.9)
				(max_width 2)
				(curved_edges yes)
				(filter_ratio 0.9)
				(enabled yes)
				(allow_two_segments yes)
				(prefer_zone_connections yes)
			)
		)
		(pad "2" smd roundrect
			(at 0.48 0 270)
			(size 0.59 0.64)
			(layers "B.Cu" "B.Mask" "B.Paste")
			(roundrect_rratio 0.25)
			(net 64 "Net-(U19-V_{CC})")
			(pintype "passive")
			(teardrops
				(best_length_ratio 0.2)
				(max_length 1)
				(best_width_ratio 0.9)
				(max_width 2)
				(curved_edges yes)
				(filter_ratio 0.9)
				(enabled yes)
				(allow_two_segments yes)
				(prefer_zone_connections yes)
			)
		)
	)
	(footprint "antmicro-footprints:SOT-23-3"
		(layer "B.Cu")
		(at 140.7 132.51)
		(property "Reference" "D22"
			(at -1.15 -1.75 0)
			(layer "B.SilkS")
			(effects
				(font
					(size 0.7 0.7)
					(thickness 0.15)
				)
				(justify right bottom mirror)
			)
		)
		(property "Value" "BAT54C"
			(at -1.9 -2.7 0)
			(layer "B.Fab")
			(effects
				(font
					(size 0.7 0.7)
					(thickness 0.15)
				)
				(justify right bottom mirror)
			)
		)
		(property "Datasheet" "https://diotec.com/request/datasheet/bat54.pdf"
			(at 0 0 0)
			(layer "F.Fab")
			(hide yes)
			(effects
				(font
					(size 1.27 1.27)
					(thickness 0.15)
				)
			)
		)
		(property "Author" "Antmicro"
			(at 0 0 0)
			(layer "B.Fab")
			(hide yes)
			(effects
				(font
					(size 1 1)
					(thickness 0.15)
				)
				(justify mirror)
			)
		)
		(property "License" "Apache-2.0"
			(at 0 0 0)
			(layer "B.Fab")
			(hide yes)
			(effects
				(font
					(size 1 1)
					(thickness 0.15)
				)
				(justify mirror)
			)
		)
		(property "MPN" "BAT54C"
			(at 0 0 0)
			(layer "B.Fab")
			(hide yes)
			(effects
				(font
					(size 1 1)
					(thickness 0.15)
				)
				(justify mirror)
			)
		)
		(property "Manufacturer" "Diotec Semiconductor"
			(at 0 0 0)
			(layer "B.Fab")
			(hide yes)
			(effects
				(font
					(size 1 1)
					(thickness 0.15)
				)
				(justify mirror)
			)
		)
		(sheetname "KR to SFI #1")
		(sheetfile "kr_sfi.kicad_sch")
		(attr smd)
		(fp_line
			(start -0.85 1.35)
			(end -1.45 1.35)
			(stroke
				(width 0.15)
				(type solid)
			)
			(layer "B.SilkS")
		)
		(fp_line
			(start -0.7 -1.5)
			(end 0.7 -1.5)
			(stroke
				(width 0.15)
				(type solid)
			)
			(layer "B.SilkS")
		)
		(fp_line
			(start -0.7 -1.35)
			(end -0.7 -1.5)
			(stroke
				(width 0.15)
				(type solid)
			)
			(layer "B.SilkS")
		)
		(fp_line
			(start -0.7 1.5)
			(end -0.85 1.35)
			(stroke
				(width 0.15)
				(type solid)
			)
			(layer "B.SilkS")
		)
		(fp_line
			(start -0.7 1.5)
			(end 0.7 1.5)
			(stroke
				(width 0.15)
				(type solid)
			)
			(layer "B.SilkS")
		)
		(fp_line
			(start 0.7 -1.5)
			(end 0.7 -0.4)
			(stroke
				(width 0.15)
				(type solid)
			)
			(layer "B.SilkS")
		)
		(fp_line
			(start 0.7 1.5)
			(end 0.7 0.4)
			(stroke
				(width 0.15)
				(type solid)
			)
			(layer "B.SilkS")
		)
		(fp_line
			(start -1.75 -1.4)
			(end -0.85 -1.4)
			(stroke
				(width 0.05)
				(type solid)
			)
			(layer "B.CrtYd")
		)
		(fp_line
			(start -1.75 -0.5)
			(end -1.75 -1.4)
			(stroke
				(width 0.05)
				(type solid)
			)
			(layer "B.CrtYd")
		)
		(fp_line
			(start -1.75 0.5)
			(end -0.85 0.5)
			(stroke
				(width 0.05)
				(type solid)
			)
			(layer "B.CrtYd")
		)
		(fp_line
			(start -1.75 1.4)
			(end -1.75 0.5)
			(stroke
				(width 0.05)
				(type solid)
			)
			(layer "B.CrtYd")
		)
		(fp_line
			(start -1.75 1.4)
			(end -0.9 1.4)
			(stroke
				(width 0.05)
				(type solid)
			)
			(layer "B.CrtYd")
		)
		(fp_line
			(start -0.9 1.4)
			(end -0.9 1.6)
			(stroke
				(width 0.05)
				(type solid)
			)
			(layer "B.CrtYd")
		)
		(fp_line
			(start -0.85 -1.65)
			(end 0.85 -1.65)
			(stroke
				(width 0.05)
				(type solid)
			)
			(layer "B.CrtYd")
		)
		(fp_line
			(start -0.85 -1.4)
			(end -0.85 -1.65)
			(stroke
				(width 0.05)
				(type solid)
			)
			(layer "B.CrtYd")
		)
		(fp_line
			(start -0.85 -0.5)
			(end -1.75 -0.5)
			(stroke
				(width 0.05)
				(type solid)
			)
			(layer "B.CrtYd")
		)
		(fp_line
			(start -0.85 0.5)
			(end -0.85 -0.5)
			(stroke
				(width 0.05)
				(type solid)
			)
			(layer "B.CrtYd")
		)
		(fp_line
			(start 0.825 0.45)
			(end 0.825 1.6)
			(stroke
				(width 0.05)
				(type solid)
			)
			(layer "B.CrtYd")
		)
		(fp_line
			(start 0.825 1.6)
			(end -0.9 1.6)
			(stroke
				(width 0.05)
				(type solid)
			)
			(layer "B.CrtYd")
		)
		(fp_line
			(start 0.85 -1.65)
			(end 0.85 -0.45)
			(stroke
				(width 0.05)
				(type solid)
			)
			(layer "B.CrtYd")
		)
		(fp_line
			(start 0.85 -0.45)
			(end 1.75 -0.45)
			(stroke
				(width 0.05)
				(type solid)
			)
			(layer "B.CrtYd")
		)
		(fp_line
			(start 1.75 -0.45)
			(end 1.75 0.45)
			(stroke
				(width 0.05)
				(type solid)
			)
			(layer "B.CrtYd")
		)
		(fp_line
			(start 1.75 0.45)
			(end 0.825 0.45)
			(stroke
				(width 0.05)
				(type solid)
			)
			(layer "B.CrtYd")
		)
		(fp_line
			(start -0.712 -1.523)
			(end -0.712 1.325)
			(stroke
				(width 0.15)
				(type solid)
			)
			(layer "B.Fab")
		)
		(fp_line
			(start -0.712 1.325)
			(end -0.437 1.526)
			(stroke
				(width 0.15)
				(type solid)
			)
			(layer "B.Fab")
		)
		(fp_line
			(start 0.688 -1.519)
			(end -0.712 -1.519)
			(stroke
				(width 0.15)
				(type solid)
			)
			(layer "B.Fab")
		)
		(fp_line
			(start 0.688 1.52)
			(end 0.688 -1.519)
			(stroke
				(width 0.15)
				(type solid)
			)
			(layer "B.Fab")
		)
		(fp_line
			(start 0.688 1.526)
			(end -0.437 1.526)
			(stroke
				(width 0.15)
				(type solid)
			)
			(layer "B.Fab")
		)
		(pad "1" smd roundrect
			(at -1.1 0.951)
			(size 1 0.6)
			(layers "B.Cu" "B.Mask" "B.Paste")
			(roundrect_rratio 0.15)
			(net 141 "/2xSFP+/KR to SFI #1/~{RESET}")
			(pinfunction "1")
			(pintype "passive")
			(teardrops
				(best_length_ratio 0.2)
				(max_length 1)
				(best_width_ratio 0.9)
				(max_width 2)
				(curved_edges yes)
				(filter_ratio 0.9)
				(enabled yes)
				(allow_two_segments yes)
				(prefer_zone_connections yes)
			)
		)
		(pad "2" smd roundrect
			(at -1.1 -0.949)
			(size 1 0.6)
			(layers "B.Cu" "B.Mask" "B.Paste")
			(roundrect_rratio 0.15)
			(net 141 "/2xSFP+/KR to SFI #1/~{RESET}")
			(pinfunction "2")
			(pintype "passive")
			(teardrops
				(best_length_ratio 0.2)
				(max_length 1)
				(best_width_ratio 0.9)
				(max_width 2)
				(curved_edges yes)
				(filter_ratio 0.9)
				(enabled yes)
				(allow_two_segments yes)
				(prefer_zone_connections yes)
			)
		)
		(pad "3" smd roundrect
			(at 1.1 0.0005)
			(size 1 0.6)
			(layers "B.Cu" "B.Mask" "B.Paste")
			(roundrect_rratio 0.15)
			(net 142 "/2xSFP+/PHY0_{RESET}")
			(pinfunction "3")
			(pintype "passive")
			(teardrops
				(best_length_ratio 0.2)
				(max_length 1)
				(best_width_ratio 0.9)
				(max_width 2)
				(curved_edges yes)
				(filter_ratio 0.9)
				(enabled yes)
				(allow_two_segments yes)
				(prefer_zone_connections yes)
			)
		)
	)
	(footprint "antmicro-footprints:C_0402_1005Metric"
		(layer "B.Cu")
		(at 110.85 96.46 180)
		(descr "Capacitor SMD 0402")
		(tags "capacitor SMD 0402")
		(property "Reference" "C2"
			(at -0.8 0.5 0)
			(layer "B.SilkS")
			(effects
				(font
					(size 0.7 0.7)
					(thickness 0.15)
				)
				(justify left bottom mirror)
			)
		)
		(property "Value" "C_1u_0402"
			(at -1.022927 -2.155213 0)
			(layer "B.Fab")
			(effects
				(font
					(size 0.7 0.7)
					(thickness 0.15)
				)
				(justify left bottom mirror)
			)
		)
		(property "Datasheet" "https://product.tdk.com/en/search/capacitor/ceramic/mlcc/info?part_no=C1005X6S1A105K050BC"
			(at 0 0 180)
			(layer "F.Fab")
			(hide yes)
			(effects
				(font
					(size 1.27 1.27)
					(thickness 0.15)
				)
			)
		)
		(property "Author" "Antmicro"
			(at 221.7 192.92 0)
			(layer "B.Fab")
			(hide yes)
			(effects
				(font
					(size 1 1)
					(thickness 0.15)
				)
				(justify mirror)
			)
		)
		(property "Dielectric" ""
			(at 221.7 192.92 0)
			(layer "B.Fab")
			(hide yes)
			(effects
				(font
					(size 1 1)
					(thickness 0.15)
				)
				(justify mirror)
			)
		)
		(property "License" "Apache-2.0"
			(at 221.7 192.92 0)
			(layer "B.Fab")
			(hide yes)
			(effects
				(font
					(size 1 1)
					(thickness 0.15)
				)
				(justify mirror)
			)
		)
		(property "MPN" "C1005X6S1A105K050BC"
			(at 221.7 192.92 0)
			(layer "B.Fab")
			(hide yes)
			(effects
				(font
					(size 1 1)
					(thickness 0.15)
				)
				(justify mirror)
			)
		)
		(property "Manufacturer" "TDK"
			(at 221.7 192.92 0)
			(layer "B.Fab")
			(hide yes)
			(effects
				(font
					(size 1 1)
					(thickness 0.15)
				)
				(justify mirror)
			)
		)
		(property "Public" "False"
			(at 221.7 192.92 0)
			(layer "B.Fab")
			(hide yes)
			(effects
				(font
					(size 1 1)
					(thickness 0.15)
				)
				(justify mirror)
			)
		)
		(property "Val" "1u"
			(at 221.7 192.92 0)
			(layer "B.Fab")
			(hide yes)
			(effects
				(font
					(size 1 1)
					(thickness 0.15)
				)
				(justify mirror)
			)
		)
		(property "Voltage" ""
			(at 221.7 192.92 0)
			(layer "B.Fab")
			(hide yes)
			(effects
				(font
					(size 1 1)
					(thickness 0.15)
				)
				(justify mirror)
			)
		)
		(sheetname "2xUSB3.0+RJ45")
		(sheetfile "usb3+rj45.kicad_sch")
		(attr smd)
		(fp_rect
			(start -0.925 0.47)
			(end 0.925 -0.47)
			(stroke
				(width 0.05)
				(type default)
			)
			(fill no)
			(layer "B.CrtYd")
		)
		(fp_line
			(start 0.504 0.25)
			(end -0.494 0.25)
			(stroke
				(width 0.15)
				(type solid)
			)
			(layer "B.Fab")
		)
		(fp_line
			(start 0.504 -0.248)
			(end 0.504 0.25)
			(stroke
				(width 0.15)
				(type solid)
			)
			(layer "B.Fab")
		)
		(fp_line
			(start -0.494 0.25)
			(end -0.494 -0.248)
			(stroke
				(width 0.15)
				(type solid)
			)
			(layer "B.Fab")
		)
		(fp_line
			(start -0.494 -0.248)
			(end 0.504 -0.248)
			(stroke
				(width 0.15)
				(type solid)
			)
			(layer "B.Fab")
		)
		(pad "1" smd roundrect
			(at -0.48 0 180)
			(size 0.59 0.64)
			(layers "B.Cu" "B.Mask" "B.Paste")
			(roundrect_rratio 0.25)
			(net 1 "GND")
			(pintype "passive")
			(teardrops
				(best_length_ratio 0.2)
				(max_length 1)
				(best_width_ratio 0.9)
				(max_width 2)
				(curved_edges yes)
				(filter_ratio 0.9)
				(enabled yes)
				(allow_two_segments yes)
				(prefer_zone_connections yes)
			)
		)
		(pad "2" smd roundrect
			(at 0.48 0 180)
			(size 0.59 0.64)
			(layers "B.Cu" "B.Mask" "B.Paste")
			(roundrect_rratio 0.25)
			(net 43 "/2xUSB3.0+RJ45/P2_VBUS")
			(pintype "passive")
			(teardrops
				(best_length_ratio 0.2)
				(max_length 1)
				(best_width_ratio 0.9)
				(max_width 2)
				(curved_edges yes)
				(filter_ratio 0.9)
				(enabled yes)
				(allow_two_segments yes)
				(prefer_zone_connections yes)
			)
		)
	)
	(footprint "antmicro-footprints:TP_SMD_0.75mm"
		(layer "B.Cu")
		(at 141.8 167.21 180)
		(property "Reference" "TP4"
			(at 0.35 0.45 0)
			(layer "B.SilkS")
			(effects
				(font
					(size 0.7 0.7)
					(thickness 0.15)
				)
				(justify left bottom mirror)
			)
		)
		(property "Value" "TP_0.75mm_SMD"
			(at 0 -1.2 0)
			(layer "B.Fab")
			(effects
				(font
					(size 0.7 0.7)
					(thickness 0.15)
				)
				(justify left bottom mirror)
			)
		)
		(property "Author" "Antmicro"
			(at 283.6 334.42 0)
			(layer "B.Fab")
			(hide yes)
			(effects
				(font
					(size 1 1)
					(thickness 0.15)
				)
				(justify mirror)
			)
		)
		(property "License" "Apache-2.0"
			(at 283.6 334.42 0)
			(layer "B.Fab")
			(hide yes)
			(effects
				(font
					(size 1 1)
					(thickness 0.15)
				)
				(justify mirror)
			)
		)
		(property "MPN" ""
			(at 283.6 334.42 0)
			(layer "B.Fab")
			(hide yes)
			(effects
				(font
					(size 1 1)
					(thickness 0.15)
				)
				(justify mirror)
			)
		)
		(property "Manufacturer" ""
			(at 283.6 334.42 0)
			(layer "B.Fab")
			(hide yes)
			(effects
				(font
					(size 1 1)
					(thickness 0.15)
				)
				(justify mirror)
			)
		)
		(property "Public" "False"
			(at 283.6 334.42 0)
			(layer "B.Fab")
			(hide yes)
			(effects
				(font
					(size 1 1)
					(thickness 0.15)
				)
				(justify mirror)
			)
		)
		(sheetname "2xSFP+")
		(sheetfile "2xSFP+.kicad_sch")
		(attr exclude_from_pos_files exclude_from_bom)
		(fp_circle
			(center 0 0)
			(end 0.475 0)
			(stroke
				(width 0.05)
				(type default)
			)
			(fill no)
			(layer "B.CrtYd")
		)
		(pad "1" smd circle
			(at 0 0 180)
			(size 0.75 0.75)
			(layers "B.Cu" "B.Mask")
			(net 876 "Net-(J2B-TX_{FAULT})")
			(pinfunction "1")
			(pintype "passive")
			(teardrops
				(best_length_ratio 0.4)
				(max_length 1)
				(best_width_ratio 0.9)
				(max_width 2)
				(curved_edges yes)
				(filter_ratio 0.9)
				(enabled yes)
				(allow_two_segments yes)
				(prefer_zone_connections yes)
			)
		)
	)
	(footprint "antmicro-footprints:R_0402_1005Metric"
		(layer "B.Cu")
		(at 309.824999 106.15 -90)
		(descr "Resistor SMD 0402")
		(tags "resistor SMD 0402")
		(property "Reference" "R91"
			(at 0.76 -0.475001 90)
			(layer "B.SilkS")
			(effects
				(font
					(size 0.7 0.7)
					(thickness 0.15)
				)
				(justify left bottom mirror)
			)
		)
		(property "Value" "R_68k_0402"
			(at -1.011843 -1.772047 90)
			(layer "B.Fab")
			(effects
				(font
					(size 0.7 0.7)
					(thickness 0.15)
				)
				(justify left bottom mirror)
			)
		)
		(property "Datasheet" "https://www.bourns.com/docs/product-datasheets/cr.pdf"
			(at 0 0 270)
			(layer "F.Fab")
			(hide yes)
			(effects
				(font
					(size 1.27 1.27)
					(thickness 0.15)
				)
			)
		)
		(property "Author" "Antmicro"
			(at 203.674999 415.974999 0)
			(layer "B.Fab")
			(hide yes)
			(effects
				(font
					(size 1 1)
					(thickness 0.15)
				)
				(justify mirror)
			)
		)
		(property "License" "Apache-2.0"
			(at 203.674999 415.974999 0)
			(layer "B.Fab")
			(hide yes)
			(effects
				(font
					(size 1 1)
					(thickness 0.15)
				)
				(justify mirror)
			)
		)
		(property "MPN" "CR0402-FX-6802GLF"
			(at 203.674999 415.974999 0)
			(layer "B.Fab")
			(hide yes)
			(effects
				(font
					(size 1 1)
					(thickness 0.15)
				)
				(justify mirror)
			)
		)
		(property "Manufacturer" "Bourns"
			(at 203.674999 415.974999 0)
			(layer "B.Fab")
			(hide yes)
			(effects
				(font
					(size 1 1)
					(thickness 0.15)
				)
				(justify mirror)
			)
		)
		(property "Public" "False"
			(at 203.674999 415.974999 0)
			(layer "B.Fab")
			(hide yes)
			(effects
				(font
					(size 1 1)
					(thickness 0.15)
				)
				(justify mirror)
			)
		)
		(property "Tolerance" "1%"
			(at 203.674999 415.974999 0)
			(layer "B.Fab")
			(hide yes)
			(effects
				(font
					(size 1 1)
					(thickness 0.15)
				)
				(justify mirror)
			)
		)
		(property "Val" "68k"
			(at 203.674999 415.974999 0)
			(layer "B.Fab")
			(hide yes)
			(effects
				(font
					(size 1 1)
					(thickness 0.15)
				)
				(justify mirror)
			)
		)
		(sheetname "Power")
		(sheetfile "power.kicad_sch")
		(attr smd dnp)
		(fp_rect
			(start -0.925 0.47)
			(end 0.925 -0.47)
			(stroke
				(width 0.05)
				(type default)
			)
			(fill no)
			(layer "B.CrtYd")
		)
		(fp_rect
			(start -0.5 0.25)
			(end 0.5 -0.25)
			(stroke
				(width 0.15)
				(type solid)
			)
			(fill no)
			(layer "B.Fab")
		)
		(pad "1" smd roundrect
			(at -0.48 0 270)
			(size 0.59 0.64)
			(layers "B.Cu" "B.Mask" "B.Paste")
			(roundrect_rratio 0.25)
			(net 576 "Net-(U19-MODE)")
			(pintype "passive")
			(teardrops
				(best_length_ratio 0.2)
				(max_length 1)
				(best_width_ratio 0.9)
				(max_width 2)
				(curved_edges yes)
				(filter_ratio 0.9)
				(enabled yes)
				(allow_two_segments yes)
				(prefer_zone_connections yes)
			)
		)
		(pad "2" smd roundrect
			(at 0.48 0 270)
			(size 0.59 0.64)
			(layers "B.Cu" "B.Mask" "B.Paste")
			(roundrect_rratio 0.25)
			(net 64 "Net-(U19-V_{CC})")
			(pintype "passive")
			(teardrops
				(best_length_ratio 0.2)
				(max_length 1)
				(best_width_ratio 0.9)
				(max_width 2)
				(curved_edges yes)
				(filter_ratio 0.9)
				(enabled yes)
				(allow_two_segments yes)
				(prefer_zone_connections yes)
			)
		)
	)
	(footprint "antmicro-footprints:TP_SMD_0.75mm"
		(layer "B.Cu")
		(at 176.25 166.1)
		(property "Reference" "TP29"
			(at 1 -0.35 180)
			(layer "B.SilkS")
			(effects
				(font
					(size 0.7 0.7)
					(thickness 0.15)
				)
				(justify right top mirror)
			)
		)
		(property "Value" "TP_0.75mm_SMD"
			(at 3.225 -53.865 0)
			(layer "B.Fab")
			(hide yes)
			(effects
				(font
					(size 0.7 0.7)
					(thickness 0.15)
				)
				(justify right top mirror)
			)
		)
		(property "Author" "Antmicro"
			(at 453.6 306.12 0)
			(layer "B.Fab")
			(hide yes)
			(effects
				(font
					(size 1 1)
					(thickness 0.15)
				)
				(justify mirror)
			)
		)
		(property "License" "Apache-2.0"
			(at 453.6 306.12 0)
			(layer "B.Fab")
			(hide yes)
			(effects
				(font
					(size 1 1)
					(thickness 0.15)
				)
				(justify mirror)
			)
		)
		(property "MPN" ""
			(at 453.6 306.12 0)
			(layer "B.Fab")
			(hide yes)
			(effects
				(font
					(size 1 1)
					(thickness 0.15)
				)
				(justify mirror)
			)
		)
		(property "Manufacturer" ""
			(at 453.6 306.12 0)
			(layer "B.Fab")
			(hide yes)
			(effects
				(font
					(size 1 1)
					(thickness 0.15)
				)
				(justify mirror)
			)
		)
		(property "Public" "False"
			(at 453.6 306.12 0)
			(layer "B.Fab")
			(hide yes)
			(effects
				(font
					(size 1 1)
					(thickness 0.15)
				)
				(justify mirror)
			)
		)
		(sheetname "Com Express 7 MGMT")
		(sheetfile "com_express_7_mgmt.kicad_sch")
		(attr exclude_from_pos_files exclude_from_bom)
		(fp_circle
			(center 0 0)
			(end 0.475 0)
			(stroke
				(width 0.05)
				(type default)
			)
			(fill no)
			(layer "B.CrtYd")
		)
		(pad "1" smd circle
			(at 0 0)
			(size 0.75 0.75)
			(layers "B.Cu" "B.Mask")
			(net 353 "Net-(J12D-~{LPC_DRQ0}{slash}~{ESPI_ALERT0})")
			(pinfunction "1")
			(pintype "passive")
			(teardrops
				(best_length_ratio 0.4)
				(max_length 1)
				(best_width_ratio 0.9)
				(max_width 2)
				(curved_edges yes)
				(filter_ratio 0.9)
				(enabled yes)
				(allow_two_segments yes)
				(prefer_zone_connections yes)
			)
		)
	)
	(footprint "antmicro-footprints:R_0402_1005Metric"
		(layer "B.Cu")
		(at 104.28 87.47 90)
		(descr "Resistor SMD 0402")
		(tags "resistor SMD 0402")
		(property "Reference" "R66"
			(at -1.09 -0.48 90)
			(layer "B.SilkS")
			(effects
				(font
					(size 0.7 0.7)
					(thickness 0.15)
				)
				(justify right bottom mirror)
			)
		)
		(property "Value" "R_330R_0402"
			(at -1.011843 -1.772047 90)
			(layer "B.Fab")
			(effects
				(font
					(size 0.7 0.7)
					(thickness 0.15)
				)
				(justify right bottom mirror)
			)
		)
		(property "Datasheet" "https://www.bourns.com/docs/product-datasheets/cr.pdf"
			(at 0 0 90)
			(layer "F.Fab")
			(hide yes)
			(effects
				(font
					(size 1.27 1.27)
					(thickness 0.15)
				)
			)
		)
		(property "Author" "Antmicro"
			(at 191.75 -16.81 0)
			(layer "B.Fab")
			(hide yes)
			(effects
				(font
					(size 1 1)
					(thickness 0.15)
				)
				(justify mirror)
			)
		)
		(property "License" "Apache-2.0"
			(at 191.75 -16.81 0)
			(layer "B.Fab")
			(hide yes)
			(effects
				(font
					(size 1 1)
					(thickness 0.15)
				)
				(justify mirror)
			)
		)
		(property "MPN" "CR0402-FX-3300GLF"
			(at 191.75 -16.81 0)
			(layer "B.Fab")
			(hide yes)
			(effects
				(font
					(size 1 1)
					(thickness 0.15)
				)
				(justify mirror)
			)
		)
		(property "Manufacturer" "Bourns"
			(at 191.75 -16.81 0)
			(layer "B.Fab")
			(hide yes)
			(effects
				(font
					(size 1 1)
					(thickness 0.15)
				)
				(justify mirror)
			)
		)
		(property "Public" "False"
			(at 191.75 -16.81 0)
			(layer "B.Fab")
			(hide yes)
			(effects
				(font
					(size 1 1)
					(thickness 0.15)
				)
				(justify mirror)
			)
		)
		(property "Tolerance" "1%"
			(at 191.75 -16.81 0)
			(layer "B.Fab")
			(hide yes)
			(effects
				(font
					(size 1 1)
					(thickness 0.15)
				)
				(justify mirror)
			)
		)
		(property "Val" "330R"
			(at 191.75 -16.81 0)
			(layer "B.Fab")
			(hide yes)
			(effects
				(font
					(size 1 1)
					(thickness 0.15)
				)
				(justify mirror)
			)
		)
		(sheetname "USB-C console")
		(sheetfile "usb-c_console.kicad_sch")
		(attr smd)
		(fp_rect
			(start -0.925 0.47)
			(end 0.925 -0.47)
			(stroke
				(width 0.05)
				(type default)
			)
			(fill no)
			(layer "B.CrtYd")
		)
		(fp_rect
			(start -0.5 0.25)
			(end 0.5 -0.25)
			(stroke
				(width 0.15)
				(type solid)
			)
			(fill no)
			(layer "B.Fab")
		)
		(pad "1" smd roundrect
			(at -0.48 0 90)
			(size 0.59 0.64)
			(layers "B.Cu" "B.Mask" "B.Paste")
			(roundrect_rratio 0.25)
			(net 54 "/USB-C console/SH")
			(pintype "passive")
			(teardrops
				(best_length_ratio 0.2)
				(max_length 1)
				(best_width_ratio 0.9)
				(max_width 2)
				(curved_edges yes)
				(filter_ratio 0.9)
				(enabled yes)
				(allow_two_segments yes)
				(prefer_zone_connections yes)
			)
		)
		(pad "2" smd roundrect
			(at 0.48 0 90)
			(size 0.59 0.64)
			(layers "B.Cu" "B.Mask" "B.Paste")
			(roundrect_rratio 0.25)
			(net 1 "GND")
			(pintype "passive")
			(teardrops
				(best_length_ratio 0.2)
				(max_length 1)
				(best_width_ratio 0.9)
				(max_width 2)
				(curved_edges yes)
				(filter_ratio 0.9)
				(enabled yes)
				(allow_two_segments yes)
				(prefer_zone_connections yes)
			)
		)
	)
	(footprint "antmicro-footprints:C_0402_1005Metric"
		(layer "B.Cu")
		(at 213.11 129.12 180)
		(descr "Capacitor SMD 0402")
		(tags "capacitor SMD 0402")
		(property "Reference" "C10"
			(at -1.14 -1.34 0)
			(layer "B.SilkS")
			(effects
				(font
					(size 0.7 0.7)
					(thickness 0.15)
				)
				(justify left bottom mirror)
			)
		)
		(property "Value" "C_100n_0402"
			(at -1.022927 -2.155213 0)
			(layer "B.Fab")
			(effects
				(font
					(size 0.7 0.7)
					(thickness 0.15)
				)
				(justify left bottom mirror)
			)
		)
		(property "Datasheet" "https://www.murata.com/products/productdetail?partno=GRM155R61H104KE14%23"
			(at 0 0 180)
			(layer "F.Fab")
			(hide yes)
			(effects
				(font
					(size 1.27 1.27)
					(thickness 0.15)
				)
			)
		)
		(property "Author" "Antmicro"
			(at 426.22 258.24 0)
			(layer "B.Fab")
			(hide yes)
			(effects
				(font
					(size 1 1)
					(thickness 0.15)
				)
				(justify mirror)
			)
		)
		(property "Dielectric" "X5R"
			(at 426.22 258.24 0)
			(layer "B.Fab")
			(hide yes)
			(effects
				(font
					(size 1 1)
					(thickness 0.15)
				)
				(justify mirror)
			)
		)
		(property "License" "Apache-2.0"
			(at 426.22 258.24 0)
			(layer "B.Fab")
			(hide yes)
			(effects
				(font
					(size 1 1)
					(thickness 0.15)
				)
				(justify mirror)
			)
		)
		(property "MPN" "GRM155R61H104KE14D"
			(at 426.22 258.24 0)
			(layer "B.Fab")
			(hide yes)
			(effects
				(font
					(size 1 1)
					(thickness 0.15)
				)
				(justify mirror)
			)
		)
		(property "Manufacturer" "Murata"
			(at 426.22 258.24 0)
			(layer "B.Fab")
			(hide yes)
			(effects
				(font
					(size 1 1)
					(thickness 0.15)
				)
				(justify mirror)
			)
		)
		(property "Public" "False"
			(at 426.22 258.24 0)
			(layer "B.Fab")
			(hide yes)
			(effects
				(font
					(size 1 1)
					(thickness 0.15)
				)
				(justify mirror)
			)
		)
		(property "Val" "100n"
			(at 426.22 258.24 0)
			(layer "B.Fab")
			(hide yes)
			(effects
				(font
					(size 1 1)
					(thickness 0.15)
				)
				(justify mirror)
			)
		)
		(property "Voltage" "50V"
			(at 426.22 258.24 0)
			(layer "B.Fab")
			(hide yes)
			(effects
				(font
					(size 1 1)
					(thickness 0.15)
				)
				(justify mirror)
			)
		)
		(sheetname "PCIe misc")
		(sheetfile "pcie_misc.kicad_sch")
		(attr smd)
		(fp_rect
			(start -0.925 0.47)
			(end 0.925 -0.47)
			(stroke
				(width 0.05)
				(type default)
			)
			(fill no)
			(layer "B.CrtYd")
		)
		(fp_line
			(start 0.504 0.25)
			(end -0.494 0.25)
			(stroke
				(width 0.15)
				(type solid)
			)
			(layer "B.Fab")
		)
		(fp_line
			(start 0.504 -0.248)
			(end 0.504 0.25)
			(stroke
				(width 0.15)
				(type solid)
			)
			(layer "B.Fab")
		)
		(fp_line
			(start -0.494 0.25)
			(end -0.494 -0.248)
			(stroke
				(width 0.15)
				(type solid)
			)
			(layer "B.Fab")
		)
		(fp_line
			(start -0.494 -0.248)
			(end 0.504 -0.248)
			(stroke
				(width 0.15)
				(type solid)
			)
			(layer "B.Fab")
		)
		(pad "1" smd roundrect
			(at -0.48 0 180)
			(size 0.59 0.64)
			(layers "B.Cu" "B.Mask" "B.Paste")
			(roundrect_rratio 0.25)
			(net 1 "GND")
			(pintype "passive")
			(teardrops
				(best_length_ratio 0.2)
				(max_length 1)
				(best_width_ratio 0.9)
				(max_width 2)
				(curved_edges yes)
				(filter_ratio 0.9)
				(enabled yes)
				(allow_two_segments yes)
				(prefer_zone_connections yes)
			)
		)
		(pad "2" smd roundrect
			(at 0.48 0 180)
			(size 0.59 0.64)
			(layers "B.Cu" "B.Mask" "B.Paste")
			(roundrect_rratio 0.25)
			(net 2 "+3V3")
			(pintype "passive")
			(teardrops
				(best_length_ratio 0.2)
				(max_length 1)
				(best_width_ratio 0.9)
				(max_width 2)
				(curved_edges yes)
				(filter_ratio 0.9)
				(enabled yes)
				(allow_two_segments yes)
				(prefer_zone_connections yes)
			)
		)
	)
	(footprint "antmicro-footprints:C_0603_1608Metric"
		(layer "B.Cu")
		(at 136.426 132.089 -90)
		(descr "Capacitor SMD 0603")
		(tags "capacitor 0603")
		(property "Reference" "C182"
			(at -1.529 -1.574 90)
			(layer "B.SilkS")
			(effects
				(font
					(size 0.7 0.7)
					(thickness 0.15)
				)
				(justify left bottom mirror)
			)
		)
		(property "Value" "C_22u_16V_0603"
			(at -1.42757 -1.770288 90)
			(layer "B.Fab")
			(effects
				(font
					(size 0.7 0.7)
					(thickness 0.15)
				)
				(justify left bottom mirror)
			)
		)
		(property "Datasheet" "https://product.samsungsem.com/mlcc/CL10A226MO7JZN.do"
			(at 0 0 270)
			(layer "F.Fab")
			(hide yes)
			(effects
				(font
					(size 1.27 1.27)
					(thickness 0.15)
				)
			)
		)
		(property "Author" "Antmicro"
			(at 4.337 268.515 0)
			(layer "B.Fab")
			(hide yes)
			(effects
				(font
					(size 1 1)
					(thickness 0.15)
				)
				(justify mirror)
			)
		)
		(property "Dielectric" ""
			(at 4.337 268.515 0)
			(layer "B.Fab")
			(hide yes)
			(effects
				(font
					(size 1 1)
					(thickness 0.15)
				)
				(justify mirror)
			)
		)
		(property "License" "Apache-2.0"
			(at 4.337 268.515 0)
			(layer "B.Fab")
			(hide yes)
			(effects
				(font
					(size 1 1)
					(thickness 0.15)
				)
				(justify mirror)
			)
		)
		(property "MPN" "CL10A226MO7JZNC"
			(at 4.337 268.515 0)
			(layer "B.Fab")
			(hide yes)
			(effects
				(font
					(size 1 1)
					(thickness 0.15)
				)
				(justify mirror)
			)
		)
		(property "Manufacturer" "Samsung Electro-Mechanics"
			(at 4.337 268.515 0)
			(layer "B.Fab")
			(hide yes)
			(effects
				(font
					(size 1 1)
					(thickness 0.15)
				)
				(justify mirror)
			)
		)
		(property "Public" "False"
			(at 4.337 268.515 0)
			(layer "B.Fab")
			(hide yes)
			(effects
				(font
					(size 1 1)
					(thickness 0.15)
				)
				(justify mirror)
			)
		)
		(property "Val" "22u"
			(at 4.337 268.515 0)
			(layer "B.Fab")
			(hide yes)
			(effects
				(font
					(size 1 1)
					(thickness 0.15)
				)
				(justify mirror)
			)
		)
		(property "Voltage" "16V"
			(at 4.337 268.515 0)
			(layer "B.Fab")
			(hide yes)
			(effects
				(font
					(size 1 1)
					(thickness 0.15)
				)
				(justify mirror)
			)
		)
		(sheetname "KR to SFI #2")
		(sheetfile "kr_sfi.kicad_sch")
		(attr smd)
		(fp_line
			(start 0.15 0.4)
			(end -0.15 0.4)
			(stroke
				(width 0.15)
				(type solid)
			)
			(layer "B.SilkS")
		)
		(fp_line
			(start 0.15 -0.4)
			(end -0.15 -0.4)
			(stroke
				(width 0.15)
				(type solid)
			)
			(layer "B.SilkS")
		)
		(fp_rect
			(start -1.25 0.65)
			(end 1.25 -0.65)
			(stroke
				(width 0.05)
				(type solid)
			)
			(fill no)
			(layer "B.CrtYd")
		)
		(fp_rect
			(start -0.8 0.4)
			(end 0.8 -0.4)
			(stroke
				(width 0.15)
				(type solid)
			)
			(fill no)
			(layer "B.Fab")
		)
		(pad "1" smd roundrect
			(at -0.7 0 270)
			(size 0.8 1)
			(layers "B.Cu" "B.Mask" "B.Paste")
			(roundrect_rratio 0.2)
			(net 1 "GND")
			(pintype "passive")
			(teardrops
				(best_length_ratio 0.2)
				(max_length 1)
				(best_width_ratio 0.9)
				(max_width 2)
				(curved_edges yes)
				(filter_ratio 0.9)
				(enabled yes)
				(allow_two_segments yes)
				(prefer_zone_connections yes)
			)
		)
		(pad "2" smd roundrect
			(at 0.7 0 270)
			(size 0.8 1)
			(layers "B.Cu" "B.Mask" "B.Paste")
			(roundrect_rratio 0.2)
			(net 74 "+1V0")
			(pintype "passive")
			(teardrops
				(best_length_ratio 0.2)
				(max_length 1)
				(best_width_ratio 0.9)
				(max_width 2)
				(curved_edges yes)
				(filter_ratio 0.9)
				(enabled yes)
				(allow_two_segments yes)
				(prefer_zone_connections yes)
			)
		)
	)
	(footprint "antmicro-footprints:TP_SMD_0.75mm"
		(layer "B.Cu")
		(at 259.95 85.06 180)
		(property "Reference" "TP11"
			(at -3.15 -0.45 0)
			(layer "B.SilkS")
			(effects
				(font
					(size 0.7 0.7)
					(thickness 0.15)
				)
				(justify left bottom mirror)
			)
		)
		(property "Value" "TP_0.75mm_SMD"
			(at 0 -1.2 0)
			(layer "B.Fab")
			(effects
				(font
					(size 0.7 0.7)
					(thickness 0.15)
				)
				(justify left bottom mirror)
			)
		)
		(property "Author" "Antmicro"
			(at 519.9 170.12 0)
			(layer "B.Fab")
			(hide yes)
			(effects
				(font
					(size 1 1)
					(thickness 0.15)
				)
				(justify mirror)
			)
		)
		(property "License" "Apache-2.0"
			(at 519.9 170.12 0)
			(layer "B.Fab")
			(hide yes)
			(effects
				(font
					(size 1 1)
					(thickness 0.15)
				)
				(justify mirror)
			)
		)
		(property "MPN" ""
			(at 519.9 170.12 0)
			(layer "B.Fab")
			(hide yes)
			(effects
				(font
					(size 1 1)
					(thickness 0.15)
				)
				(justify mirror)
			)
		)
		(property "Manufacturer" ""
			(at 519.9 170.12 0)
			(layer "B.Fab")
			(hide yes)
			(effects
				(font
					(size 1 1)
					(thickness 0.15)
				)
				(justify mirror)
			)
		)
		(property "Public" "False"
			(at 519.9 170.12 0)
			(layer "B.Fab")
			(hide yes)
			(effects
				(font
					(size 1 1)
					(thickness 0.15)
				)
				(justify mirror)
			)
		)
		(sheetname "Misc")
		(sheetfile "misc.kicad_sch")
		(attr exclude_from_pos_files exclude_from_bom)
		(fp_circle
			(center 0 0)
			(end 0.475 0)
			(stroke
				(width 0.05)
				(type default)
			)
			(fill no)
			(layer "B.CrtYd")
		)
		(pad "1" smd circle
			(at 0 0 180)
			(size 0.75 0.75)
			(layers "B.Cu" "B.Mask")
			(net 703 "Net-(U24-GPIO3)")
			(pinfunction "1")
			(pintype "passive")
			(teardrops
				(best_length_ratio 0.4)
				(max_length 1)
				(best_width_ratio 0.9)
				(max_width 2)
				(curved_edges yes)
				(filter_ratio 0.9)
				(enabled yes)
				(allow_two_segments yes)
				(prefer_zone_connections yes)
			)
		)
	)
	(footprint "antmicro-footprints:R_0402_1005Metric"
		(layer "B.Cu")
		(at 126.09 140.06)
		(descr "Resistor SMD 0402")
		(tags "resistor SMD 0402")
		(property "Reference" "R289"
			(at -3.64 1.15 0)
			(layer "B.SilkS")
			(effects
				(font
					(size 0.7 0.7)
					(thickness 0.15)
				)
				(justify right bottom mirror)
			)
		)
		(property "Value" "R_10k_0402"
			(at -1.011843 -1.772047 0)
			(layer "B.Fab")
			(effects
				(font
					(size 0.7 0.7)
					(thickness 0.15)
				)
				(justify right bottom mirror)
			)
		)
		(property "Datasheet" "https://www.bourns.com/docs/product-datasheets/cr.pdf"
			(at 0 0 0)
			(layer "F.Fab")
			(hide yes)
			(effects
				(font
					(size 1.27 1.27)
					(thickness 0.15)
				)
			)
		)
		(property "Author" "Antmicro"
			(at 0 0 0)
			(layer "B.Fab")
			(hide yes)
			(effects
				(font
					(size 1 1)
					(thickness 0.15)
				)
				(justify mirror)
			)
		)
		(property "License" "Apache-2.0"
			(at 0 0 0)
			(layer "B.Fab")
			(hide yes)
			(effects
				(font
					(size 1 1)
					(thickness 0.15)
				)
				(justify mirror)
			)
		)
		(property "MPN" "CR0402-FX-1002GLF"
			(at 0 0 0)
			(layer "B.Fab")
			(hide yes)
			(effects
				(font
					(size 1 1)
					(thickness 0.15)
				)
				(justify mirror)
			)
		)
		(property "Manufacturer" "Bourns"
			(at 0 0 0)
			(layer "B.Fab")
			(hide yes)
			(effects
				(font
					(size 1 1)
					(thickness 0.15)
				)
				(justify mirror)
			)
		)
		(property "Public" "False"
			(at 0 0 0)
			(layer "B.Fab")
			(hide yes)
			(effects
				(font
					(size 1 1)
					(thickness 0.15)
				)
				(justify mirror)
			)
		)
		(property "Tolerance" "1%"
			(at 0 0 0)
			(layer "B.Fab")
			(hide yes)
			(effects
				(font
					(size 1 1)
					(thickness 0.15)
				)
				(justify mirror)
			)
		)
		(property "Val" "10k"
			(at 0 0 0)
			(layer "B.Fab")
			(hide yes)
			(effects
				(font
					(size 1 1)
					(thickness 0.15)
				)
				(justify mirror)
			)
		)
		(sheetname "KR to SFI #2")
		(sheetfile "kr_sfi.kicad_sch")
		(attr smd)
		(fp_rect
			(start -0.925 0.47)
			(end 0.925 -0.47)
			(stroke
				(width 0.05)
				(type default)
			)
			(fill no)
			(layer "B.CrtYd")
		)
		(fp_rect
			(start -0.5 0.25)
			(end 0.5 -0.25)
			(stroke
				(width 0.15)
				(type solid)
			)
			(fill no)
			(layer "B.Fab")
		)
		(pad "1" smd roundrect
			(at -0.48 0)
			(size 0.59 0.64)
			(layers "B.Cu" "B.Mask" "B.Paste")
			(roundrect_rratio 0.25)
			(net 1 "GND")
			(pintype "passive")
			(teardrops
				(best_length_ratio 0.2)
				(max_length 1)
				(best_width_ratio 0.9)
				(max_width 2)
				(curved_edges yes)
				(filter_ratio 0.9)
				(enabled yes)
				(allow_two_segments yes)
				(prefer_zone_connections yes)
			)
		)
		(pad "2" smd roundrect
			(at 0.48 0)
			(size 0.59 0.64)
			(layers "B.Cu" "B.Mask" "B.Paste")
			(roundrect_rratio 0.25)
			(net 674 "Net-(U45C-TESTEN)")
			(pintype "passive")
			(teardrops
				(best_length_ratio 0.2)
				(max_length 1)
				(best_width_ratio 0.9)
				(max_width 2)
				(curved_edges yes)
				(filter_ratio 0.9)
				(enabled yes)
				(allow_two_segments yes)
				(prefer_zone_connections yes)
			)
		)
	)
	(footprint "antmicro-footprints:C_0402_1005Metric"
		(layer "B.Cu")
		(at 218.247 130.326)
		(descr "Capacitor SMD 0402")
		(tags "capacitor SMD 0402")
		(property "Reference" "C107"
			(at -1.397 1.334 0)
			(layer "B.SilkS")
			(effects
				(font
					(size 0.7 0.7)
					(thickness 0.15)
				)
				(justify right bottom mirror)
			)
		)
		(property "Value" "C_100n_0402"
			(at -1.022927 -2.155213 0)
			(layer "B.Fab")
			(effects
				(font
					(size 0.7 0.7)
					(thickness 0.15)
				)
				(justify right bottom mirror)
			)
		)
		(property "Datasheet" "https://www.murata.com/products/productdetail?partno=GRM155R61H104KE14%23"
			(at 0 0 0)
			(layer "F.Fab")
			(hide yes)
			(effects
				(font
					(size 1.27 1.27)
					(thickness 0.15)
				)
			)
		)
		(property "Author" "Antmicro"
			(at 0 0 0)
			(layer "B.Fab")
			(hide yes)
			(effects
				(font
					(size 1 1)
					(thickness 0.15)
				)
				(justify mirror)
			)
		)
		(property "Dielectric" "X5R"
			(at 0 0 0)
			(layer "B.Fab")
			(hide yes)
			(effects
				(font
					(size 1 1)
					(thickness 0.15)
				)
				(justify mirror)
			)
		)
		(property "License" "Apache-2.0"
			(at 0 0 0)
			(layer "B.Fab")
			(hide yes)
			(effects
				(font
					(size 1 1)
					(thickness 0.15)
				)
				(justify mirror)
			)
		)
		(property "MPN" "GRM155R61H104KE14D"
			(at 0 0 0)
			(layer "B.Fab")
			(hide yes)
			(effects
				(font
					(size 1 1)
					(thickness 0.15)
				)
				(justify mirror)
			)
		)
		(property "Manufacturer" "Murata"
			(at 0 0 0)
			(layer "B.Fab")
			(hide yes)
			(effects
				(font
					(size 1 1)
					(thickness 0.15)
				)
				(justify mirror)
			)
		)
		(property "Public" "False"
			(at 0 0 0)
			(layer "B.Fab")
			(hide yes)
			(effects
				(font
					(size 1 1)
					(thickness 0.15)
				)
				(justify mirror)
			)
		)
		(property "Val" "100n"
			(at 0 0 0)
			(layer "B.Fab")
			(hide yes)
			(effects
				(font
					(size 1 1)
					(thickness 0.15)
				)
				(justify mirror)
			)
		)
		(property "Voltage" "50V"
			(at 0 0 0)
			(layer "B.Fab")
			(hide yes)
			(effects
				(font
					(size 1 1)
					(thickness 0.15)
				)
				(justify mirror)
			)
		)
		(sheetname "PCIe misc")
		(sheetfile "pcie_misc.kicad_sch")
		(attr smd)
		(fp_rect
			(start -0.925 0.47)
			(end 0.925 -0.47)
			(stroke
				(width 0.05)
				(type default)
			)
			(fill no)
			(layer "B.CrtYd")
		)
		(fp_line
			(start -0.494 -0.248)
			(end 0.504 -0.248)
			(stroke
				(width 0.15)
				(type solid)
			)
			(layer "B.Fab")
		)
		(fp_line
			(start -0.494 0.25)
			(end -0.494 -0.248)
			(stroke
				(width 0.15)
				(type solid)
			)
			(layer "B.Fab")
		)
		(fp_line
			(start 0.504 -0.248)
			(end 0.504 0.25)
			(stroke
				(width 0.15)
				(type solid)
			)
			(layer "B.Fab")
		)
		(fp_line
			(start 0.504 0.25)
			(end -0.494 0.25)
			(stroke
				(width 0.15)
				(type solid)
			)
			(layer "B.Fab")
		)
		(pad "1" smd roundrect
			(at -0.48 0)
			(size 0.59 0.64)
			(layers "B.Cu" "B.Mask" "B.Paste")
			(roundrect_rratio 0.25)
			(net 1 "GND")
			(pintype "passive")
			(teardrops
				(best_length_ratio 0.2)
				(max_length 1)
				(best_width_ratio 0.9)
				(max_width 2)
				(curved_edges yes)
				(filter_ratio 0.9)
				(enabled yes)
				(allow_two_segments yes)
				(prefer_zone_connections yes)
			)
		)
		(pad "2" smd roundrect
			(at 0.48 0)
			(size 0.59 0.64)
			(layers "B.Cu" "B.Mask" "B.Paste")
			(roundrect_rratio 0.25)
			(net 2 "+3V3")
			(pintype "passive")
			(teardrops
				(best_length_ratio 0.2)
				(max_length 1)
				(best_width_ratio 0.9)
				(max_width 2)
				(curved_edges yes)
				(filter_ratio 0.9)
				(enabled yes)
				(allow_two_segments yes)
				(prefer_zone_connections yes)
			)
		)
	)
	(footprint "antmicro-footprints:TP_SMD_0.75mm"
		(layer "B.Cu")
		(at 197.075 157.625 180)
		(property "Reference" "TP18"
			(at -3.425 -0.375 0)
			(layer "B.SilkS")
			(effects
				(font
					(size 0.7 0.7)
					(thickness 0.15)
				)
				(justify left bottom mirror)
			)
		)
		(property "Value" "TP_0.75mm_SMD"
			(at 3.225 -53.865 0)
			(layer "B.Fab")
			(hide yes)
			(effects
				(font
					(size 0.7 0.7)
					(thickness 0.15)
				)
				(justify left bottom mirror)
			)
		)
		(property "Author" "Antmicro"
			(at 429.2 321.82 0)
			(layer "B.Fab")
			(hide yes)
			(effects
				(font
					(size 1 1)
					(thickness 0.15)
				)
				(justify mirror)
			)
		)
		(property "License" "Apache-2.0"
			(at 429.2 321.82 0)
			(layer "B.Fab")
			(hide yes)
			(effects
				(font
					(size 1 1)
					(thickness 0.15)
				)
				(justify mirror)
			)
		)
		(property "MPN" ""
			(at 429.2 321.82 0)
			(layer "B.Fab")
			(hide yes)
			(effects
				(font
					(size 1 1)
					(thickness 0.15)
				)
				(justify mirror)
			)
		)
		(property "Manufacturer" ""
			(at 429.2 321.82 0)
			(layer "B.Fab")
			(hide yes)
			(effects
				(font
					(size 1 1)
					(thickness 0.15)
				)
				(justify mirror)
			)
		)
		(property "Public" "False"
			(at 429.2 321.82 0)
			(layer "B.Fab")
			(hide yes)
			(effects
				(font
					(size 1 1)
					(thickness 0.15)
				)
				(justify mirror)
			)
		)
		(sheetname "Com Express 7 Interfaces")
		(sheetfile "com_express_7_interfaces.kicad_sch")
		(attr exclude_from_pos_files exclude_from_bom)
		(fp_circle
			(center 0 0)
			(end 0.475 0)
			(stroke
				(width 0.05)
				(type default)
			)
			(fill no)
			(layer "B.CrtYd")
		)
		(pad "1" smd circle
			(at 0 0 180)
			(size 0.75 0.75)
			(layers "B.Cu" "B.Mask")
			(net 426 "Net-(J12K-10G_SDP0)")
			(pinfunction "1")
			(pintype "passive")
			(teardrops
				(best_length_ratio 0.4)
				(max_length 1)
				(best_width_ratio 0.9)
				(max_width 2)
				(curved_edges yes)
				(filter_ratio 0.9)
				(enabled yes)
				(allow_two_segments yes)
				(prefer_zone_connections yes)
			)
		)
	)
	(footprint "antmicro-footprints:TP_SMD_0.75mm"
		(layer "B.Cu")
		(at 122.3 150.21 180)
		(property "Reference" "TP51"
			(at -0.45 -0.35 90)
			(layer "B.SilkS")
			(effects
				(font
					(size 0.7 0.7)
					(thickness 0.15)
				)
				(justify left bottom mirror)
			)
		)
		(property "Value" "TP_0.75mm_SMD"
			(at 0 -1.2 0)
			(layer "B.Fab")
			(effects
				(font
					(size 0.7 0.7)
					(thickness 0.15)
				)
				(justify left bottom mirror)
			)
		)
		(property "Author" "Antmicro"
			(at 244.6 300.42 0)
			(layer "B.Fab")
			(hide yes)
			(effects
				(font
					(size 1 1)
					(thickness 0.15)
				)
				(justify mirror)
			)
		)
		(property "License" "Apache-2.0"
			(at 244.6 300.42 0)
			(layer "B.Fab")
			(hide yes)
			(effects
				(font
					(size 1 1)
					(thickness 0.15)
				)
				(justify mirror)
			)
		)
		(property "MPN" ""
			(at 244.6 300.42 0)
			(layer "B.Fab")
			(hide yes)
			(effects
				(font
					(size 1 1)
					(thickness 0.15)
				)
				(justify mirror)
			)
		)
		(property "Manufacturer" ""
			(at 244.6 300.42 0)
			(layer "B.Fab")
			(hide yes)
			(effects
				(font
					(size 1 1)
					(thickness 0.15)
				)
				(justify mirror)
			)
		)
		(property "Public" "False"
			(at 244.6 300.42 0)
			(layer "B.Fab")
			(hide yes)
			(effects
				(font
					(size 1 1)
					(thickness 0.15)
				)
				(justify mirror)
			)
		)
		(sheetname "PCIe redriver")
		(sheetfile "pcie_redriver.kicad_sch")
		(attr exclude_from_pos_files exclude_from_bom)
		(fp_circle
			(center 0 0)
			(end 0.475 0)
			(stroke
				(width 0.05)
				(type default)
			)
			(fill no)
			(layer "B.CrtYd")
		)
		(pad "1" smd circle
			(at 0 0 180)
			(size 0.75 0.75)
			(layers "B.Cu" "B.Mask")
			(net 714 "Net-(U39-I2C_{DONE})")
			(pinfunction "1")
			(pintype "passive")
			(teardrops
				(best_length_ratio 0.4)
				(max_length 1)
				(best_width_ratio 0.9)
				(max_width 2)
				(curved_edges yes)
				(filter_ratio 0.9)
				(enabled yes)
				(allow_two_segments yes)
				(prefer_zone_connections yes)
			)
		)
	)
	(footprint "antmicro-footprints:R_0402_1005Metric"
		(layer "B.Cu")
		(at 313.024999 106.15 -90)
		(descr "Resistor SMD 0402")
		(tags "resistor SMD 0402")
		(property "Reference" "R96"
			(at 0.81 -0.425001 90)
			(layer "B.SilkS")
			(effects
				(font
					(size 0.7 0.7)
					(thickness 0.15)
				)
				(justify left bottom mirror)
			)
		)
		(property "Value" "R_10k_0402"
			(at -1.011843 -1.772046 90)
			(layer "B.Fab")
			(effects
				(font
					(size 0.7 0.7)
					(thickness 0.15)
				)
				(justify left bottom mirror)
			)
		)
		(property "Datasheet" "https://www.bourns.com/docs/product-datasheets/cr.pdf"
			(at 0 0 270)
			(layer "F.Fab")
			(hide yes)
			(effects
				(font
					(size 1.27 1.27)
					(thickness 0.15)
				)
			)
		)
		(property "Author" "Antmicro"
			(at 206.874999 419.174999 0)
			(layer "B.Fab")
			(hide yes)
			(effects
				(font
					(size 1 1)
					(thickness 0.15)
				)
				(justify mirror)
			)
		)
		(property "License" "Apache-2.0"
			(at 206.874999 419.174999 0)
			(layer "B.Fab")
			(hide yes)
			(effects
				(font
					(size 1 1)
					(thickness 0.15)
				)
				(justify mirror)
			)
		)
		(property "MPN" "CR0402-FX-1002GLF"
			(at 206.874999 419.174999 0)
			(layer "B.Fab")
			(hide yes)
			(effects
				(font
					(size 1 1)
					(thickness 0.15)
				)
				(justify mirror)
			)
		)
		(property "Manufacturer" "Bourns"
			(at 206.874999 419.174999 0)
			(layer "B.Fab")
			(hide yes)
			(effects
				(font
					(size 1 1)
					(thickness 0.15)
				)
				(justify mirror)
			)
		)
		(property "Public" "False"
			(at 206.874999 419.174999 0)
			(layer "B.Fab")
			(hide yes)
			(effects
				(font
					(size 1 1)
					(thickness 0.15)
				)
				(justify mirror)
			)
		)
		(property "Tolerance" "1%"
			(at 206.874999 419.174999 0)
			(layer "B.Fab")
			(hide yes)
			(effects
				(font
					(size 1 1)
					(thickness 0.15)
				)
				(justify mirror)
			)
		)
		(property "Val" "10k"
			(at 206.874999 419.174999 0)
			(layer "B.Fab")
			(hide yes)
			(effects
				(font
					(size 1 1)
					(thickness 0.15)
				)
				(justify mirror)
			)
		)
		(sheetname "Power")
		(sheetfile "power.kicad_sch")
		(attr smd)
		(fp_rect
			(start -0.925 0.47)
			(end 0.925 -0.47)
			(stroke
				(width 0.05)
				(type default)
			)
			(fill no)
			(layer "B.CrtYd")
		)
		(fp_rect
			(start -0.5 0.25)
			(end 0.5 -0.25)
			(stroke
				(width 0.15)
				(type solid)
			)
			(fill no)
			(layer "B.Fab")
		)
		(pad "1" smd roundrect
			(at -0.48 0 270)
			(size 0.59 0.64)
			(layers "B.Cu" "B.Mask" "B.Paste")
			(roundrect_rratio 0.25)
			(net 889 "/Power/PG_{3V3}")
			(pintype "passive")
			(teardrops
				(best_length_ratio 0.2)
				(max_length 1)
				(best_width_ratio 0.9)
				(max_width 2)
				(curved_edges yes)
				(filter_ratio 0.9)
				(enabled yes)
				(allow_two_segments yes)
				(prefer_zone_connections yes)
			)
		)
		(pad "2" smd roundrect
			(at 0.48 0 270)
			(size 0.59 0.64)
			(layers "B.Cu" "B.Mask" "B.Paste")
			(roundrect_rratio 0.25)
			(net 64 "Net-(U19-V_{CC})")
			(pintype "passive")
			(teardrops
				(best_length_ratio 0.2)
				(max_length 1)
				(best_width_ratio 0.9)
				(max_width 2)
				(curved_edges yes)
				(filter_ratio 0.9)
				(enabled yes)
				(allow_two_segments yes)
				(prefer_zone_connections yes)
			)
		)
	)
	(footprint "antmicro-footprints:R_0402_1005Metric"
		(layer "B.Cu")
		(at 123.4 107.81)
		(descr "Resistor SMD 0402")
		(tags "resistor SMD 0402")
		(property "Reference" "R10"
			(at 0.8 0.45 0)
			(layer "B.SilkS")
			(effects
				(font
					(size 0.7 0.7)
					(thickness 0.15)
				)
				(justify right bottom mirror)
			)
		)
		(property "Value" "R_470R_0402"
			(at -1.011843 -1.772047 0)
			(layer "B.Fab")
			(effects
				(font
					(size 0.7 0.7)
					(thickness 0.15)
				)
				(justify right bottom mirror)
			)
		)
		(property "Datasheet" "https://www.bourns.com/docs/product-datasheets/cr.pdf"
			(at 0 0 0)
			(layer "F.Fab")
			(hide yes)
			(effects
				(font
					(size 1.27 1.27)
					(thickness 0.15)
				)
			)
		)
		(property "Author" "Antmicro"
			(at 0 0 0)
			(layer "B.Fab")
			(hide yes)
			(effects
				(font
					(size 1 1)
					(thickness 0.15)
				)
				(justify mirror)
			)
		)
		(property "License" "Apache-2.0"
			(at 0 0 0)
			(layer "B.Fab")
			(hide yes)
			(effects
				(font
					(size 1 1)
					(thickness 0.15)
				)
				(justify mirror)
			)
		)
		(property "MPN" "CR0402-FX-4700GLF"
			(at 0 0 0)
			(layer "B.Fab")
			(hide yes)
			(effects
				(font
					(size 1 1)
					(thickness 0.15)
				)
				(justify mirror)
			)
		)
		(property "Manufacturer" "Bourns"
			(at 0 0 0)
			(layer "B.Fab")
			(hide yes)
			(effects
				(font
					(size 1 1)
					(thickness 0.15)
				)
				(justify mirror)
			)
		)
		(property "Public" "False"
			(at 0 0 0)
			(layer "B.Fab")
			(hide yes)
			(effects
				(font
					(size 1 1)
					(thickness 0.15)
				)
				(justify mirror)
			)
		)
		(property "Tolerance" "1%"
			(at 0 0 0)
			(layer "B.Fab")
			(hide yes)
			(effects
				(font
					(size 1 1)
					(thickness 0.15)
				)
				(justify mirror)
			)
		)
		(property "Val" "470R"
			(at 0 0 0)
			(layer "B.Fab")
			(hide yes)
			(effects
				(font
					(size 1 1)
					(thickness 0.15)
				)
				(justify mirror)
			)
		)
		(sheetname "2xUSB3.0+RJ45")
		(sheetfile "usb3+rj45.kicad_sch")
		(attr smd dnp)
		(fp_rect
			(start -0.925 0.47)
			(end 0.925 -0.47)
			(stroke
				(width 0.05)
				(type default)
			)
			(fill no)
			(layer "B.CrtYd")
		)
		(fp_rect
			(start -0.5 0.25)
			(end 0.5 -0.25)
			(stroke
				(width 0.15)
				(type solid)
			)
			(fill no)
			(layer "B.Fab")
		)
		(pad "1" smd roundrect
			(at -0.48 0)
			(size 0.59 0.64)
			(layers "B.Cu" "B.Mask" "B.Paste")
			(roundrect_rratio 0.25)
			(net 157 "Net-(J1A-LED_D4)")
			(pintype "passive")
			(teardrops
				(best_length_ratio 0.2)
				(max_length 1)
				(best_width_ratio 0.9)
				(max_width 2)
				(curved_edges yes)
				(filter_ratio 0.9)
				(enabled yes)
				(allow_two_segments yes)
				(prefer_zone_connections yes)
			)
		)
		(pad "2" smd roundrect
			(at 0.48 0)
			(size 0.59 0.64)
			(layers "B.Cu" "B.Mask" "B.Paste")
			(roundrect_rratio 0.25)
			(net 2 "+3V3")
			(pintype "passive")
			(teardrops
				(best_length_ratio 0.2)
				(max_length 1)
				(best_width_ratio 0.9)
				(max_width 2)
				(curved_edges yes)
				(filter_ratio 0.9)
				(enabled yes)
				(allow_two_segments yes)
				(prefer_zone_connections yes)
			)
		)
	)
	(footprint "antmicro-footprints:TP_SMD_0.75mm"
		(layer "B.Cu")
		(at 183.5 170.8 90)
		(property "Reference" "TP36"
			(at -0.5 0.6 180)
			(layer "B.SilkS")
			(effects
				(font
					(size 0.7 0.7)
					(thickness 0.15)
				)
				(justify right bottom mirror)
			)
		)
		(property "Value" "TP_0.75mm_SMD"
			(at 0 -1.2 90)
			(layer "B.Fab")
			(effects
				(font
					(size 0.7 0.7)
					(thickness 0.15)
				)
				(justify right bottom mirror)
			)
		)
		(property "Author" "Antmicro"
			(at 371.06 -72.24 0)
			(layer "B.Fab")
			(hide yes)
			(effects
				(font
					(size 1 1)
					(thickness 0.15)
				)
				(justify mirror)
			)
		)
		(property "License" "Apache-2.0"
			(at 371.06 -72.24 0)
			(layer "B.Fab")
			(hide yes)
			(effects
				(font
					(size 1 1)
					(thickness 0.15)
				)
				(justify mirror)
			)
		)
		(property "MPN" ""
			(at 371.06 -72.24 0)
			(layer "B.Fab")
			(hide yes)
			(effects
				(font
					(size 1 1)
					(thickness 0.15)
				)
				(justify mirror)
			)
		)
		(property "Manufacturer" ""
			(at 371.06 -72.24 0)
			(layer "B.Fab")
			(hide yes)
			(effects
				(font
					(size 1 1)
					(thickness 0.15)
				)
				(justify mirror)
			)
		)
		(property "Public" "False"
			(at 371.06 -72.24 0)
			(layer "B.Fab")
			(hide yes)
			(effects
				(font
					(size 1 1)
					(thickness 0.15)
				)
				(justify mirror)
			)
		)
		(sheetname "Com Express 7 MGMT")
		(sheetfile "com_express_7_mgmt.kicad_sch")
		(attr exclude_from_pos_files exclude_from_bom)
		(fp_circle
			(center 0 0)
			(end 0.475 0)
			(stroke
				(width 0.05)
				(type default)
			)
			(fill no)
			(layer "B.CrtYd")
		)
		(pad "1" smd circle
			(at 0 0 90)
			(size 0.75 0.75)
			(layers "B.Cu" "B.Mask")
			(net 300 "Net-(J12D-~{SUS_S4})")
			(pinfunction "1")
			(pintype "passive")
			(teardrops
				(best_length_ratio 0.4)
				(max_length 1)
				(best_width_ratio 0.9)
				(max_width 2)
				(curved_edges yes)
				(filter_ratio 0.9)
				(enabled yes)
				(allow_two_segments yes)
				(prefer_zone_connections yes)
			)
		)
	)
	(footprint "antmicro-footprints:R_0402_1005Metric"
		(layer "B.Cu")
		(at 144.05 169.16 -90)
		(descr "Resistor SMD 0402")
		(tags "resistor SMD 0402")
		(property "Reference" "R55"
			(at -3.9 13.5 90)
			(layer "B.SilkS")
			(effects
				(font
					(size 0.7 0.7)
					(thickness 0.15)
				)
				(justify left bottom mirror)
			)
		)
		(property "Value" "R_1k_0402"
			(at -1.011843 -1.772047 90)
			(layer "B.Fab")
			(effects
				(font
					(size 0.7 0.7)
					(thickness 0.15)
				)
				(justify left bottom mirror)
			)
		)
		(property "Datasheet" "https://www.bourns.com/docs/product-datasheets/cr.pdf"
			(at 0 0 270)
			(layer "F.Fab")
			(hide yes)
			(effects
				(font
					(size 1.27 1.27)
					(thickness 0.15)
				)
			)
		)
		(property "Author" "Antmicro"
			(at -25.11 313.21 0)
			(layer "B.Fab")
			(hide yes)
			(effects
				(font
					(size 1 1)
					(thickness 0.15)
				)
				(justify mirror)
			)
		)
		(property "License" "Apache-2.0"
			(at -25.11 313.21 0)
			(layer "B.Fab")
			(hide yes)
			(effects
				(font
					(size 1 1)
					(thickness 0.15)
				)
				(justify mirror)
			)
		)
		(property "MPN" "CR0402-FX-1001GLF"
			(at -25.11 313.21 0)
			(layer "B.Fab")
			(hide yes)
			(effects
				(font
					(size 1 1)
					(thickness 0.15)
				)
				(justify mirror)
			)
		)
		(property "Manufacturer" "Bourns"
			(at -25.11 313.21 0)
			(layer "B.Fab")
			(hide yes)
			(effects
				(font
					(size 1 1)
					(thickness 0.15)
				)
				(justify mirror)
			)
		)
		(property "Public" "False"
			(at -25.11 313.21 0)
			(layer "B.Fab")
			(hide yes)
			(effects
				(font
					(size 1 1)
					(thickness 0.15)
				)
				(justify mirror)
			)
		)
		(property "Tolerance" "1%"
			(at -25.11 313.21 0)
			(layer "B.Fab")
			(hide yes)
			(effects
				(font
					(size 1 1)
					(thickness 0.15)
				)
				(justify mirror)
			)
		)
		(property "Val" "1k"
			(at -25.11 313.21 0)
			(layer "B.Fab")
			(hide yes)
			(effects
				(font
					(size 1 1)
					(thickness 0.15)
				)
				(justify mirror)
			)
		)
		(sheetname "2xSFP+")
		(sheetfile "2xSFP+.kicad_sch")
		(attr smd)
		(fp_rect
			(start -0.925 0.47)
			(end 0.925 -0.47)
			(stroke
				(width 0.05)
				(type default)
			)
			(fill no)
			(layer "B.CrtYd")
		)
		(fp_rect
			(start -0.5 0.25)
			(end 0.5 -0.25)
			(stroke
				(width 0.15)
				(type solid)
			)
			(fill no)
			(layer "B.Fab")
		)
		(pad "1" smd roundrect
			(at -0.48 0 270)
			(size 0.59 0.64)
			(layers "B.Cu" "B.Mask" "B.Paste")
			(roundrect_rratio 0.25)
			(net 166 "Net-(J2A-MOD_{ABS})")
			(pintype "passive")
			(teardrops
				(best_length_ratio 0.2)
				(max_length 1)
				(best_width_ratio 0.9)
				(max_width 2)
				(curved_edges yes)
				(filter_ratio 0.9)
				(enabled yes)
				(allow_two_segments yes)
				(prefer_zone_connections yes)
			)
		)
		(pad "2" smd roundrect
			(at 0.48 0 270)
			(size 0.59 0.64)
			(layers "B.Cu" "B.Mask" "B.Paste")
			(roundrect_rratio 0.25)
			(net 2 "+3V3")
			(pintype "passive")
			(teardrops
				(best_length_ratio 0.2)
				(max_length 1)
				(best_width_ratio 0.9)
				(max_width 2)
				(curved_edges yes)
				(filter_ratio 0.9)
				(enabled yes)
				(allow_two_segments yes)
				(prefer_zone_connections yes)
			)
		)
	)
	(footprint "antmicro-footprints:SOT-23-3"
		(layer "B.Cu")
		(at 97.75 71.86 90)
		(property "Reference" "Q8"
			(at 0.95 0.45 180)
			(layer "B.SilkS")
			(effects
				(font
					(size 0.7 0.7)
					(thickness 0.15)
				)
				(justify right bottom mirror)
			)
		)
		(property "Value" "BSS138-7-F"
			(at -1.9 -2.7 90)
			(layer "B.Fab")
			(effects
				(font
					(size 0.7 0.7)
					(thickness 0.15)
				)
				(justify right bottom mirror)
			)
		)
		(property "Datasheet" "https://www.diodes.com/assets/Datasheets/ds30144.pdf"
			(at 0 0 90)
			(layer "F.Fab")
			(hide yes)
			(effects
				(font
					(size 1.27 1.27)
					(thickness 0.15)
				)
			)
		)
		(property "Author" "Antmicro"
			(at 169.61 -25.89 0)
			(layer "B.Fab")
			(hide yes)
			(effects
				(font
					(size 1 1)
					(thickness 0.15)
				)
				(justify mirror)
			)
		)
		(property "License" "Apache-2.0"
			(at 169.61 -25.89 0)
			(layer "B.Fab")
			(hide yes)
			(effects
				(font
					(size 1 1)
					(thickness 0.15)
				)
				(justify mirror)
			)
		)
		(property "MPN" "BSS138-7-F"
			(at 169.61 -25.89 0)
			(layer "B.Fab")
			(hide yes)
			(effects
				(font
					(size 1 1)
					(thickness 0.15)
				)
				(justify mirror)
			)
		)
		(property "Manufacturer" "Diodes Incorporated"
			(at 169.61 -25.89 0)
			(layer "B.Fab")
			(hide yes)
			(effects
				(font
					(size 1 1)
					(thickness 0.15)
				)
				(justify mirror)
			)
		)
		(sheetname "Misc")
		(sheetfile "misc.kicad_sch")
		(attr smd)
		(fp_line
			(start 0.7 -1.5)
			(end 0.7 -0.4)
			(stroke
				(width 0.15)
				(type solid)
			)
			(layer "B.SilkS")
		)
		(fp_line
			(start -0.7 -1.5)
			(end 0.7 -1.5)
			(stroke
				(width 0.15)
				(type solid)
			)
			(layer "B.SilkS")
		)
		(fp_line
			(start -0.7 -1.35)
			(end -0.7 -1.5)
			(stroke
				(width 0.15)
				(type solid)
			)
			(layer "B.SilkS")
		)
		(fp_line
			(start -0.85 1.35)
			(end -1.45 1.35)
			(stroke
				(width 0.15)
				(type solid)
			)
			(layer "B.SilkS")
		)
		(fp_line
			(start 0.7 1.5)
			(end 0.7 0.4)
			(stroke
				(width 0.15)
				(type solid)
			)
			(layer "B.SilkS")
		)
		(fp_line
			(start -0.7 1.5)
			(end -0.85 1.35)
			(stroke
				(width 0.15)
				(type solid)
			)
			(layer "B.SilkS")
		)
		(fp_line
			(start -0.7 1.5)
			(end 0.7 1.5)
			(stroke
				(width 0.15)
				(type solid)
			)
			(layer "B.SilkS")
		)
		(fp_line
			(start 0.85 -1.65)
			(end 0.85 -0.45)
			(stroke
				(width 0.05)
				(type solid)
			)
			(layer "B.CrtYd")
		)
		(fp_line
			(start -0.85 -1.65)
			(end 0.85 -1.65)
			(stroke
				(width 0.05)
				(type solid)
			)
			(layer "B.CrtYd")
		)
		(fp_line
			(start -0.85 -1.4)
			(end -0.85 -1.65)
			(stroke
				(width 0.05)
				(type solid)
			)
			(layer "B.CrtYd")
		)
		(fp_line
			(start -1.75 -1.4)
			(end -0.85 -1.4)
			(stroke
				(width 0.05)
				(type solid)
			)
			(layer "B.CrtYd")
		)
		(fp_line
			(start -0.85 -0.5)
			(end -1.75 -0.5)
			(stroke
				(width 0.05)
				(type solid)
			)
			(layer "B.CrtYd")
		)
		(fp_line
			(start -1.75 -0.5)
			(end -1.75 -1.4)
			(stroke
				(width 0.05)
				(type solid)
			)
			(layer "B.CrtYd")
		)
		(fp_line
			(start 1.75 -0.45)
			(end 1.75 0.45)
			(stroke
				(width 0.05)
				(type solid)
			)
			(layer "B.CrtYd")
		)
		(fp_line
			(start 0.85 -0.45)
			(end 1.75 -0.45)
			(stroke
				(width 0.05)
				(type solid)
			)
			(layer "B.CrtYd")
		)
		(fp_line
			(start 1.75 0.45)
			(end 0.825 0.45)
			(stroke
				(width 0.05)
				(type solid)
			)
			(layer "B.CrtYd")
		)
		(fp_line
			(start 0.825 0.45)
			(end 0.825 1.6)
			(stroke
				(width 0.05)
				(type solid)
			)
			(layer "B.CrtYd")
		)
		(fp_line
			(start -0.85 0.5)
			(end -0.85 -0.5)
			(stroke
				(width 0.05)
				(type solid)
			)
			(layer "B.CrtYd")
		)
		(fp_line
			(start -1.75 0.5)
			(end -0.85 0.5)
			(stroke
				(width 0.05)
				(type solid)
			)
			(layer "B.CrtYd")
		)
		(fp_line
			(start -0.9 1.4)
			(end -0.9 1.6)
			(stroke
				(width 0.05)
				(type solid)
			)
			(layer "B.CrtYd")
		)
		(fp_line
			(start -1.75 1.4)
			(end -1.75 0.5)
			(stroke
				(width 0.05)
				(type solid)
			)
			(layer "B.CrtYd")
		)
		(fp_line
			(start -1.75 1.4)
			(end -0.9 1.4)
			(stroke
				(width 0.05)
				(type solid)
			)
			(layer "B.CrtYd")
		)
		(fp_line
			(start 0.825 1.6)
			(end -0.9 1.6)
			(stroke
				(width 0.05)
				(type solid)
			)
			(layer "B.CrtYd")
		)
		(fp_line
			(start -0.712 -1.523)
			(end -0.712 1.325)
			(stroke
				(width 0.15)
				(type solid)
			)
			(layer "B.Fab")
		)
		(fp_line
			(start 0.688 -1.519)
			(end -0.712 -1.519)
			(stroke
				(width 0.15)
				(type solid)
			)
			(layer "B.Fab")
		)
		(fp_line
			(start -0.712 1.325)
			(end -0.437 1.526)
			(stroke
				(width 0.15)
				(type solid)
			)
			(layer "B.Fab")
		)
		(fp_line
			(start 0.688 1.52)
			(end 0.688 -1.519)
			(stroke
				(width 0.15)
				(type solid)
			)
			(layer "B.Fab")
		)
		(fp_line
			(start 0.688 1.526)
			(end -0.437 1.526)
			(stroke
				(width 0.15)
				(type solid)
			)
			(layer "B.Fab")
		)
		(pad "1" smd roundrect
			(at -1.1 0.951 90)
			(size 1 0.6)
			(layers "B.Cu" "B.Mask" "B.Paste")
			(roundrect_rratio 0.15)
			(net 539 "/Misc/~{PWR_OK}")
			(pinfunction "G")
			(pintype "bidirectional")
			(teardrops
				(best_length_ratio 0.2)
				(max_length 1)
				(best_width_ratio 0.9)
				(max_width 2)
				(curved_edges yes)
				(filter_ratio 0.9)
				(enabled yes)
				(allow_two_segments yes)
				(prefer_zone_connections yes)
			)
		)
		(pad "2" smd roundrect
			(at -1.1 -0.949 90)
			(size 1 0.6)
			(layers "B.Cu" "B.Mask" "B.Paste")
			(roundrect_rratio 0.15)
			(net 1 "GND")
			(pinfunction "S")
			(pintype "bidirectional")
			(teardrops
				(best_length_ratio 0.2)
				(max_length 1)
				(best_width_ratio 0.9)
				(max_width 2)
				(curved_edges yes)
				(filter_ratio 0.9)
				(enabled yes)
				(allow_two_segments yes)
				(prefer_zone_connections yes)
			)
		)
		(pad "3" smd roundrect
			(at 1.1 0.0005 90)
			(size 1 0.6)
			(layers "B.Cu" "B.Mask" "B.Paste")
			(roundrect_rratio 0.15)
			(net 540 "Net-(Q8-D)")
			(pinfunction "D")
			(pintype "bidirectional")
			(teardrops
				(best_length_ratio 0.2)
				(max_length 1)
				(best_width_ratio 0.9)
				(max_width 2)
				(curved_edges yes)
				(filter_ratio 0.9)
				(enabled yes)
				(allow_two_segments yes)
				(prefer_zone_connections yes)
			)
		)
	)
	(footprint "antmicro-footprints:C_0402_1005Metric"
		(layer "B.Cu")
		(at 131.79 134.86)
		(descr "Capacitor SMD 0402")
		(tags "capacitor SMD 0402")
		(property "Reference" "C194"
			(at -2.99 -4.85 0)
			(layer "B.SilkS")
			(effects
				(font
					(size 0.7 0.7)
					(thickness 0.15)
				)
				(justify right bottom mirror)
			)
		)
		(property "Value" "C_100n_0402"
			(at -1.022927 -2.155213 0)
			(layer "B.Fab")
			(effects
				(font
					(size 0.7 0.7)
					(thickness 0.15)
				)
				(justify right bottom mirror)
			)
		)
		(property "Datasheet" "https://www.murata.com/products/productdetail?partno=GRM155R61H104KE14%23"
			(at 0 0 0)
			(layer "F.Fab")
			(hide yes)
			(effects
				(font
					(size 1.27 1.27)
					(thickness 0.15)
				)
			)
		)
		(property "Author" "Antmicro"
			(at 0 0 0)
			(layer "B.Fab")
			(hide yes)
			(effects
				(font
					(size 1 1)
					(thickness 0.15)
				)
				(justify mirror)
			)
		)
		(property "Dielectric" "X5R"
			(at 0 0 0)
			(layer "B.Fab")
			(hide yes)
			(effects
				(font
					(size 1 1)
					(thickness 0.15)
				)
				(justify mirror)
			)
		)
		(property "License" "Apache-2.0"
			(at 0 0 0)
			(layer "B.Fab")
			(hide yes)
			(effects
				(font
					(size 1 1)
					(thickness 0.15)
				)
				(justify mirror)
			)
		)
		(property "MPN" "GRM155R61H104KE14D"
			(at 0 0 0)
			(layer "B.Fab")
			(hide yes)
			(effects
				(font
					(size 1 1)
					(thickness 0.15)
				)
				(justify mirror)
			)
		)
		(property "Manufacturer" "Murata"
			(at 0 0 0)
			(layer "B.Fab")
			(hide yes)
			(effects
				(font
					(size 1 1)
					(thickness 0.15)
				)
				(justify mirror)
			)
		)
		(property "Public" "False"
			(at 0 0 0)
			(layer "B.Fab")
			(hide yes)
			(effects
				(font
					(size 1 1)
					(thickness 0.15)
				)
				(justify mirror)
			)
		)
		(property "Val" "100n"
			(at 0 0 0)
			(layer "B.Fab")
			(hide yes)
			(effects
				(font
					(size 1 1)
					(thickness 0.15)
				)
				(justify mirror)
			)
		)
		(property "Voltage" "50V"
			(at 0 0 0)
			(layer "B.Fab")
			(hide yes)
			(effects
				(font
					(size 1 1)
					(thickness 0.15)
				)
				(justify mirror)
			)
		)
		(sheetname "KR to SFI #2")
		(sheetfile "kr_sfi.kicad_sch")
		(attr smd)
		(fp_rect
			(start -0.925 0.47)
			(end 0.925 -0.47)
			(stroke
				(width 0.05)
				(type default)
			)
			(fill no)
			(layer "B.CrtYd")
		)
		(fp_line
			(start -0.494 -0.248)
			(end 0.504 -0.248)
			(stroke
				(width 0.15)
				(type solid)
			)
			(layer "B.Fab")
		)
		(fp_line
			(start -0.494 0.25)
			(end -0.494 -0.248)
			(stroke
				(width 0.15)
				(type solid)
			)
			(layer "B.Fab")
		)
		(fp_line
			(start 0.504 -0.248)
			(end 0.504 0.25)
			(stroke
				(width 0.15)
				(type solid)
			)
			(layer "B.Fab")
		)
		(fp_line
			(start 0.504 0.25)
			(end -0.494 0.25)
			(stroke
				(width 0.15)
				(type solid)
			)
			(layer "B.Fab")
		)
		(pad "1" smd roundrect
			(at -0.48 0)
			(size 0.59 0.64)
			(layers "B.Cu" "B.Mask" "B.Paste")
			(roundrect_rratio 0.25)
			(net 1 "GND")
			(pintype "passive")
			(teardrops
				(best_length_ratio 0.2)
				(max_length 1)
				(best_width_ratio 0.9)
				(max_width 2)
				(curved_edges yes)
				(filter_ratio 0.9)
				(enabled yes)
				(allow_two_segments yes)
				(prefer_zone_connections yes)
			)
		)
		(pad "2" smd roundrect
			(at 0.48 0)
			(size 0.59 0.64)
			(layers "B.Cu" "B.Mask" "B.Paste")
			(roundrect_rratio 0.25)
			(net 74 "+1V0")
			(pintype "passive")
			(teardrops
				(best_length_ratio 0.2)
				(max_length 1)
				(best_width_ratio 0.9)
				(max_width 2)
				(curved_edges yes)
				(filter_ratio 0.9)
				(enabled yes)
				(allow_two_segments yes)
				(prefer_zone_connections yes)
			)
		)
	)
	(footprint "antmicro-footprints:TP_SMD_0.75mm"
		(layer "B.Cu")
		(at 184.25 149.1 180)
		(property "Reference" "TP21"
			(at -3.25 -0.4 0)
			(layer "B.SilkS")
			(effects
				(font
					(size 0.7 0.7)
					(thickness 0.15)
				)
				(justify left bottom mirror)
			)
		)
		(property "Value" "TP_0.75mm_SMD"
			(at 3.225 -53.865 0)
			(layer "B.Fab")
			(hide yes)
			(effects
				(font
					(size 0.7 0.7)
					(thickness 0.15)
				)
				(justify left bottom mirror)
			)
		)
		(property "Author" "Antmicro"
			(at 444.9 333.72 0)
			(layer "B.Fab")
			(hide yes)
			(effects
				(font
					(size 1 1)
					(thickness 0.15)
				)
				(justify mirror)
			)
		)
		(property "License" "Apache-2.0"
			(at 444.9 333.72 0)
			(layer "B.Fab")
			(hide yes)
			(effects
				(font
					(size 1 1)
					(thickness 0.15)
				)
				(justify mirror)
			)
		)
		(property "MPN" ""
			(at 444.9 333.72 0)
			(layer "B.Fab")
			(hide yes)
			(effects
				(font
					(size 1 1)
					(thickness 0.15)
				)
				(justify mirror)
			)
		)
		(property "Manufacturer" ""
			(at 444.9 333.72 0)
			(layer "B.Fab")
			(hide yes)
			(effects
				(font
					(size 1 1)
					(thickness 0.15)
				)
				(justify mirror)
			)
		)
		(property "Public" "False"
			(at 444.9 333.72 0)
			(layer "B.Fab")
			(hide yes)
			(effects
				(font
					(size 1 1)
					(thickness 0.15)
				)
				(justify mirror)
			)
		)
		(sheetname "Com Express 7 Interfaces")
		(sheetfile "com_express_7_interfaces.kicad_sch")
		(attr exclude_from_pos_files exclude_from_bom)
		(fp_circle
			(center 0 0)
			(end 0.475 0)
			(stroke
				(width 0.05)
				(type default)
			)
			(fill no)
			(layer "B.CrtYd")
		)
		(pad "1" smd circle
			(at 0 0 180)
			(size 0.75 0.75)
			(layers "B.Cu" "B.Mask")
			(net 471 "Net-(J12K-10G_SDP3)")
			(pinfunction "1")
			(pintype "passive")
			(teardrops
				(best_length_ratio 0.4)
				(max_length 1)
				(best_width_ratio 0.9)
				(max_width 2)
				(curved_edges yes)
				(filter_ratio 0.9)
				(enabled yes)
				(allow_two_segments yes)
				(prefer_zone_connections yes)
			)
		)
	)
	(footprint "antmicro-footprints:C_0402_1005Metric"
		(layer "B.Cu")
		(at 198.560696 137.023438 135)
		(descr "Capacitor SMD 0402")
		(tags "capacitor SMD 0402")
		(property "Reference" "C126"
			(at -2.768935 -0.026345 135)
			(layer "B.SilkS")
			(effects
				(font
					(size 0.7 0.7)
					(thickness 0.15)
				)
				(justify right bottom mirror)
			)
		)
		(property "Value" "C_220n_0402"
			(at -1.022927 -2.155213 135)
			(layer "B.Fab")
			(effects
				(font
					(size 0.7 0.7)
					(thickness 0.15)
				)
				(justify right bottom mirror)
			)
		)
		(property "Datasheet" "https://www.yageo.com/en/Chart/Download/pdf/CC0402KRX5R6BB224"
			(at 0 0 135)
			(layer "F.Fab")
			(hide yes)
			(effects
				(font
					(size 1.27 1.27)
					(thickness 0.15)
				)
			)
		)
		(property "Author" "Antmicro"
			(at 336.71 -36.089999 45)
			(layer "B.Fab")
			(hide yes)
			(effects
				(font
					(size 1 1)
					(thickness 0.15)
				)
				(justify mirror)
			)
		)
		(property "Dielectric" ""
			(at 336.71 -36.089999 45)
			(layer "B.Fab")
			(hide yes)
			(effects
				(font
					(size 1 1)
					(thickness 0.15)
				)
				(justify mirror)
			)
		)
		(property "License" "Apache-2.0"
			(at 336.71 -36.089999 45)
			(layer "B.Fab")
			(hide yes)
			(effects
				(font
					(size 1 1)
					(thickness 0.15)
				)
				(justify mirror)
			)
		)
		(property "MPN" "CC0402KRX5R6BB224"
			(at 336.71 -36.089999 45)
			(layer "B.Fab")
			(hide yes)
			(effects
				(font
					(size 1 1)
					(thickness 0.15)
				)
				(justify mirror)
			)
		)
		(property "Manufacturer" "YAGEO"
			(at 336.71 -36.089999 45)
			(layer "B.Fab")
			(hide yes)
			(effects
				(font
					(size 1 1)
					(thickness 0.15)
				)
				(justify mirror)
			)
		)
		(property "Public" "False"
			(at 336.71 -36.089999 45)
			(layer "B.Fab")
			(hide yes)
			(effects
				(font
					(size 1 1)
					(thickness 0.15)
				)
				(justify mirror)
			)
		)
		(property "Val" "220n"
			(at 336.71 -36.089999 45)
			(layer "B.Fab")
			(hide yes)
			(effects
				(font
					(size 1 1)
					(thickness 0.15)
				)
				(justify mirror)
			)
		)
		(property "Voltage" ""
			(at 336.71 -36.089999 45)
			(layer "B.Fab")
			(hide yes)
			(effects
				(font
					(size 1 1)
					(thickness 0.15)
				)
				(justify mirror)
			)
		)
		(sheetname "PCIe redriver")
		(sheetfile "pcie_redriver.kicad_sch")
		(attr smd)
		(fp_poly
			(pts
				(xy -0.925 0.47) (xy 0.925 0.47) (xy 0.925 -0.47) (xy -0.925 -0.47)
			)
			(stroke
				(width 0.05)
				(type default)
			)
			(fill no)
			(layer "B.CrtYd")
		)
		(fp_line
			(start 0.504 -0.248)
			(end 0.504 0.25)
			(stroke
				(width 0.15)
				(type solid)
			)
			(layer "B.Fab")
		)
		(fp_line
			(start 0.504 0.25)
			(end -0.494 0.25)
			(stroke
				(width 0.15)
				(type solid)
			)
			(layer "B.Fab")
		)
		(fp_line
			(start -0.494 -0.248)
			(end 0.504 -0.248)
			(stroke
				(width 0.15)
				(type solid)
			)
			(layer "B.Fab")
		)
		(fp_line
			(start -0.494 0.25)
			(end -0.494 -0.248)
			(stroke
				(width 0.15)
				(type solid)
			)
			(layer "B.Fab")
		)
		(pad "1" smd roundrect
			(at -0.48 0 135)
			(size 0.59 0.64)
			(layers "B.Cu" "B.Mask" "B.Paste")
			(roundrect_rratio 0.25)
			(net 221 "/Com Express 7 Interfaces/PCIe_{B1x4}.RX0-")
			(pintype "passive")
			(teardrops
				(best_length_ratio 0.2)
				(max_length 1)
				(best_width_ratio 0.9)
				(max_width 2)
				(curved_edges yes)
				(filter_ratio 0.9)
				(enabled yes)
				(allow_two_segments yes)
				(prefer_zone_connections yes)
			)
		)
		(pad "2" smd roundrect
			(at 0.48 0 135)
			(size 0.59 0.64)
			(layers "B.Cu" "B.Mask" "B.Paste")
			(roundrect_rratio 0.25)
			(net 101 "/PCIe redriver/PCIe_{I}_C.RX0-")
			(pintype "passive")
			(teardrops
				(best_length_ratio 0.2)
				(max_length 1)
				(best_width_ratio 0.9)
				(max_width 2)
				(curved_edges yes)
				(filter_ratio 0.9)
				(enabled yes)
				(allow_two_segments yes)
				(prefer_zone_connections yes)
			)
		)
	)
	(footprint "antmicro-footprints:R_0402_1005Metric"
		(layer "B.Cu")
		(at 198.752322 135.660843 135)
		(descr "Resistor SMD 0402")
		(tags "resistor SMD 0402")
		(property "Reference" "R215"
			(at -1.051351 0.430289 135)
			(layer "B.SilkS")
			(effects
				(font
					(size 0.7 0.7)
					(thickness 0.15)
				)
				(justify right top mirror)
			)
		)
		(property "Value" "R_0R_0402"
			(at -1.011843 -1.772046 135)
			(layer "B.Fab")
			(effects
				(font
					(size 0.7 0.7)
					(thickness 0.15)
				)
				(justify right top mirror)
			)
		)
		(property "Datasheet" "https://industrial.panasonic.com/cdbs/www-data/pdf/RDA0000/AOA0000C301.pdf"
			(at 0 0 135)
			(layer "B.Fab")
			(hide yes)
			(effects
				(font
					(size 1.27 1.27)
					(thickness 0.15)
				)
				(justify mirror)
			)
		)
		(property "Author" "Antmicro"
			(at 324.173 46.429 45)
			(layer "B.Fab")
			(hide yes)
			(effects
				(font
					(size 1 1)
					(thickness 0.15)
				)
				(justify mirror)
			)
		)
		(property "Current" "1A"
			(at 324.173 46.429 45)
			(layer "B.Fab")
			(hide yes)
			(effects
				(font
					(size 1 1)
					(thickness 0.15)
				)
				(justify mirror)
			)
		)
		(property "License" "Apache-2.0"
			(at 324.173 46.429 45)
			(layer "B.Fab")
			(hide yes)
			(effects
				(font
					(size 1 1)
					(thickness 0.15)
				)
				(justify mirror)
			)
		)
		(property "MPN" "ERJ2GE0R00X"
			(at 324.173 46.429 45)
			(layer "B.Fab")
			(hide yes)
			(effects
				(font
					(size 1 1)
					(thickness 0.15)
				)
				(justify mirror)
			)
		)
		(property "Manufacturer" "Panasonic"
			(at 324.173 46.429 45)
			(layer "B.Fab")
			(hide yes)
			(effects
				(font
					(size 1 1)
					(thickness 0.15)
				)
				(justify mirror)
			)
		)
		(property "Public" "False"
			(at 324.173 46.429 45)
			(layer "B.Fab")
			(hide yes)
			(effects
				(font
					(size 1 1)
					(thickness 0.15)
				)
				(justify mirror)
			)
		)
		(property "Tolerance" ""
			(at 324.173 46.429 45)
			(layer "B.Fab")
			(hide yes)
			(effects
				(font
					(size 1 1)
					(thickness 0.15)
				)
				(justify mirror)
			)
		)
		(property "Val" "0R"
			(at 324.173 46.429 45)
			(layer "B.Fab")
			(hide yes)
			(effects
				(font
					(size 1 1)
					(thickness 0.15)
				)
				(justify mirror)
			)
		)
		(sheetname "PCIe redriver")
		(sheetfile "pcie_redriver.kicad_sch")
		(attr smd)
		(fp_poly
			(pts
				(xy -0.925 0.47) (xy 0.925 0.47) (xy 0.925 -0.47) (xy -0.925 -0.47)
			)
			(stroke
				(width 0.05)
				(type default)
			)
			(fill no)
			(layer "B.CrtYd")
		)
		(fp_poly
			(pts
				(xy -0.5 0.25) (xy 0.5 0.25) (xy 0.5 -0.25) (xy -0.5 -0.25)
			)
			(stroke
				(width 0.15)
				(type solid)
			)
			(fill no)
			(layer "B.Fab")
		)
		(pad "1" smd roundrect
			(at -0.48 0 135)
			(size 0.59 0.64)
			(layers "B.Cu" "B.Mask" "B.Paste")
			(roundrect_rratio 0.25)
			(net 2 "+3V3")
			(pintype "passive")
			(teardrops
				(best_length_ratio 0.2)
				(max_length 1)
				(best_width_ratio 0.9)
				(max_width 2)
				(curved_edges yes)
				(filter_ratio 0.9)
				(enabled yes)
				(allow_two_segments yes)
				(prefer_zone_connections yes)
			)
		)
		(pad "2" smd roundrect
			(at 0.48 0 135)
			(size 0.59 0.64)
			(layers "B.Cu" "B.Mask" "B.Paste")
			(roundrect_rratio 0.25)
			(net 630 "Net-(U40-RXDET)")
			(pintype "passive")
			(teardrops
				(best_length_ratio 0.2)
				(max_length 1)
				(best_width_ratio 0.9)
				(max_width 2)
				(curved_edges yes)
				(filter_ratio 0.9)
				(enabled yes)
				(allow_two_segments yes)
				(prefer_zone_connections yes)
			)
		)
	)
	(footprint "antmicro-footprints:R_0402_1005Metric"
		(layer "B.Cu")
		(at 110.9 69.86 -90)
		(descr "Resistor SMD 0402")
		(tags "resistor SMD 0402")
		(property "Reference" "R73"
			(at 0.8 -0.45 90)
			(layer "B.SilkS")
			(effects
				(font
					(size 0.7 0.7)
					(thickness 0.15)
				)
				(justify left bottom mirror)
			)
		)
		(property "Value" "R_220R_0402"
			(at -1.011843 -1.772047 90)
			(layer "B.Fab")
			(effects
				(font
					(size 0.7 0.7)
					(thickness 0.15)
				)
				(justify left bottom mirror)
			)
		)
		(property "Datasheet" "https://www.bourns.com/docs/product-datasheets/cr.pdf"
			(at 0 0 270)
			(layer "F.Fab")
			(hide yes)
			(effects
				(font
					(size 1.27 1.27)
					(thickness 0.15)
				)
			)
		)
		(property "Author" "Antmicro"
			(at 41.04 180.76 0)
			(layer "B.Fab")
			(hide yes)
			(effects
				(font
					(size 1 1)
					(thickness 0.15)
				)
				(justify mirror)
			)
		)
		(property "License" "Apache-2.0"
			(at 41.04 180.76 0)
			(layer "B.Fab")
			(hide yes)
			(effects
				(font
					(size 1 1)
					(thickness 0.15)
				)
				(justify mirror)
			)
		)
		(property "MPN" "CR0402-FX-2200GLF"
			(at 41.04 180.76 0)
			(layer "B.Fab")
			(hide yes)
			(effects
				(font
					(size 1 1)
					(thickness 0.15)
				)
				(justify mirror)
			)
		)
		(property "Manufacturer" "Bourns"
			(at 41.04 180.76 0)
			(layer "B.Fab")
			(hide yes)
			(effects
				(font
					(size 1 1)
					(thickness 0.15)
				)
				(justify mirror)
			)
		)
		(property "Public" "False"
			(at 41.04 180.76 0)
			(layer "B.Fab")
			(hide yes)
			(effects
				(font
					(size 1 1)
					(thickness 0.15)
				)
				(justify mirror)
			)
		)
		(property "Tolerance" "1%"
			(at 41.04 180.76 0)
			(layer "B.Fab")
			(hide yes)
			(effects
				(font
					(size 1 1)
					(thickness 0.15)
				)
				(justify mirror)
			)
		)
		(property "Val" "220R"
			(at 41.04 180.76 0)
			(layer "B.Fab")
			(hide yes)
			(effects
				(font
					(size 1 1)
					(thickness 0.15)
				)
				(justify mirror)
			)
		)
		(sheetname "USB-C console")
		(sheetfile "usb-c_console.kicad_sch")
		(attr smd)
		(fp_rect
			(start -0.925 0.47)
			(end 0.925 -0.47)
			(stroke
				(width 0.05)
				(type default)
			)
			(fill no)
			(layer "B.CrtYd")
		)
		(fp_rect
			(start -0.5 0.25)
			(end 0.5 -0.25)
			(stroke
				(width 0.15)
				(type solid)
			)
			(fill no)
			(layer "B.Fab")
		)
		(pad "1" smd roundrect
			(at -0.48 0 270)
			(size 0.59 0.64)
			(layers "B.Cu" "B.Mask" "B.Paste")
			(roundrect_rratio 0.25)
			(net 934 "Net-(D12-A)")
			(pintype "passive")
			(teardrops
				(best_length_ratio 0.2)
				(max_length 1)
				(best_width_ratio 0.9)
				(max_width 2)
				(curved_edges yes)
				(filter_ratio 0.9)
				(enabled yes)
				(allow_two_segments yes)
				(prefer_zone_connections yes)
			)
		)
		(pad "2" smd roundrect
			(at 0.48 0 270)
			(size 0.59 0.64)
			(layers "B.Cu" "B.Mask" "B.Paste")
			(roundrect_rratio 0.25)
			(net 57 "/USB-C console/FTDI_VCCIO")
			(pintype "passive")
			(teardrops
				(best_length_ratio 0.2)
				(max_length 1)
				(best_width_ratio 0.9)
				(max_width 2)
				(curved_edges yes)
				(filter_ratio 0.9)
				(enabled yes)
				(allow_two_segments yes)
				(prefer_zone_connections yes)
			)
		)
	)
	(footprint "antmicro-footprints:R_0402_1005Metric"
		(layer "B.Cu")
		(at 121.7 160.56 180)
		(descr "Resistor SMD 0402")
		(tags "resistor SMD 0402")
		(property "Reference" "R77"
			(at -1 0.5 0)
			(layer "B.SilkS")
			(effects
				(font
					(size 0.7 0.7)
					(thickness 0.15)
				)
				(justify left bottom mirror)
			)
		)
		(property "Value" "R_0R_0402"
			(at -1.011843 -1.772047 0)
			(layer "B.Fab")
			(effects
				(font
					(size 0.7 0.7)
					(thickness 0.15)
				)
				(justify left bottom mirror)
			)
		)
		(property "Datasheet" "https://industrial.panasonic.com/cdbs/www-data/pdf/RDA0000/AOA0000C301.pdf"
			(at 0 0 180)
			(layer "F.Fab")
			(hide yes)
			(effects
				(font
					(size 1.27 1.27)
					(thickness 0.15)
				)
			)
		)
		(property "Author" "Antmicro"
			(at 243.4 321.12 0)
			(layer "B.Fab")
			(hide yes)
			(effects
				(font
					(size 1 1)
					(thickness 0.15)
				)
				(justify mirror)
			)
		)
		(property "Current" "1A"
			(at 243.4 321.12 0)
			(layer "B.Fab")
			(hide yes)
			(effects
				(font
					(size 1 1)
					(thickness 0.15)
				)
				(justify mirror)
			)
		)
		(property "License" "Apache-2.0"
			(at 243.4 321.12 0)
			(layer "B.Fab")
			(hide yes)
			(effects
				(font
					(size 1 1)
					(thickness 0.15)
				)
				(justify mirror)
			)
		)
		(property "MPN" "ERJ2GE0R00X"
			(at 243.4 321.12 0)
			(layer "B.Fab")
			(hide yes)
			(effects
				(font
					(size 1 1)
					(thickness 0.15)
				)
				(justify mirror)
			)
		)
		(property "Manufacturer" "Panasonic"
			(at 243.4 321.12 0)
			(layer "B.Fab")
			(hide yes)
			(effects
				(font
					(size 1 1)
					(thickness 0.15)
				)
				(justify mirror)
			)
		)
		(property "Public" "False"
			(at 243.4 321.12 0)
			(layer "B.Fab")
			(hide yes)
			(effects
				(font
					(size 1 1)
					(thickness 0.15)
				)
				(justify mirror)
			)
		)
		(property "Tolerance" ""
			(at 243.4 321.12 0)
			(layer "B.Fab")
			(hide yes)
			(effects
				(font
					(size 1 1)
					(thickness 0.15)
				)
				(justify mirror)
			)
		)
		(property "Val" "0R"
			(at 243.4 321.12 0)
			(layer "B.Fab")
			(hide yes)
			(effects
				(font
					(size 1 1)
					(thickness 0.15)
				)
				(justify mirror)
			)
		)
		(sheetname "OCuLink")
		(sheetfile "oculink.kicad_sch")
		(attr smd)
		(fp_rect
			(start -0.925 0.47)
			(end 0.925 -0.47)
			(stroke
				(width 0.05)
				(type default)
			)
			(fill no)
			(layer "B.CrtYd")
		)
		(fp_rect
			(start -0.5 0.25)
			(end 0.5 -0.25)
			(stroke
				(width 0.15)
				(type solid)
			)
			(fill no)
			(layer "B.Fab")
		)
		(pad "1" smd roundrect
			(at -0.48 0 180)
			(size 0.59 0.64)
			(layers "B.Cu" "B.Mask" "B.Paste")
			(roundrect_rratio 0.25)
			(net 945 "/GPIO expander/GPIOEX5")
			(pintype "passive")
			(teardrops
				(best_length_ratio 0.2)
				(max_length 1)
				(best_width_ratio 0.9)
				(max_width 2)
				(curved_edges yes)
				(filter_ratio 0.9)
				(enabled yes)
				(allow_two_segments yes)
				(prefer_zone_connections yes)
			)
		)
		(pad "2" smd roundrect
			(at 0.48 0 180)
			(size 0.59 0.64)
			(layers "B.Cu" "B.Mask" "B.Paste")
			(roundrect_rratio 0.25)
			(net 201 "/OCuLink/~{CPRSNT_D0}")
			(pintype "passive")
			(teardrops
				(best_length_ratio 0.2)
				(max_length 1)
				(best_width_ratio 0.9)
				(max_width 2)
				(curved_edges yes)
				(filter_ratio 0.9)
				(enabled yes)
				(allow_two_segments yes)
				(prefer_zone_connections yes)
			)
		)
	)
	(footprint "antmicro-footprints:WQFN-42-1EP_3.5x9mm_P0.5mm"
		(layer "B.Cu")
		(at 193.591857 135.943686 -45)
		(descr "WQFN, 42 Pin (http://www.ti.com/lit/ds/symlink/ts3l501e.pdf#page=23), generated with kicad-footprint-generator ipc_noLead_generator.py")
		(tags "WQFN NoLead")
		(property "Reference" "U40"
			(at -0.166554 5.195942 135)
			(layer "B.SilkS")
			(effects
				(font
					(size 0.7 0.7)
					(thickness 0.15)
				)
				(justify left top mirror)
			)
		)
		(property "Value" "PI3EQX16904GL"
			(at 0 -5.819999 135)
			(layer "B.Fab")
			(effects
				(font
					(size 0.7 0.7)
					(thickness 0.15)
				)
				(justify left top mirror)
			)
		)
		(property "Datasheet" "https://www.diodes.com/part/view/PI3EQX16904GL"
			(at 0 0 135)
			(layer "B.Fab")
			(hide yes)
			(effects
				(font
					(size 1.27 1.27)
					(thickness 0.15)
				)
				(justify mirror)
			)
		)
		(property "Author" "Antmicro"
			(at 53.727 -324.573 45)
			(layer "B.Fab")
			(hide yes)
			(effects
				(font
					(size 1 1)
					(thickness 0.15)
				)
				(justify mirror)
			)
		)
		(property "License" "Apache-2.0"
			(at 53.727 -324.573 45)
			(layer "B.Fab")
			(hide yes)
			(effects
				(font
					(size 1 1)
					(thickness 0.15)
				)
				(justify mirror)
			)
		)
		(property "MPN" "PI3EQX16904GLZHEX"
			(at 53.727 -324.573 45)
			(layer "B.Fab")
			(hide yes)
			(effects
				(font
					(size 1 1)
					(thickness 0.15)
				)
				(justify mirror)
			)
		)
		(property "Manufacturer" "Diodes Incorporated"
			(at 53.727 -324.573 45)
			(layer "B.Fab")
			(hide yes)
			(effects
				(font
					(size 1 1)
					(thickness 0.15)
				)
				(justify mirror)
			)
		)
		(sheetname "PCIe redriver")
		(sheetfile "pcie_redriver.kicad_sch")
		(attr smd)
		(fp_line
			(start -1.861 4.611)
			(end -1.135 4.611)
			(stroke
				(width 0.15)
				(type solid)
			)
			(layer "B.SilkS")
		)
		(fp_line
			(start 1.86 4.611)
			(end 1.134 4.610999)
			(stroke
				(width 0.15)
				(type solid)
			)
			(layer "B.SilkS")
		)
		(fp_line
			(start 1.86 4.385)
			(end 1.86 4.611)
			(stroke
				(width 0.15)
				(type solid)
			)
			(layer "B.SilkS")
		)
		(fp_line
			(start -1.861 -4.384)
			(end -1.861 -4.61)
			(stroke
				(width 0.15)
				(type solid)
			)
			(layer "B.SilkS")
		)
		(fp_line
			(start -1.861 -4.61)
			(end -1.135 -4.61)
			(stroke
				(width 0.15)
				(type solid)
			)
			(layer "B.SilkS")
		)
		(fp_line
			(start 1.86 -4.384001)
			(end 1.86 -4.61)
			(stroke
				(width 0.15)
				(type solid)
			)
			(layer "B.SilkS")
		)
		(fp_line
			(start 1.86 -4.61)
			(end 1.134 -4.61)
			(stroke
				(width 0.15)
				(type solid)
			)
			(layer "B.SilkS")
		)
		(fp_circle
			(center -2.68 4)
			(end -2.63 4)
			(stroke
				(width 0.15)
				(type solid)
			)
			(fill yes)
			(layer "B.SilkS")
		)
		(fp_poly
			(pts
				(xy -2.25 5) (xy 2.249 5) (xy 2.249 -4.998) (xy -2.25 -4.998)
			)
			(stroke
				(width 0.05)
				(type solid)
			)
			(fill no)
			(layer "B.CrtYd")
		)
		(fp_line
			(start -1.75 3.625)
			(end -1.75 -4.498)
			(stroke
				(width 0.15)
				(type solid)
			)
			(layer "B.Fab")
		)
		(fp_line
			(start -0.875 4.5)
			(end -1.75 3.625)
			(stroke
				(width 0.15)
				(type solid)
			)
			(layer "B.Fab")
		)
		(fp_line
			(start 1.749 4.5)
			(end -0.875 4.5)
			(stroke
				(width 0.15)
				(type solid)
			)
			(layer "B.Fab")
		)
		(fp_line
			(start -1.75 -4.498)
			(end 1.749 -4.498)
			(stroke
				(width 0.15)
				(type solid)
			)
			(layer "B.Fab")
		)
		(fp_line
			(start 1.749 -4.498)
			(end 1.749 4.5)
			(stroke
				(width 0.15)
				(type solid)
			)
			(layer "B.Fab")
		)
		(pad "" smd roundrect
			(at -0.51 -2.16 315)
			(size 0.83 0.87)
			(layers "B.Paste")
			(roundrect_rratio 0.25)
			(teardrops
				(best_length_ratio 0.2)
				(max_length 1)
				(best_width_ratio 0.9)
				(max_width 2)
				(curved_edges yes)
				(filter_ratio 0.9)
				(enabled yes)
				(allow_two_segments yes)
				(prefer_zone_connections yes)
			)
		)
		(pad "" smd roundrect
			(at -0.51 -1.08 315)
			(size 0.83 0.87)
			(layers "B.Paste")
			(roundrect_rratio 0.25)
			(teardrops
				(best_length_ratio 0.2)
				(max_length 1)
				(best_width_ratio 0.9)
				(max_width 2)
				(curved_edges yes)
				(filter_ratio 0.9)
				(enabled yes)
				(allow_two_segments yes)
				(prefer_zone_connections yes)
			)
		)
		(pad "" smd roundrect
			(at -0.51 1.081 315)
			(size 0.83 0.87)
			(layers "B.Paste")
			(roundrect_rratio 0.25)
			(teardrops
				(best_length_ratio 0.2)
				(max_length 1)
				(best_width_ratio 0.9)
				(max_width 2)
				(curved_edges yes)
				(filter_ratio 0.9)
				(enabled yes)
				(allow_two_segments yes)
				(prefer_zone_connections yes)
			)
		)
		(pad "" smd roundrect
			(at -0.51 2.161 315)
			(size 0.83 0.87)
			(layers "B.Paste")
			(roundrect_rratio 0.25)
			(teardrops
				(best_length_ratio 0.2)
				(max_length 1)
				(best_width_ratio 0.9)
				(max_width 2)
				(curved_edges yes)
				(filter_ratio 0.9)
				(enabled yes)
				(allow_two_segments yes)
				(prefer_zone_connections yes)
			)
		)
		(pad "" smd roundrect
			(at -0.51 3.242 315)
			(size 0.83 0.87)
			(layers "B.Paste")
			(roundrect_rratio 0.25)
			(teardrops
				(best_length_ratio 0.2)
				(max_length 1)
				(best_width_ratio 0.9)
				(max_width 2)
				(curved_edges yes)
				(filter_ratio 0.9)
				(enabled yes)
				(allow_two_segments yes)
				(prefer_zone_connections yes)
			)
		)
		(pad "" smd roundrect
			(at -0.509999 -3.24 315)
			(size 0.83 0.87)
			(layers "B.Paste")
			(roundrect_rratio 0.25)
			(teardrops
				(best_length_ratio 0.2)
				(max_length 1)
				(best_width_ratio 0.9)
				(max_width 2)
				(curved_edges yes)
				(filter_ratio 0.9)
				(enabled yes)
				(allow_two_segments yes)
				(prefer_zone_connections yes)
			)
		)
		(pad "" smd roundrect
			(at -0.509999 0 315)
			(size 0.83 0.87)
			(layers "B.Paste")
			(roundrect_rratio 0.25)
			(teardrops
				(best_length_ratio 0.2)
				(max_length 1)
				(best_width_ratio 0.9)
				(max_width 2)
				(curved_edges yes)
				(filter_ratio 0.9)
				(enabled yes)
				(allow_two_segments yes)
				(prefer_zone_connections yes)
			)
		)
		(pad "" smd roundrect
			(at 0.508 -3.24 315)
			(size 0.83 0.87)
			(layers "B.Paste")
			(roundrect_rratio 0.25)
			(teardrops
				(best_length_ratio 0.2)
				(max_length 1)
				(best_width_ratio 0.9)
				(max_width 2)
				(curved_edges yes)
				(filter_ratio 0.9)
				(enabled yes)
				(allow_two_segments yes)
				(prefer_zone_connections yes)
			)
		)
		(pad "" smd roundrect
			(at 0.508 -2.16 315)
			(size 0.83 0.87)
			(layers "B.Paste")
			(roundrect_rratio 0.25)
			(teardrops
				(best_length_ratio 0.2)
				(max_length 1)
				(best_width_ratio 0.9)
				(max_width 2)
				(curved_edges yes)
				(filter_ratio 0.9)
				(enabled yes)
				(allow_two_segments yes)
				(prefer_zone_connections yes)
			)
		)
		(pad "" smd roundrect
			(at 0.508 -1.08 315)
			(size 0.83 0.87)
			(layers "B.Paste")
			(roundrect_rratio 0.25)
			(teardrops
				(best_length_ratio 0.2)
				(max_length 1)
				(best_width_ratio 0.9)
				(max_width 2)
				(curved_edges yes)
				(filter_ratio 0.9)
				(enabled yes)
				(allow_two_segments yes)
				(prefer_zone_connections yes)
			)
		)
		(pad "" smd roundrect
			(at 0.508 0 315)
			(size 0.83 0.87)
			(layers "B.Paste")
			(roundrect_rratio 0.25)
			(teardrops
				(best_length_ratio 0.2)
				(max_length 1)
				(best_width_ratio 0.9)
				(max_width 2)
				(curved_edges yes)
				(filter_ratio 0.9)
				(enabled yes)
				(allow_two_segments yes)
				(prefer_zone_connections yes)
			)
		)
		(pad "" smd roundrect
			(at 0.508 1.081 315)
			(size 0.83 0.87)
			(layers "B.Paste")
			(roundrect_rratio 0.25)
			(teardrops
				(best_length_ratio 0.2)
				(max_length 1)
				(best_width_ratio 0.9)
				(max_width 2)
				(curved_edges yes)
				(filter_ratio 0.9)
				(enabled yes)
				(allow_two_segments yes)
				(prefer_zone_connections yes)
			)
		)
		(pad "" smd roundrect
			(at 0.508 2.161 315)
			(size 0.83 0.87)
			(layers "B.Paste")
			(roundrect_rratio 0.25)
			(teardrops
				(best_length_ratio 0.2)
				(max_length 1)
				(best_width_ratio 0.9)
				(max_width 2)
				(curved_edges yes)
				(filter_ratio 0.9)
				(enabled yes)
				(allow_two_segments yes)
				(prefer_zone_connections yes)
			)
		)
		(pad "" smd roundrect
			(at 0.508 3.242 315)
			(size 0.83 0.87)
			(layers "B.Paste")
			(roundrect_rratio 0.25)
			(teardrops
				(best_length_ratio 0.2)
				(max_length 1)
				(best_width_ratio 0.9)
				(max_width 2)
				(curved_edges yes)
				(filter_ratio 0.9)
				(enabled yes)
				(allow_two_segments yes)
				(prefer_zone_connections yes)
			)
		)
		(pad "1" smd roundrect
			(at -1.688 4 315)
			(size 0.875 0.25)
			(layers "B.Cu" "B.Mask" "B.Paste")
			(roundrect_rratio 0.25)
			(net 976 "/PCIe redriver/RX_EQ2")
			(pinfunction "EQ2")
			(pintype "passive")
			(teardrops
				(best_length_ratio 0.2)
				(max_length 1)
				(best_width_ratio 0.9)
				(max_width 2)
				(curved_edges yes)
				(filter_ratio 0.9)
				(enabled yes)
				(allow_two_segments yes)
				(prefer_zone_connections yes)
			)
		)
		(pad "2" smd roundrect
			(at -1.688 3.5 315)
			(size 0.875 0.25)
			(layers "B.Cu" "B.Mask" "B.Paste")
			(roundrect_rratio 0.25)
			(net 973 "/PCIe redriver/RX_SW")
			(pinfunction "SW1")
			(pintype "input")
			(teardrops
				(best_length_ratio 0.2)
				(max_length 1)
				(best_width_ratio 0.9)
				(max_width 2)
				(curved_edges yes)
				(filter_ratio 0.9)
				(enabled yes)
				(allow_two_segments yes)
				(prefer_zone_connections yes)
			)
		)
		(pad "3" smd roundrect
			(at -1.688 3 315)
			(size 0.875 0.25)
			(layers "B.Cu" "B.Mask" "B.Paste")
			(roundrect_rratio 0.25)
			(net 2 "+3V3")
			(pinfunction "VCC")
			(pintype "passive")
			(teardrops
				(best_length_ratio 0.2)
				(max_length 1)
				(best_width_ratio 0.9)
				(max_width 2)
				(curved_edges yes)
				(filter_ratio 0.9)
				(enabled yes)
				(allow_two_segments yes)
				(prefer_zone_connections yes)
			)
		)
		(pad "4" smd roundrect
			(at -1.688 2.5 315)
			(size 0.875 0.25)
			(layers "B.Cu" "B.Mask" "B.Paste")
			(roundrect_rratio 0.25)
			(net 196 "/OCuLink/PCIe_{x4}.RX3+")
			(pinfunction "A0RX+")
			(pintype "input")
			(teardrops
				(best_length_ratio 0.2)
				(max_length 1)
				(best_width_ratio 0.9)
				(max_width 2)
				(curved_edges yes)
				(filter_ratio 0.9)
				(enabled yes)
				(allow_two_segments yes)
				(prefer_zone_connections yes)
			)
		)
		(pad "5" smd roundrect
			(at -1.688 2 315)
			(size 0.875 0.25)
			(layers "B.Cu" "B.Mask" "B.Paste")
			(roundrect_rratio 0.25)
			(net 197 "/OCuLink/PCIe_{x4}.RX3-")
			(pinfunction "A0RX-")
			(pintype "input")
			(teardrops
				(best_length_ratio 0.2)
				(max_length 1)
				(best_width_ratio 0.9)
				(max_width 2)
				(curved_edges yes)
				(filter_ratio 0.9)
				(enabled yes)
				(allow_two_segments yes)
				(prefer_zone_connections yes)
			)
		)
		(pad "6" smd roundrect
			(at -1.688 1.5 315)
			(size 0.875 0.25)
			(layers "B.Cu" "B.Mask" "B.Paste")
			(roundrect_rratio 0.25)
			(net 2 "+3V3")
			(pinfunction "VCC")
			(pintype "passive")
			(teardrops
				(best_length_ratio 0.2)
				(max_length 1)
				(best_width_ratio 0.9)
				(max_width 2)
				(curved_edges yes)
				(filter_ratio 0.9)
				(enabled yes)
				(allow_two_segments yes)
				(prefer_zone_connections yes)
			)
		)
		(pad "7" smd roundrect
			(at -1.688 1 315)
			(size 0.875 0.25)
			(layers "B.Cu" "B.Mask" "B.Paste")
			(roundrect_rratio 0.25)
			(net 194 "/OCuLink/PCIe_{x4}.RX2+")
			(pinfunction "A1RX+")
			(pintype "input")
			(teardrops
				(best_length_ratio 0.2)
				(max_length 1)
				(best_width_ratio 0.9)
				(max_width 2)
				(curved_edges yes)
				(filter_ratio 0.9)
				(enabled yes)
				(allow_two_segments yes)
				(prefer_zone_connections yes)
			)
		)
		(pad "8" smd roundrect
			(at -1.688 0.5 315)
			(size 0.875 0.25)
			(layers "B.Cu" "B.Mask" "B.Paste")
			(roundrect_rratio 0.25)
			(net 195 "/OCuLink/PCIe_{x4}.RX2-")
			(pinfunction "A1RX-")
			(pintype "input")
			(teardrops
				(best_length_ratio 0.2)
				(max_length 1)
				(best_width_ratio 0.9)
				(max_width 2)
				(curved_edges yes)
				(filter_ratio 0.9)
				(enabled yes)
				(allow_two_segments yes)
				(prefer_zone_connections yes)
			)
		)
		(pad "9" smd roundrect
			(at -1.688 0 315)
			(size 0.875 0.25)
			(layers "B.Cu" "B.Mask" "B.Paste")
			(roundrect_rratio 0.25)
			(net 2 "+3V3")
			(pinfunction "VCC")
			(pintype "passive")
			(teardrops
				(best_length_ratio 0.2)
				(max_length 1)
				(best_width_ratio 0.9)
				(max_width 2)
				(curved_edges yes)
				(filter_ratio 0.9)
				(enabled yes)
				(allow_two_segments yes)
				(prefer_zone_connections yes)
			)
		)
		(pad "10" smd roundrect
			(at -1.688 -0.5 315)
			(size 0.875 0.25)
			(layers "B.Cu" "B.Mask" "B.Paste")
			(roundrect_rratio 0.25)
			(net 188 "/OCuLink/PCIe_{x4}.RX1+")
			(pinfunction "A2RX+")
			(pintype "input")
			(teardrops
				(best_length_ratio 0.2)
				(max_length 1)
				(best_width_ratio 0.9)
				(max_width 2)
				(curved_edges yes)
				(filter_ratio 0.9)
				(enabled yes)
				(allow_two_segments yes)
				(prefer_zone_connections yes)
			)
		)
		(pad "11" smd roundrect
			(at -1.688 -1 315)
			(size 0.875 0.25)
			(layers "B.Cu" "B.Mask" "B.Paste")
			(roundrect_rratio 0.25)
			(net 189 "/OCuLink/PCIe_{x4}.RX1-")
			(pinfunction "A2RX-")
			(pintype "input")
			(teardrops
				(best_length_ratio 0.2)
				(max_length 1)
				(best_width_ratio 0.9)
				(max_width 2)
				(curved_edges yes)
				(filter_ratio 0.9)
				(enabled yes)
				(allow_two_segments yes)
				(prefer_zone_connections yes)
			)
		)
		(pad "12" smd roundrect
			(at -1.688 -1.5 315)
			(size 0.875 0.25)
			(layers "B.Cu" "B.Mask" "B.Paste")
			(roundrect_rratio 0.25)
			(net 2 "+3V3")
			(pinfunction "VCC")
			(pintype "power_in")
			(teardrops
				(best_length_ratio 0.2)
				(max_length 1)
				(best_width_ratio 0.9)
				(max_width 2)
				(curved_edges yes)
				(filter_ratio 0.9)
				(enabled yes)
				(allow_two_segments yes)
				(prefer_zone_connections yes)
			)
		)
		(pad "13" smd roundrect
			(at -1.688 -2 315)
			(size 0.875 0.25)
			(layers "B.Cu" "B.Mask" "B.Paste")
			(roundrect_rratio 0.25)
			(net 186 "/OCuLink/PCIe_{x4}.RX0+")
			(pinfunction "A3RX+")
			(pintype "input")
			(teardrops
				(best_length_ratio 0.2)
				(max_length 1)
				(best_width_ratio 0.9)
				(max_width 2)
				(curved_edges yes)
				(filter_ratio 0.9)
				(enabled yes)
				(allow_two_segments yes)
				(prefer_zone_connections yes)
			)
		)
		(pad "14" smd roundrect
			(at -1.688 -2.5 315)
			(size 0.875 0.25)
			(layers "B.Cu" "B.Mask" "B.Paste")
			(roundrect_rratio 0.25)
			(net 187 "/OCuLink/PCIe_{x4}.RX0-")
			(pinfunction "A3RX-")
			(pintype "input")
			(teardrops
				(best_length_ratio 0.2)
				(max_length 1)
				(best_width_ratio 0.9)
				(max_width 2)
				(curved_edges yes)
				(filter_ratio 0.9)
				(enabled yes)
				(allow_two_segments yes)
				(prefer_zone_connections yes)
			)
		)
		(pad "15" smd roundrect
			(at -1.688 -3 315)
			(size 0.875 0.25)
			(layers "B.Cu" "B.Mask" "B.Paste")
			(roundrect_rratio 0.25)
			(net 2 "+3V3")
			(pinfunction "VCC")
			(pintype "passive")
			(teardrops
				(best_length_ratio 0.2)
				(max_length 1)
				(best_width_ratio 0.9)
				(max_width 2)
				(curved_edges yes)
				(filter_ratio 0.9)
				(enabled yes)
				(allow_two_segments yes)
				(prefer_zone_connections yes)
			)
		)
		(pad "16" smd roundrect
			(at -1.688 -3.5 315)
			(size 0.875 0.25)
			(layers "B.Cu" "B.Mask" "B.Paste")
			(roundrect_rratio 0.25)
			(net 719 "Net-(U40-~{I2C_{RESET}})")
			(pinfunction "~{I2C_{RESET}}")
			(pintype "input")
			(teardrops
				(best_length_ratio 0.2)
				(max_length 1)
				(best_width_ratio 0.9)
				(max_width 2)
				(curved_edges yes)
				(filter_ratio 0.9)
				(enabled yes)
				(allow_two_segments yes)
				(prefer_zone_connections yes)
			)
		)
		(pad "17" smd roundrect
			(at -1.688 -4 315)
			(size 0.875 0.25)
			(layers "B.Cu" "B.Mask" "B.Paste")
			(roundrect_rratio 0.25)
			(net 1 "GND")
			(pinfunction "AD1")
			(pintype "passive")
			(teardrops
				(best_length_ratio 0.2)
				(max_length 1)
				(best_width_ratio 0.9)
				(max_width 2)
				(curved_edges yes)
				(filter_ratio 0.9)
				(enabled yes)
				(allow_two_segments yes)
				(prefer_zone_connections yes)
			)
		)
		(pad "18" smd roundrect
			(at -0.75 -4.437 315)
			(size 0.25 0.875)
			(layers "B.Cu" "B.Mask" "B.Paste")
			(roundrect_rratio 0.25)
			(net 716 "Net-(U40-SDA)")
			(pinfunction "SDA")
			(pintype "open_collector")
			(teardrops
				(best_length_ratio 0.2)
				(max_length 1)
				(best_width_ratio 0.9)
				(max_width 2)
				(curved_edges yes)
				(filter_ratio 0.9)
				(enabled yes)
				(allow_two_segments yes)
				(prefer_zone_connections yes)
			)
		)
		(pad "19" smd roundrect
			(at -0.25 -4.437 315)
			(size 0.25 0.875)
			(layers "B.Cu" "B.Mask" "B.Paste")
			(roundrect_rratio 0.25)
			(net 717 "Net-(U40-SCL)")
			(pinfunction "SCL")
			(pintype "open_collector")
			(teardrops
				(best_length_ratio 0.2)
				(max_length 1)
				(best_width_ratio 0.9)
				(max_width 2)
				(curved_edges yes)
				(filter_ratio 0.9)
				(enabled yes)
				(allow_two_segments yes)
				(prefer_zone_connections yes)
			)
		)
		(pad "20" smd roundrect
			(at 0.25 -4.437 315)
			(size 0.25 0.875)
			(layers "B.Cu" "B.Mask" "B.Paste")
			(roundrect_rratio 0.25)
			(net 945 "/GPIO expander/GPIOEX5")
			(pinfunction "~{PRSNT}")
			(pintype "input")
			(teardrops
				(best_length_ratio 0.2)
				(max_length 1)
				(best_width_ratio 0.9)
				(max_width 2)
				(curved_edges yes)
				(filter_ratio 0.9)
				(enabled yes)
				(allow_two_segments yes)
				(prefer_zone_connections yes)
			)
		)
		(pad "21" smd roundrect
			(at 0.75 -4.437 315)
			(size 0.25 0.875)
			(layers "B.Cu" "B.Mask" "B.Paste")
			(roundrect_rratio 0.25)
			(net 632 "Net-(U40-EN_{I2C})")
			(pinfunction "EN_{I2C}")
			(pintype "input")
			(teardrops
				(best_length_ratio 0.2)
				(max_length 1)
				(best_width_ratio 0.9)
				(max_width 2)
				(curved_edges yes)
				(filter_ratio 0.9)
				(enabled yes)
				(allow_two_segments yes)
				(prefer_zone_connections yes)
			)
		)
		(pad "22" smd roundrect
			(at 1.687 -4 315)
			(size 0.875 0.25)
			(layers "B.Cu" "B.Mask" "B.Paste")
			(roundrect_rratio 0.25)
			(net 718 "Net-(U40-I2C_{DONE})")
			(pinfunction "I2C_{DONE}")
			(pintype "input")
			(teardrops
				(best_length_ratio 0.2)
				(max_length 1)
				(best_width_ratio 0.9)
				(max_width 2)
				(curved_edges yes)
				(filter_ratio 0.9)
				(enabled yes)
				(allow_two_segments yes)
				(prefer_zone_connections yes)
			)
		)
		(pad "23" smd roundrect
			(at 1.687 -3.5 315)
			(size 0.875 0.25)
			(layers "B.Cu" "B.Mask" "B.Paste")
			(roundrect_rratio 0.25)
			(net 630 "Net-(U40-RXDET)")
			(pinfunction "RXDET")
			(pintype "input")
			(teardrops
				(best_length_ratio 0.2)
				(max_length 1)
				(best_width_ratio 0.9)
				(max_width 2)
				(curved_edges yes)
				(filter_ratio 0.9)
				(enabled yes)
				(allow_two_segments yes)
				(prefer_zone_connections yes)
			)
		)
		(pad "24" smd roundrect
			(at 1.687 -3 315)
			(size 0.875 0.25)
			(layers "B.Cu" "B.Mask" "B.Paste")
			(roundrect_rratio 0.25)
			(net 2 "+3V3")
			(pinfunction "VCC")
			(pintype "passive")
			(teardrops
				(best_length_ratio 0.2)
				(max_length 1)
				(best_width_ratio 0.9)
				(max_width 2)
				(curved_edges yes)
				(filter_ratio 0.9)
				(enabled yes)
				(allow_two_segments yes)
				(prefer_zone_connections yes)
			)
		)
		(pad "25" smd roundrect
			(at 1.687 -2.5 315)
			(size 0.875 0.25)
			(layers "B.Cu" "B.Mask" "B.Paste")
			(roundrect_rratio 0.25)
			(net 101 "/PCIe redriver/PCIe_{I}_C.RX0-")
			(pinfunction "A3TX-")
			(pintype "output")
			(teardrops
				(best_length_ratio 0.2)
				(max_length 1)
				(best_width_ratio 0.9)
				(max_width 2)
				(curved_edges yes)
				(filter_ratio 0.9)
				(enabled yes)
				(allow_two_segments yes)
				(prefer_zone_connections yes)
			)
		)
		(pad "26" smd roundrect
			(at 1.687001 -2 315)
			(size 0.875 0.25)
			(layers "B.Cu" "B.Mask" "B.Paste")
			(roundrect_rratio 0.25)
			(net 957 "/PCIe redriver/PCIe_{I}_C.RX0+")
			(pinfunction "A3TX+")
			(pintype "input")
			(teardrops
				(best_length_ratio 0.2)
				(max_length 1)
				(best_width_ratio 0.9)
				(max_width 2)
				(curved_edges yes)
				(filter_ratio 0.9)
				(enabled yes)
				(allow_two_segments yes)
				(prefer_zone_connections yes)
			)
		)
		(pad "27" smd roundrect
			(at 1.687 -1.5 315)
			(size 0.875 0.25)
			(layers "B.Cu" "B.Mask" "B.Paste")
			(roundrect_rratio 0.25)
			(net 2 "+3V3")
			(pinfunction "VCC")
			(pintype "passive")
			(teardrops
				(best_length_ratio 0.2)
				(max_length 1)
				(best_width_ratio 0.9)
				(max_width 2)
				(curved_edges yes)
				(filter_ratio 0.9)
				(enabled yes)
				(allow_two_segments yes)
				(prefer_zone_connections yes)
			)
		)
		(pad "28" smd roundrect
			(at 1.687 -1 315)
			(size 0.875 0.25)
			(layers "B.Cu" "B.Mask" "B.Paste")
			(roundrect_rratio 0.25)
			(net 103 "/PCIe redriver/PCIe_{I}_C.RX1-")
			(pinfunction "A2TX-")
			(pintype "output")
			(teardrops
				(best_length_ratio 0.2)
				(max_length 1)
				(best_width_ratio 0.9)
				(max_width 2)
				(curved_edges yes)
				(filter_ratio 0.9)
				(enabled yes)
				(allow_two_segments yes)
				(prefer_zone_connections yes)
			)
		)
		(pad "29" smd roundrect
			(at 1.687001 -0.5 315)
			(size 0.875 0.25)
			(layers "B.Cu" "B.Mask" "B.Paste")
			(roundrect_rratio 0.25)
			(net 958 "/PCIe redriver/PCIe_{I}_C.RX1+")
			(pinfunction "A2TX+")
			(pintype "input")
			(teardrops
				(best_length_ratio 0.2)
				(max_length 1)
				(best_width_ratio 0.9)
				(max_width 2)
				(curved_edges yes)
				(filter_ratio 0.9)
				(enabled yes)
				(allow_two_segments yes)
				(prefer_zone_connections yes)
			)
		)
		(pad "30" smd roundrect
			(at 1.687 0 315)
			(size 0.875 0.25)
			(layers "B.Cu" "B.Mask" "B.Paste")
			(roundrect_rratio 0.25)
			(net 2 "+3V3")
			(pinfunction "VCC")
			(pintype "passive")
			(teardrops
				(best_length_ratio 0.2)
				(max_length 1)
				(best_width_ratio 0.9)
				(max_width 2)
				(curved_edges yes)
				(filter_ratio 0.9)
				(enabled yes)
				(allow_two_segments yes)
				(prefer_zone_connections yes)
			)
		)
		(pad "31" smd roundrect
			(at 1.687001 0.5 315)
			(size 0.875 0.25)
			(layers "B.Cu" "B.Mask" "B.Paste")
			(roundrect_rratio 0.25)
			(net 105 "/PCIe redriver/PCIe_{I}_C.RX2-")
			(pinfunction "A1TX-")
			(pintype "output")
			(teardrops
				(best_length_ratio 0.2)
				(max_length 1)
				(best_width_ratio 0.9)
				(max_width 2)
				(curved_edges yes)
				(filter_ratio 0.9)
				(enabled yes)
				(allow_two_segments yes)
				(prefer_zone_connections yes)
			)
		)
		(pad "32" smd roundrect
			(at 1.687 1 315)
			(size 0.875 0.25)
			(layers "B.Cu" "B.Mask" "B.Paste")
			(roundrect_rratio 0.25)
			(net 959 "/PCIe redriver/PCIe_{I}_C.RX2+")
			(pinfunction "A1TX+")
			(pintype "input")
			(teardrops
				(best_length_ratio 0.2)
				(max_length 1)
				(best_width_ratio 0.9)
				(max_width 2)
				(curved_edges yes)
				(filter_ratio 0.9)
				(enabled yes)
				(allow_two_segments yes)
				(prefer_zone_connections yes)
			)
		)
		(pad "33" smd roundrect
			(at 1.687 1.5 315)
			(size 0.875 0.25)
			(layers "B.Cu" "B.Mask" "B.Paste")
			(roundrect_rratio 0.25)
			(net 2 "+3V3")
			(pinfunction "VCC")
			(pintype "passive")
			(teardrops
				(best_length_ratio 0.2)
				(max_length 1)
				(best_width_ratio 0.9)
				(max_width 2)
				(curved_edges yes)
				(filter_ratio 0.9)
				(enabled yes)
				(allow_two_segments yes)
				(prefer_zone_connections yes)
			)
		)
		(pad "34" smd roundrect
			(at 1.687001 2 315)
			(size 0.875 0.25)
			(layers "B.Cu" "B.Mask" "B.Paste")
			(roundrect_rratio 0.25)
			(net 956 "/PCIe redriver/PCIe_{I}_C.RX3-")
			(pinfunction "A0TX-")
			(pintype "output")
			(teardrops
				(best_length_ratio 0.2)
				(max_length 1)
				(best_width_ratio 0.9)
				(max_width 2)
				(curved_edges yes)
				(filter_ratio 0.9)
				(enabled yes)
				(allow_two_segments yes)
				(prefer_zone_connections yes)
			)
		)
		(pad "35" smd roundrect
			(at 1.687 2.5 315)
			(size 0.875 0.25)
			(layers "B.Cu" "B.Mask" "B.Paste")
			(roundrect_rratio 0.25)
			(net 960 "/PCIe redriver/PCIe_{I}_C.RX3+")
			(pinfunction "A0TX+")
			(pintype "input")
			(teardrops
				(best_length_ratio 0.2)
				(max_length 1)
				(best_width_ratio 0.9)
				(max_width 2)
				(curved_edges yes)
				(filter_ratio 0.9)
				(enabled yes)
				(allow_two_segments yes)
				(prefer_zone_connections yes)
			)
		)
		(pad "36" smd roundrect
			(at 1.687 3 315)
			(size 0.875 0.25)
			(layers "B.Cu" "B.Mask" "B.Paste")
			(roundrect_rratio 0.25)
			(net 2 "+3V3")
			(pinfunction "VCC")
			(pintype "passive")
			(teardrops
				(best_length_ratio 0.2)
				(max_length 1)
				(best_width_ratio 0.9)
				(max_width 2)
				(curved_edges yes)
				(filter_ratio 0.9)
				(enabled yes)
				(allow_two_segments yes)
				(prefer_zone_connections yes)
			)
		)
		(pad "37" smd roundrect
			(at 1.687 3.5 315)
			(size 0.875 0.25)
			(layers "B.Cu" "B.Mask" "B.Paste")
			(roundrect_rratio 0.25)
			(net 975 "/PCIe redriver/RX_FG0")
			(pinfunction "FG0")
			(pintype "passive")
			(teardrops
				(best_length_ratio 0.2)
				(max_length 1)
				(best_width_ratio 0.9)
				(max_width 2)
				(curved_edges yes)
				(filter_ratio 0.9)
				(enabled yes)
				(allow_two_segments yes)
				(prefer_zone_connections yes)
			)
		)
		(pad "38" smd roundrect
			(at 1.687 4 315)
			(size 0.875 0.25)
			(layers "B.Cu" "B.Mask" "B.Paste")
			(roundrect_rratio 0.25)
			(net 974 "/PCIe redriver/RX_FG1")
			(pinfunction "FG1")
			(pintype "passive")
			(teardrops
				(best_length_ratio 0.2)
				(max_length 1)
				(best_width_ratio 0.9)
				(max_width 2)
				(curved_edges yes)
				(filter_ratio 0.9)
				(enabled yes)
				(allow_two_segments yes)
				(prefer_zone_connections yes)
			)
		)
		(pad "39" smd roundrect
			(at 0.75 4.438 315)
			(size 0.25 0.875)
			(layers "B.Cu" "B.Mask" "B.Paste")
			(roundrect_rratio 0.25)
			(net 978 "/PCIe redriver/RX_EQ0")
			(pinfunction "EQ0")
			(pintype "passive")
			(teardrops
				(best_length_ratio 0.2)
				(max_length 1)
				(best_width_ratio 0.9)
				(max_width 2)
				(curved_edges yes)
				(filter_ratio 0.9)
				(enabled yes)
				(allow_two_segments yes)
				(prefer_zone_connections yes)
			)
		)
		(pad "40" smd roundrect
			(at 0.25 4.438 315)
			(size 0.25 0.875)
			(layers "B.Cu" "B.Mask" "B.Paste")
			(roundrect_rratio 0.25)
			(net 977 "/PCIe redriver/RX_EQ1")
			(pinfunction "EQ1")
			(pintype "passive")
			(teardrops
				(best_length_ratio 0.2)
				(max_length 1)
				(best_width_ratio 0.9)
				(max_width 2)
				(curved_edges yes)
				(filter_ratio 0.9)
				(enabled yes)
				(allow_two_segments yes)
				(prefer_zone_connections yes)
			)
		)
		(pad "41" smd roundrect
			(at -0.25 4.438 315)
			(size 0.25 0.875)
			(layers "B.Cu" "B.Mask" "B.Paste")
			(roundrect_rratio 0.25)
			(net 1 "GND")
			(pinfunction "AD2")
			(pintype "passive")
			(teardrops
				(best_length_ratio 0.2)
				(max_length 1)
				(best_width_ratio 0.9)
				(max_width 2)
				(curved_edges yes)
				(filter_ratio 0.9)
				(enabled yes)
				(allow_two_segments yes)
				(prefer_zone_connections yes)
			)
		)
		(pad "42" smd roundrect
			(at -0.75 4.438 315)
			(size 0.25 0.875)
			(layers "B.Cu" "B.Mask" "B.Paste")
			(roundrect_rratio 0.25)
			(net 1 "GND")
			(pinfunction "AD3")
			(pintype "passive")
			(teardrops
				(best_length_ratio 0.2)
				(max_length 1)
				(best_width_ratio 0.9)
				(max_width 2)
				(curved_edges yes)
				(filter_ratio 0.9)
				(enabled yes)
				(allow_two_segments yes)
				(prefer_zone_connections yes)
			)
		)
		(pad "43" smd rect
			(at 0 0 315)
			(size 2.05 7.55)
			(layers "B.Cu" "B.Mask")
			(net 1 "GND")
			(pinfunction "GND")
			(pintype "power_in")
			(teardrops
				(best_length_ratio 0.2)
				(max_length 1)
				(best_width_ratio 0.9)
				(max_width 2)
				(curved_edges yes)
				(filter_ratio 0.9)
				(enabled no)
				(allow_two_segments yes)
				(prefer_zone_connections yes)
			)
		)
	)
	(footprint "antmicro-footprints:TP_SMD_0.75mm"
		(layer "B.Cu")
		(at 177.35 163.8)
		(property "Reference" "TP22"
			(at -0.35 -2.3 270)
			(layer "B.SilkS")
			(effects
				(font
					(size 0.7 0.7)
					(thickness 0.15)
				)
				(justify right top mirror)
			)
		)
		(property "Value" "TP_0.75mm_SMD"
			(at 3.225 -53.865 0)
			(layer "B.Fab")
			(hide yes)
			(effects
				(font
					(size 0.7 0.7)
					(thickness 0.15)
				)
				(justify right top mirror)
			)
		)
		(property "Author" "Antmicro"
			(at 454.8 308.02 0)
			(layer "B.Fab")
			(hide yes)
			(effects
				(font
					(size 1 1)
					(thickness 0.15)
				)
				(justify mirror)
			)
		)
		(property "License" "Apache-2.0"
			(at 454.8 308.02 0)
			(layer "B.Fab")
			(hide yes)
			(effects
				(font
					(size 1 1)
					(thickness 0.15)
				)
				(justify mirror)
			)
		)
		(property "MPN" ""
			(at 454.8 308.02 0)
			(layer "B.Fab")
			(hide yes)
			(effects
				(font
					(size 1 1)
					(thickness 0.15)
				)
				(justify mirror)
			)
		)
		(property "Manufacturer" ""
			(at 454.8 308.02 0)
			(layer "B.Fab")
			(hide yes)
			(effects
				(font
					(size 1 1)
					(thickness 0.15)
				)
				(justify mirror)
			)
		)
		(property "Public" "False"
			(at 454.8 308.02 0)
			(layer "B.Fab")
			(hide yes)
			(effects
				(font
					(size 1 1)
					(thickness 0.15)
				)
				(justify mirror)
			)
		)
		(sheetname "Com Express 7 MGMT")
		(sheetfile "com_express_7_mgmt.kicad_sch")
		(attr exclude_from_pos_files exclude_from_bom)
		(fp_circle
			(center 0 0)
			(end 0.475 0)
			(stroke
				(width 0.05)
				(type default)
			)
			(fill no)
			(layer "B.CrtYd")
		)
		(pad "1" smd circle
			(at 0 0)
			(size 0.75 0.75)
			(layers "B.Cu" "B.Mask")
			(net 352 "Net-(J12D-LPC_AD3{slash}ESPI_IO_3)")
			(pinfunction "1")
			(pintype "passive")
			(teardrops
				(best_length_ratio 0.4)
				(max_length 1)
				(best_width_ratio 0.9)
				(max_width 2)
				(curved_edges yes)
				(filter_ratio 0.9)
				(enabled yes)
				(allow_two_segments yes)
				(prefer_zone_connections yes)
			)
		)
	)
	(footprint "antmicro-footprints:R_0402_1005Metric"
		(layer "B.Cu")
		(at 126.09 138.06)
		(descr "Resistor SMD 0402")
		(tags "resistor SMD 0402")
		(property "Reference" "R297"
			(at -3.64 1.25 0)
			(layer "B.SilkS")
			(effects
				(font
					(size 0.7 0.7)
					(thickness 0.15)
				)
				(justify right bottom mirror)
			)
		)
		(property "Value" "R_10k_0402"
			(at -1.011843 -1.772047 0)
			(layer "B.Fab")
			(effects
				(font
					(size 0.7 0.7)
					(thickness 0.15)
				)
				(justify right bottom mirror)
			)
		)
		(property "Datasheet" "https://www.bourns.com/docs/product-datasheets/cr.pdf"
			(at 0 0 0)
			(layer "F.Fab")
			(hide yes)
			(effects
				(font
					(size 1.27 1.27)
					(thickness 0.15)
				)
			)
		)
		(property "Author" "Antmicro"
			(at 0 0 0)
			(layer "B.Fab")
			(hide yes)
			(effects
				(font
					(size 1 1)
					(thickness 0.15)
				)
				(justify mirror)
			)
		)
		(property "License" "Apache-2.0"
			(at 0 0 0)
			(layer "B.Fab")
			(hide yes)
			(effects
				(font
					(size 1 1)
					(thickness 0.15)
				)
				(justify mirror)
			)
		)
		(property "MPN" "CR0402-FX-1002GLF"
			(at 0 0 0)
			(layer "B.Fab")
			(hide yes)
			(effects
				(font
					(size 1 1)
					(thickness 0.15)
				)
				(justify mirror)
			)
		)
		(property "Manufacturer" "Bourns"
			(at 0 0 0)
			(layer "B.Fab")
			(hide yes)
			(effects
				(font
					(size 1 1)
					(thickness 0.15)
				)
				(justify mirror)
			)
		)
		(property "Public" "False"
			(at 0 0 0)
			(layer "B.Fab")
			(hide yes)
			(effects
				(font
					(size 1 1)
					(thickness 0.15)
				)
				(justify mirror)
			)
		)
		(property "Tolerance" "1%"
			(at 0 0 0)
			(layer "B.Fab")
			(hide yes)
			(effects
				(font
					(size 1 1)
					(thickness 0.15)
				)
				(justify mirror)
			)
		)
		(property "Val" "10k"
			(at 0 0 0)
			(layer "B.Fab")
			(hide yes)
			(effects
				(font
					(size 1 1)
					(thickness 0.15)
				)
				(justify mirror)
			)
		)
		(sheetname "KR to SFI #2")
		(sheetfile "kr_sfi.kicad_sch")
		(attr smd)
		(fp_rect
			(start -0.925 0.47)
			(end 0.925 -0.47)
			(stroke
				(width 0.05)
				(type default)
			)
			(fill no)
			(layer "B.CrtYd")
		)
		(fp_rect
			(start -0.5 0.25)
			(end 0.5 -0.25)
			(stroke
				(width 0.15)
				(type solid)
			)
			(fill no)
			(layer "B.Fab")
		)
		(pad "1" smd roundrect
			(at -0.48 0)
			(size 0.59 0.64)
			(layers "B.Cu" "B.Mask" "B.Paste")
			(roundrect_rratio 0.25)
			(net 1 "GND")
			(pintype "passive")
			(teardrops
				(best_length_ratio 0.2)
				(max_length 1)
				(best_width_ratio 0.9)
				(max_width 2)
				(curved_edges yes)
				(filter_ratio 0.9)
				(enabled yes)
				(allow_two_segments yes)
				(prefer_zone_connections yes)
			)
		)
		(pad "2" smd roundrect
			(at 0.48 0)
			(size 0.59 0.64)
			(layers "B.Cu" "B.Mask" "B.Paste")
			(roundrect_rratio 0.25)
			(net 677 "Net-(U45C-PRTAD1)")
			(pintype "passive")
			(teardrops
				(best_length_ratio 0.2)
				(max_length 1)
				(best_width_ratio 0.9)
				(max_width 2)
				(curved_edges yes)
				(filter_ratio 0.9)
				(enabled yes)
				(allow_two_segments yes)
				(prefer_zone_connections yes)
			)
		)
	)
	(footprint "antmicro-footprints:R_0402_1005Metric"
		(layer "B.Cu")
		(at 307.464999 121.96 90)
		(descr "Resistor SMD 0402")
		(tags "resistor SMD 0402")
		(property "Reference" "R93"
			(at -2.95 0.485001 90)
			(layer "B.SilkS")
			(effects
				(font
					(size 0.7 0.7)
					(thickness 0.15)
				)
				(justify right bottom mirror)
			)
		)
		(property "Value" "R_0R_0402"
			(at -1.011843 -1.772047 90)
			(layer "B.Fab")
			(effects
				(font
					(size 0.7 0.7)
					(thickness 0.15)
				)
				(justify right bottom mirror)
			)
		)
		(property "Datasheet" "https://industrial.panasonic.com/cdbs/www-data/pdf/RDA0000/AOA0000C301.pdf"
			(at 0 0 90)
			(layer "F.Fab")
			(hide yes)
			(effects
				(font
					(size 1.27 1.27)
					(thickness 0.15)
				)
			)
		)
		(property "Author" "Antmicro"
			(at 429.424999 -185.504999 0)
			(layer "B.Fab")
			(hide yes)
			(effects
				(font
					(size 1 1)
					(thickness 0.15)
				)
				(justify mirror)
			)
		)
		(property "Current" "1A"
			(at 429.424999 -185.504999 0)
			(layer "B.Fab")
			(hide yes)
			(effects
				(font
					(size 1 1)
					(thickness 0.15)
				)
				(justify mirror)
			)
		)
		(property "License" "Apache-2.0"
			(at 429.424999 -185.504999 0)
			(layer "B.Fab")
			(hide yes)
			(effects
				(font
					(size 1 1)
					(thickness 0.15)
				)
				(justify mirror)
			)
		)
		(property "MPN" "ERJ2GE0R00X"
			(at 429.424999 -185.504999 0)
			(layer "B.Fab")
			(hide yes)
			(effects
				(font
					(size 1 1)
					(thickness 0.15)
				)
				(justify mirror)
			)
		)
		(property "Manufacturer" "Panasonic"
			(at 429.424999 -185.504999 0)
			(layer "B.Fab")
			(hide yes)
			(effects
				(font
					(size 1 1)
					(thickness 0.15)
				)
				(justify mirror)
			)
		)
		(property "Public" "False"
			(at 429.424999 -185.504999 0)
			(layer "B.Fab")
			(hide yes)
			(effects
				(font
					(size 1 1)
					(thickness 0.15)
				)
				(justify mirror)
			)
		)
		(property "Tolerance" ""
			(at 429.424999 -185.504999 0)
			(layer "B.Fab")
			(hide yes)
			(effects
				(font
					(size 1 1)
					(thickness 0.15)
				)
				(justify mirror)
			)
		)
		(property "Val" "0R"
			(at 429.424999 -185.504999 0)
			(layer "B.Fab")
			(hide yes)
			(effects
				(font
					(size 1 1)
					(thickness 0.15)
				)
				(justify mirror)
			)
		)
		(sheetname "Power")
		(sheetfile "power.kicad_sch")
		(attr smd)
		(fp_rect
			(start -0.925 0.47)
			(end 0.925 -0.47)
			(stroke
				(width 0.05)
				(type default)
			)
			(fill no)
			(layer "B.CrtYd")
		)
		(fp_rect
			(start -0.5 0.25)
			(end 0.5 -0.25)
			(stroke
				(width 0.15)
				(type solid)
			)
			(fill no)
			(layer "B.Fab")
		)
		(pad "1" smd roundrect
			(at -0.48 0 90)
			(size 0.59 0.64)
			(layers "B.Cu" "B.Mask" "B.Paste")
			(roundrect_rratio 0.25)
			(net 78 "+1V8")
			(pintype "passive")
			(teardrops
				(best_length_ratio 0.2)
				(max_length 1)
				(best_width_ratio 0.9)
				(max_width 2)
				(curved_edges yes)
				(filter_ratio 0.9)
				(enabled yes)
				(allow_two_segments yes)
				(prefer_zone_connections yes)
			)
		)
		(pad "2" smd roundrect
			(at 0.48 0 90)
			(size 0.59 0.64)
			(layers "B.Cu" "B.Mask" "B.Paste")
			(roundrect_rratio 0.25)
			(net 577 "Net-(U18-EN)")
			(pintype "passive")
			(teardrops
				(best_length_ratio 0.2)
				(max_length 1)
				(best_width_ratio 0.9)
				(max_width 2)
				(curved_edges yes)
				(filter_ratio 0.9)
				(enabled yes)
				(allow_two_segments yes)
				(prefer_zone_connections yes)
			)
		)
	)
	(footprint "antmicro-footprints:R_0402_1005Metric"
		(layer "B.Cu")
		(at 144.25 136.06 180)
		(descr "Resistor SMD 0402")
		(tags "resistor SMD 0402")
		(property "Reference" "R259"
			(at -1.3 1.45 0)
			(layer "B.SilkS")
			(effects
				(font
					(size 0.7 0.7)
					(thickness 0.15)
				)
				(justify left bottom mirror)
			)
		)
		(property "Value" "R_10k_0402"
			(at -1.011843 -1.772047 0)
			(layer "B.Fab")
			(effects
				(font
					(size 0.7 0.7)
					(thickness 0.15)
				)
				(justify left bottom mirror)
			)
		)
		(property "Datasheet" "https://www.bourns.com/docs/product-datasheets/cr.pdf"
			(at 0 0 180)
			(layer "F.Fab")
			(hide yes)
			(effects
				(font
					(size 1.27 1.27)
					(thickness 0.15)
				)
			)
		)
		(property "Author" "Antmicro"
			(at 288.5 272.12 0)
			(layer "B.Fab")
			(hide yes)
			(effects
				(font
					(size 1 1)
					(thickness 0.15)
				)
				(justify mirror)
			)
		)
		(property "License" "Apache-2.0"
			(at 288.5 272.12 0)
			(layer "B.Fab")
			(hide yes)
			(effects
				(font
					(size 1 1)
					(thickness 0.15)
				)
				(justify mirror)
			)
		)
		(property "MPN" "CR0402-FX-1002GLF"
			(at 288.5 272.12 0)
			(layer "B.Fab")
			(hide yes)
			(effects
				(font
					(size 1 1)
					(thickness 0.15)
				)
				(justify mirror)
			)
		)
		(property "Manufacturer" "Bourns"
			(at 288.5 272.12 0)
			(layer "B.Fab")
			(hide yes)
			(effects
				(font
					(size 1 1)
					(thickness 0.15)
				)
				(justify mirror)
			)
		)
		(property "Public" "False"
			(at 288.5 272.12 0)
			(layer "B.Fab")
			(hide yes)
			(effects
				(font
					(size 1 1)
					(thickness 0.15)
				)
				(justify mirror)
			)
		)
		(property "Tolerance" "1%"
			(at 288.5 272.12 0)
			(layer "B.Fab")
			(hide yes)
			(effects
				(font
					(size 1 1)
					(thickness 0.15)
				)
				(justify mirror)
			)
		)
		(property "Val" "10k"
			(at 288.5 272.12 0)
			(layer "B.Fab")
			(hide yes)
			(effects
				(font
					(size 1 1)
					(thickness 0.15)
				)
				(justify mirror)
			)
		)
		(sheetname "KR to SFI #1")
		(sheetfile "kr_sfi.kicad_sch")
		(attr smd)
		(fp_rect
			(start -0.925 0.47)
			(end 0.925 -0.47)
			(stroke
				(width 0.05)
				(type default)
			)
			(fill no)
			(layer "B.CrtYd")
		)
		(fp_rect
			(start -0.5 0.25)
			(end 0.5 -0.25)
			(stroke
				(width 0.15)
				(type solid)
			)
			(fill no)
			(layer "B.Fab")
		)
		(pad "1" smd roundrect
			(at -0.48 0 180)
			(size 0.59 0.64)
			(layers "B.Cu" "B.Mask" "B.Paste")
			(roundrect_rratio 0.25)
			(net 141 "/2xSFP+/KR to SFI #1/~{RESET}")
			(pintype "passive")
			(teardrops
				(best_length_ratio 0.2)
				(max_length 1)
				(best_width_ratio 0.9)
				(max_width 2)
				(curved_edges yes)
				(filter_ratio 0.9)
				(enabled yes)
				(allow_two_segments yes)
				(prefer_zone_connections yes)
			)
		)
		(pad "2" smd roundrect
			(at 0.48 0 180)
			(size 0.59 0.64)
			(layers "B.Cu" "B.Mask" "B.Paste")
			(roundrect_rratio 0.25)
			(net 78 "+1V8")
			(pintype "passive")
			(teardrops
				(best_length_ratio 0.2)
				(max_length 1)
				(best_width_ratio 0.9)
				(max_width 2)
				(curved_edges yes)
				(filter_ratio 0.9)
				(enabled yes)
				(allow_two_segments yes)
				(prefer_zone_connections yes)
			)
		)
	)
	(footprint "antmicro-footprints:C_0402_1005Metric"
		(layer "B.Cu")
		(at 149.95 134.86)
		(descr "Capacitor SMD 0402")
		(tags "capacitor SMD 0402")
		(property "Reference" "C167"
			(at -3.1 -4.85 0)
			(layer "B.SilkS")
			(effects
				(font
					(size 0.7 0.7)
					(thickness 0.15)
				)
				(justify right bottom mirror)
			)
		)
		(property "Value" "C_100n_0402"
			(at -1.022927 -2.155213 0)
			(layer "B.Fab")
			(effects
				(font
					(size 0.7 0.7)
					(thickness 0.15)
				)
				(justify right bottom mirror)
			)
		)
		(property "Datasheet" "https://www.murata.com/products/productdetail?partno=GRM155R61H104KE14%23"
			(at 0 0 0)
			(layer "F.Fab")
			(hide yes)
			(effects
				(font
					(size 1.27 1.27)
					(thickness 0.15)
				)
			)
		)
		(property "Author" "Antmicro"
			(at 0 0 0)
			(layer "B.Fab")
			(hide yes)
			(effects
				(font
					(size 1 1)
					(thickness 0.15)
				)
				(justify mirror)
			)
		)
		(property "Dielectric" "X5R"
			(at 0 0 0)
			(layer "B.Fab")
			(hide yes)
			(effects
				(font
					(size 1 1)
					(thickness 0.15)
				)
				(justify mirror)
			)
		)
		(property "License" "Apache-2.0"
			(at 0 0 0)
			(layer "B.Fab")
			(hide yes)
			(effects
				(font
					(size 1 1)
					(thickness 0.15)
				)
				(justify mirror)
			)
		)
		(property "MPN" "GRM155R61H104KE14D"
			(at 0 0 0)
			(layer "B.Fab")
			(hide yes)
			(effects
				(font
					(size 1 1)
					(thickness 0.15)
				)
				(justify mirror)
			)
		)
		(property "Manufacturer" "Murata"
			(at 0 0 0)
			(layer "B.Fab")
			(hide yes)
			(effects
				(font
					(size 1 1)
					(thickness 0.15)
				)
				(justify mirror)
			)
		)
		(property "Public" "False"
			(at 0 0 0)
			(layer "B.Fab")
			(hide yes)
			(effects
				(font
					(size 1 1)
					(thickness 0.15)
				)
				(justify mirror)
			)
		)
		(property "Val" "100n"
			(at 0 0 0)
			(layer "B.Fab")
			(hide yes)
			(effects
				(font
					(size 1 1)
					(thickness 0.15)
				)
				(justify mirror)
			)
		)
		(property "Voltage" "50V"
			(at 0 0 0)
			(layer "B.Fab")
			(hide yes)
			(effects
				(font
					(size 1 1)
					(thickness 0.15)
				)
				(justify mirror)
			)
		)
		(sheetname "KR to SFI #1")
		(sheetfile "kr_sfi.kicad_sch")
		(attr smd)
		(fp_rect
			(start -0.925 0.47)
			(end 0.925 -0.47)
			(stroke
				(width 0.05)
				(type default)
			)
			(fill no)
			(layer "B.CrtYd")
		)
		(fp_line
			(start -0.494 -0.248)
			(end 0.504 -0.248)
			(stroke
				(width 0.15)
				(type solid)
			)
			(layer "B.Fab")
		)
		(fp_line
			(start -0.494 0.25)
			(end -0.494 -0.248)
			(stroke
				(width 0.15)
				(type solid)
			)
			(layer "B.Fab")
		)
		(fp_line
			(start 0.504 -0.248)
			(end 0.504 0.25)
			(stroke
				(width 0.15)
				(type solid)
			)
			(layer "B.Fab")
		)
		(fp_line
			(start 0.504 0.25)
			(end -0.494 0.25)
			(stroke
				(width 0.15)
				(type solid)
			)
			(layer "B.Fab")
		)
		(pad "1" smd roundrect
			(at -0.48 0)
			(size 0.59 0.64)
			(layers "B.Cu" "B.Mask" "B.Paste")
			(roundrect_rratio 0.25)
			(net 1 "GND")
			(pintype "passive")
			(teardrops
				(best_length_ratio 0.2)
				(max_length 1)
				(best_width_ratio 0.9)
				(max_width 2)
				(curved_edges yes)
				(filter_ratio 0.9)
				(enabled yes)
				(allow_two_segments yes)
				(prefer_zone_connections yes)
			)
		)
		(pad "2" smd roundrect
			(at 0.48 0)
			(size 0.59 0.64)
			(layers "B.Cu" "B.Mask" "B.Paste")
			(roundrect_rratio 0.25)
			(net 74 "+1V0")
			(pintype "passive")
			(teardrops
				(best_length_ratio 0.2)
				(max_length 1)
				(best_width_ratio 0.9)
				(max_width 2)
				(curved_edges yes)
				(filter_ratio 0.9)
				(enabled yes)
				(allow_two_segments yes)
				(prefer_zone_connections yes)
			)
		)
	)
	(footprint "antmicro-footprints:C_0402_1005Metric"
		(layer "B.Cu")
		(at 196.00804 142.248957 135)
		(descr "Capacitor SMD 0402")
		(tags "capacitor SMD 0402")
		(property "Reference" "C129"
			(at -3.530586 -0.359976 135)
			(layer "B.SilkS")
			(effects
				(font
					(size 0.7 0.7)
					(thickness 0.15)
				)
				(justify right bottom mirror)
			)
		)
		(property "Value" "C_220n_0402"
			(at -1.022927 -2.155213 135)
			(layer "B.Fab")
			(effects
				(font
					(size 0.7 0.7)
					(thickness 0.15)
				)
				(justify right bottom mirror)
			)
		)
		(property "Datasheet" "https://www.yageo.com/en/Chart/Download/pdf/CC0402KRX5R6BB224"
			(at 0 0 135)
			(layer "F.Fab")
			(hide yes)
			(effects
				(font
					(size 1.27 1.27)
					(thickness 0.15)
				)
			)
		)
		(property "Author" "Antmicro"
			(at 340.300001 -43.5 45)
			(layer "B.Fab")
			(hide yes)
			(effects
				(font
					(size 1 1)
					(thickness 0.15)
				)
				(justify mirror)
			)
		)
		(property "Dielectric" ""
			(at 340.300001 -43.5 45)
			(layer "B.Fab")
			(hide yes)
			(effects
				(font
					(size 1 1)
					(thickness 0.15)
				)
				(justify mirror)
			)
		)
		(property "License" "Apache-2.0"
			(at 340.300001 -43.5 45)
			(layer "B.Fab")
			(hide yes)
			(effects
				(font
					(size 1 1)
					(thickness 0.15)
				)
				(justify mirror)
			)
		)
		(property "MPN" "CC0402KRX5R6BB224"
			(at 340.300001 -43.5 45)
			(layer "B.Fab")
			(hide yes)
			(effects
				(font
					(size 1 1)
					(thickness 0.15)
				)
				(justify mirror)
			)
		)
		(property "Manufacturer" "YAGEO"
			(at 340.300001 -43.5 45)
			(layer "B.Fab")
			(hide yes)
			(effects
				(font
					(size 1 1)
					(thickness 0.15)
				)
				(justify mirror)
			)
		)
		(property "Public" "False"
			(at 340.300001 -43.5 45)
			(layer "B.Fab")
			(hide yes)
			(effects
				(font
					(size 1 1)
					(thickness 0.15)
				)
				(justify mirror)
			)
		)
		(property "Val" "220n"
			(at 340.300001 -43.5 45)
			(layer "B.Fab")
			(hide yes)
			(effects
				(font
					(size 1 1)
					(thickness 0.15)
				)
				(justify mirror)
			)
		)
		(property "Voltage" ""
			(at 340.300001 -43.5 45)
			(layer "B.Fab")
			(hide yes)
			(effects
				(font
					(size 1 1)
					(thickness 0.15)
				)
				(justify mirror)
			)
		)
		(sheetname "PCIe redriver")
		(sheetfile "pcie_redriver.kicad_sch")
		(attr smd)
		(fp_poly
			(pts
				(xy -0.925 0.47) (xy 0.925 0.47) (xy 0.925 -0.47) (xy -0.925 -0.47)
			)
			(stroke
				(width 0.05)
				(type default)
			)
			(fill no)
			(layer "B.CrtYd")
		)
		(fp_line
			(start 0.504 -0.248)
			(end 0.504 0.25)
			(stroke
				(width 0.15)
				(type solid)
			)
			(layer "B.Fab")
		)
		(fp_line
			(start 0.504 0.25)
			(end -0.494 0.25)
			(stroke
				(width 0.15)
				(type solid)
			)
			(layer "B.Fab")
		)
		(fp_line
			(start -0.494 -0.248)
			(end 0.504 -0.248)
			(stroke
				(width 0.15)
				(type solid)
			)
			(layer "B.Fab")
		)
		(fp_line
			(start -0.494 0.25)
			(end -0.494 -0.248)
			(stroke
				(width 0.15)
				(type solid)
			)
			(layer "B.Fab")
		)
		(pad "1" smd roundrect
			(at -0.48 0 135)
			(size 0.59 0.64)
			(layers "B.Cu" "B.Mask" "B.Paste")
			(roundrect_rratio 0.25)
			(net 210 "/Com Express 7 Interfaces/PCIe_{B1x4}.RX3+")
			(pintype "passive")
			(teardrops
				(best_length_ratio 0.2)
				(max_length 1)
				(best_width_ratio 0.9)
				(max_width 2)
				(curved_edges yes)
				(filter_ratio 0.9)
				(enabled yes)
				(allow_two_segments yes)
				(prefer_zone_connections yes)
			)
		)
		(pad "2" smd roundrect
			(at 0.48 0 135)
			(size 0.59 0.64)
			(layers "B.Cu" "B.Mask" "B.Paste")
			(roundrect_rratio 0.25)
			(net 960 "/PCIe redriver/PCIe_{I}_C.RX3+")
			(pintype "passive")
			(teardrops
				(best_length_ratio 0.2)
				(max_length 1)
				(best_width_ratio 0.9)
				(max_width 2)
				(curved_edges yes)
				(filter_ratio 0.9)
				(enabled yes)
				(allow_two_segments yes)
				(prefer_zone_connections yes)
			)
		)
	)
	(footprint "antmicro-footprints:C_0402_1005Metric"
		(layer "B.Cu")
		(at 150.45 138.36 -90)
		(descr "Capacitor SMD 0402")
		(tags "capacitor SMD 0402")
		(property "Reference" "C172"
			(at -0.3 0.55 90)
			(layer "B.SilkS")
			(effects
				(font
					(size 0.7 0.7)
					(thickness 0.15)
				)
				(justify left bottom mirror)
			)
		)
		(property "Value" "C_100n_0402"
			(at -1.022927 -2.155213 90)
			(layer "B.Fab")
			(effects
				(font
					(size 0.7 0.7)
					(thickness 0.15)
				)
				(justify left bottom mirror)
			)
		)
		(property "Datasheet" "https://www.murata.com/products/productdetail?partno=GRM155R61H104KE14%23"
			(at 0 0 270)
			(layer "F.Fab")
			(hide yes)
			(effects
				(font
					(size 1.27 1.27)
					(thickness 0.15)
				)
			)
		)
		(property "Author" "Antmicro"
			(at 12.09 288.81 0)
			(layer "B.Fab")
			(hide yes)
			(effects
				(font
					(size 1 1)
					(thickness 0.15)
				)
				(justify mirror)
			)
		)
		(property "Dielectric" "X5R"
			(at 12.09 288.81 0)
			(layer "B.Fab")
			(hide yes)
			(effects
				(font
					(size 1 1)
					(thickness 0.15)
				)
				(justify mirror)
			)
		)
		(property "License" "Apache-2.0"
			(at 12.09 288.81 0)
			(layer "B.Fab")
			(hide yes)
			(effects
				(font
					(size 1 1)
					(thickness 0.15)
				)
				(justify mirror)
			)
		)
		(property "MPN" "GRM155R61H104KE14D"
			(at 12.09 288.81 0)
			(layer "B.Fab")
			(hide yes)
			(effects
				(font
					(size 1 1)
					(thickness 0.15)
				)
				(justify mirror)
			)
		)
		(property "Manufacturer" "Murata"
			(at 12.09 288.81 0)
			(layer "B.Fab")
			(hide yes)
			(effects
				(font
					(size 1 1)
					(thickness 0.15)
				)
				(justify mirror)
			)
		)
		(property "Public" "False"
			(at 12.09 288.81 0)
			(layer "B.Fab")
			(hide yes)
			(effects
				(font
					(size 1 1)
					(thickness 0.15)
				)
				(justify mirror)
			)
		)
		(property "Val" "100n"
			(at 12.09 288.81 0)
			(layer "B.Fab")
			(hide yes)
			(effects
				(font
					(size 1 1)
					(thickness 0.15)
				)
				(justify mirror)
			)
		)
		(property "Voltage" "50V"
			(at 12.09 288.81 0)
			(layer "B.Fab")
			(hide yes)
			(effects
				(font
					(size 1 1)
					(thickness 0.15)
				)
				(justify mirror)
			)
		)
		(sheetname "KR to SFI #1")
		(sheetfile "kr_sfi.kicad_sch")
		(attr smd)
		(fp_rect
			(start -0.925 0.47)
			(end 0.925 -0.47)
			(stroke
				(width 0.05)
				(type default)
			)
			(fill no)
			(layer "B.CrtYd")
		)
		(fp_line
			(start -0.494 0.25)
			(end -0.494 -0.248)
			(stroke
				(width 0.15)
				(type solid)
			)
			(layer "B.Fab")
		)
		(fp_line
			(start 0.504 0.25)
			(end -0.494 0.25)
			(stroke
				(width 0.15)
				(type solid)
			)
			(layer "B.Fab")
		)
		(fp_line
			(start -0.494 -0.248)
			(end 0.504 -0.248)
			(stroke
				(width 0.15)
				(type solid)
			)
			(layer "B.Fab")
		)
		(fp_line
			(start 0.504 -0.248)
			(end 0.504 0.25)
			(stroke
				(width 0.15)
				(type solid)
			)
			(layer "B.Fab")
		)
		(pad "1" smd roundrect
			(at -0.48 0 270)
			(size 0.59 0.64)
			(layers "B.Cu" "B.Mask" "B.Paste")
			(roundrect_rratio 0.25)
			(net 1 "GND")
			(pintype "passive")
			(teardrops
				(best_length_ratio 0.2)
				(max_length 1)
				(best_width_ratio 0.9)
				(max_width 2)
				(curved_edges yes)
				(filter_ratio 0.9)
				(enabled yes)
				(allow_two_segments yes)
				(prefer_zone_connections yes)
			)
		)
		(pad "2" smd roundrect
			(at 0.48 0 270)
			(size 0.59 0.64)
			(layers "B.Cu" "B.Mask" "B.Paste")
			(roundrect_rratio 0.25)
			(net 74 "+1V0")
			(pintype "passive")
			(teardrops
				(best_length_ratio 0.2)
				(max_length 1)
				(best_width_ratio 0.9)
				(max_width 2)
				(curved_edges yes)
				(filter_ratio 0.9)
				(enabled yes)
				(allow_two_segments yes)
				(prefer_zone_connections yes)
			)
		)
	)
	(footprint "antmicro-footprints:TP_SMD_0.75mm"
		(layer "B.Cu")
		(at 193.05 163.35 90)
		(property "Reference" "TP33"
			(at 0.85 0.45 270)
			(layer "B.SilkS")
			(effects
				(font
					(size 0.7 0.7)
					(thickness 0.15)
				)
				(justify right bottom mirror)
			)
		)
		(property "Value" "TP_0.75mm_SMD"
			(at 0 -1.2 90)
			(layer "B.Fab")
			(effects
				(font
					(size 0.7 0.7)
					(thickness 0.15)
				)
				(justify right bottom mirror)
			)
		)
		(property "Author" "Antmicro"
			(at 362.31 -49.29 0)
			(layer "B.Fab")
			(hide yes)
			(effects
				(font
					(size 1 1)
					(thickness 0.15)
				)
				(justify mirror)
			)
		)
		(property "License" "Apache-2.0"
			(at 362.31 -49.29 0)
			(layer "B.Fab")
			(hide yes)
			(effects
				(font
					(size 1 1)
					(thickness 0.15)
				)
				(justify mirror)
			)
		)
		(property "MPN" ""
			(at 362.31 -49.29 0)
			(layer "B.Fab")
			(hide yes)
			(effects
				(font
					(size 1 1)
					(thickness 0.15)
				)
				(justify mirror)
			)
		)
		(property "Manufacturer" ""
			(at 362.31 -49.29 0)
			(layer "B.Fab")
			(hide yes)
			(effects
				(font
					(size 1 1)
					(thickness 0.15)
				)
				(justify mirror)
			)
		)
		(property "Public" "False"
			(at 362.31 -49.29 0)
			(layer "B.Fab")
			(hide yes)
			(effects
				(font
					(size 1 1)
					(thickness 0.15)
				)
				(justify mirror)
			)
		)
		(sheetname "Com Express 7 MGMT")
		(sheetfile "com_express_7_mgmt.kicad_sch")
		(attr exclude_from_pos_files exclude_from_bom)
		(fp_circle
			(center 0 0)
			(end 0.475 0)
			(stroke
				(width 0.05)
				(type default)
			)
			(fill no)
			(layer "B.CrtYd")
		)
		(pad "1" smd circle
			(at 0 0 90)
			(size 0.75 0.75)
			(layers "B.Cu" "B.Mask")
			(net 381 "Net-(J12D-~{SYS_RESET})")
			(pinfunction "1")
			(pintype "passive")
			(teardrops
				(best_length_ratio 0.4)
				(max_length 1)
				(best_width_ratio 0.9)
				(max_width 2)
				(curved_edges yes)
				(filter_ratio 0.9)
				(enabled yes)
				(allow_two_segments yes)
				(prefer_zone_connections yes)
			)
		)
	)
	(footprint "antmicro-footprints:C_0402_1005Metric"
		(layer "B.Cu")
		(at 154.45 137.36 -90)
		(descr "Capacitor SMD 0402")
		(tags "capacitor SMD 0402")
		(property "Reference" "C164"
			(at -1.4 -1.4 90)
			(layer "B.SilkS")
			(effects
				(font
					(size 0.7 0.7)
					(thickness 0.15)
				)
				(justify left bottom mirror)
			)
		)
		(property "Value" "C_100n_0402"
			(at -1.022927 -2.155213 90)
			(layer "B.Fab")
			(effects
				(font
					(size 0.7 0.7)
					(thickness 0.15)
				)
				(justify left bottom mirror)
			)
		)
		(property "Datasheet" "https://www.murata.com/products/productdetail?partno=GRM155R61H104KE14%23"
			(at 0 0 270)
			(layer "F.Fab")
			(hide yes)
			(effects
				(font
					(size 1.27 1.27)
					(thickness 0.15)
				)
			)
		)
		(property "Author" "Antmicro"
			(at 17.09 291.81 0)
			(layer "B.Fab")
			(hide yes)
			(effects
				(font
					(size 1 1)
					(thickness 0.15)
				)
				(justify mirror)
			)
		)
		(property "Dielectric" "X5R"
			(at 17.09 291.81 0)
			(layer "B.Fab")
			(hide yes)
			(effects
				(font
					(size 1 1)
					(thickness 0.15)
				)
				(justify mirror)
			)
		)
		(property "License" "Apache-2.0"
			(at 17.09 291.81 0)
			(layer "B.Fab")
			(hide yes)
			(effects
				(font
					(size 1 1)
					(thickness 0.15)
				)
				(justify mirror)
			)
		)
		(property "MPN" "GRM155R61H104KE14D"
			(at 17.09 291.81 0)
			(layer "B.Fab")
			(hide yes)
			(effects
				(font
					(size 1 1)
					(thickness 0.15)
				)
				(justify mirror)
			)
		)
		(property "Manufacturer" "Murata"
			(at 17.09 291.81 0)
			(layer "B.Fab")
			(hide yes)
			(effects
				(font
					(size 1 1)
					(thickness 0.15)
				)
				(justify mirror)
			)
		)
		(property "Public" "False"
			(at 17.09 291.81 0)
			(layer "B.Fab")
			(hide yes)
			(effects
				(font
					(size 1 1)
					(thickness 0.15)
				)
				(justify mirror)
			)
		)
		(property "Val" "100n"
			(at 17.09 291.81 0)
			(layer "B.Fab")
			(hide yes)
			(effects
				(font
					(size 1 1)
					(thickness 0.15)
				)
				(justify mirror)
			)
		)
		(property "Voltage" "50V"
			(at 17.09 291.81 0)
			(layer "B.Fab")
			(hide yes)
			(effects
				(font
					(size 1 1)
					(thickness 0.15)
				)
				(justify mirror)
			)
		)
		(sheetname "KR to SFI #1")
		(sheetfile "kr_sfi.kicad_sch")
		(attr smd)
		(fp_rect
			(start -0.925 0.47)
			(end 0.925 -0.47)
			(stroke
				(width 0.05)
				(type default)
			)
			(fill no)
			(layer "B.CrtYd")
		)
		(fp_line
			(start -0.494 0.25)
			(end -0.494 -0.248)
			(stroke
				(width 0.15)
				(type solid)
			)
			(layer "B.Fab")
		)
		(fp_line
			(start 0.504 0.25)
			(end -0.494 0.25)
			(stroke
				(width 0.15)
				(type solid)
			)
			(layer "B.Fab")
		)
		(fp_line
			(start -0.494 -0.248)
			(end 0.504 -0.248)
			(stroke
				(width 0.15)
				(type solid)
			)
			(layer "B.Fab")
		)
		(fp_line
			(start 0.504 -0.248)
			(end 0.504 0.25)
			(stroke
				(width 0.15)
				(type solid)
			)
			(layer "B.Fab")
		)
		(pad "1" smd roundrect
			(at -0.48 0 270)
			(size 0.59 0.64)
			(layers "B.Cu" "B.Mask" "B.Paste")
			(roundrect_rratio 0.25)
			(net 1 "GND")
			(pintype "passive")
			(teardrops
				(best_length_ratio 0.2)
				(max_length 1)
				(best_width_ratio 0.9)
				(max_width 2)
				(curved_edges yes)
				(filter_ratio 0.9)
				(enabled yes)
				(allow_two_segments yes)
				(prefer_zone_connections yes)
			)
		)
		(pad "2" smd roundrect
			(at 0.48 0 270)
			(size 0.59 0.64)
			(layers "B.Cu" "B.Mask" "B.Paste")
			(roundrect_rratio 0.25)
			(net 74 "+1V0")
			(pintype "passive")
			(teardrops
				(best_length_ratio 0.2)
				(max_length 1)
				(best_width_ratio 0.9)
				(max_width 2)
				(curved_edges yes)
				(filter_ratio 0.9)
				(enabled yes)
				(allow_two_segments yes)
				(prefer_zone_connections yes)
			)
		)
	)
	(footprint "antmicro-footprints:C_0402_1005Metric"
		(layer "B.Cu")
		(at 118.48 168.91)
		(descr "Capacitor SMD 0402")
		(tags "capacitor SMD 0402")
		(property "Reference" "C28"
			(at -1.03 -0.5 0)
			(layer "B.SilkS")
			(effects
				(font
					(size 0.7 0.7)
					(thickness 0.15)
				)
				(justify right bottom mirror)
			)
		)
		(property "Value" "C_100n_0402"
			(at -1.022927 -2.155213 0)
			(layer "B.Fab")
			(effects
				(font
					(size 0.7 0.7)
					(thickness 0.15)
				)
				(justify right bottom mirror)
			)
		)
		(property "Datasheet" "https://www.murata.com/products/productdetail?partno=GRM155R61H104KE14%23"
			(at 0 0 0)
			(layer "F.Fab")
			(hide yes)
			(effects
				(font
					(size 1.27 1.27)
					(thickness 0.15)
				)
			)
		)
		(property "Author" "Antmicro"
			(at 0 0 0)
			(layer "B.Fab")
			(hide yes)
			(effects
				(font
					(size 1 1)
					(thickness 0.15)
				)
				(justify mirror)
			)
		)
		(property "Dielectric" "X5R"
			(at 0 0 0)
			(layer "B.Fab")
			(hide yes)
			(effects
				(font
					(size 1 1)
					(thickness 0.15)
				)
				(justify mirror)
			)
		)
		(property "License" "Apache-2.0"
			(at 0 0 0)
			(layer "B.Fab")
			(hide yes)
			(effects
				(font
					(size 1 1)
					(thickness 0.15)
				)
				(justify mirror)
			)
		)
		(property "MPN" "GRM155R61H104KE14D"
			(at 0 0 0)
			(layer "B.Fab")
			(hide yes)
			(effects
				(font
					(size 1 1)
					(thickness 0.15)
				)
				(justify mirror)
			)
		)
		(property "Manufacturer" "Murata"
			(at 0 0 0)
			(layer "B.Fab")
			(hide yes)
			(effects
				(font
					(size 1 1)
					(thickness 0.15)
				)
				(justify mirror)
			)
		)
		(property "Public" "False"
			(at 0 0 0)
			(layer "B.Fab")
			(hide yes)
			(effects
				(font
					(size 1 1)
					(thickness 0.15)
				)
				(justify mirror)
			)
		)
		(property "Val" "100n"
			(at 0 0 0)
			(layer "B.Fab")
			(hide yes)
			(effects
				(font
					(size 1 1)
					(thickness 0.15)
				)
				(justify mirror)
			)
		)
		(property "Voltage" "50V"
			(at 0 0 0)
			(layer "B.Fab")
			(hide yes)
			(effects
				(font
					(size 1 1)
					(thickness 0.15)
				)
				(justify mirror)
			)
		)
		(sheetname "2xSFP+")
		(sheetfile "2xSFP+.kicad_sch")
		(attr smd)
		(fp_rect
			(start -0.925 0.47)
			(end 0.925 -0.47)
			(stroke
				(width 0.05)
				(type default)
			)
			(fill no)
			(layer "B.CrtYd")
		)
		(fp_line
			(start -0.494 -0.248)
			(end 0.504 -0.248)
			(stroke
				(width 0.15)
				(type solid)
			)
			(layer "B.Fab")
		)
		(fp_line
			(start -0.494 0.25)
			(end -0.494 -0.248)
			(stroke
				(width 0.15)
				(type solid)
			)
			(layer "B.Fab")
		)
		(fp_line
			(start 0.504 -0.248)
			(end 0.504 0.25)
			(stroke
				(width 0.15)
				(type solid)
			)
			(layer "B.Fab")
		)
		(fp_line
			(start 0.504 0.25)
			(end -0.494 0.25)
			(stroke
				(width 0.15)
				(type solid)
			)
			(layer "B.Fab")
		)
		(pad "1" smd roundrect
			(at -0.48 0)
			(size 0.59 0.64)
			(layers "B.Cu" "B.Mask" "B.Paste")
			(roundrect_rratio 0.25)
			(net 53 "/2xSFP+/SH")
			(pintype "passive")
			(teardrops
				(best_length_ratio 0.2)
				(max_length 1)
				(best_width_ratio 0.9)
				(max_width 2)
				(curved_edges yes)
				(filter_ratio 0.9)
				(enabled yes)
				(allow_two_segments yes)
				(prefer_zone_connections yes)
			)
		)
		(pad "2" smd roundrect
			(at 0.48 0)
			(size 0.59 0.64)
			(layers "B.Cu" "B.Mask" "B.Paste")
			(roundrect_rratio 0.25)
			(net 1 "GND")
			(pintype "passive")
			(teardrops
				(best_length_ratio 0.2)
				(max_length 1)
				(best_width_ratio 0.9)
				(max_width 2)
				(curved_edges yes)
				(filter_ratio 0.9)
				(enabled yes)
				(allow_two_segments yes)
				(prefer_zone_connections yes)
			)
		)
	)
	(footprint "antmicro-footprints:C_0603_1608Metric"
		(layer "B.Cu")
		(at 147.3 132.078 -90)
		(descr "Capacitor SMD 0603")
		(tags "capacitor 0603")
		(property "Reference" "C156"
			(at -6.968 1.9 90)
			(layer "B.SilkS")
			(effects
				(font
					(size 0.7 0.7)
					(thickness 0.15)
				)
				(justify left bottom mirror)
			)
		)
		(property "Value" "C_22u_16V_0603"
			(at -1.42757 -1.770288 90)
			(layer "B.Fab")
			(effects
				(font
					(size 0.7 0.7)
					(thickness 0.15)
				)
				(justify left bottom mirror)
			)
		)
		(property "Datasheet" "https://product.samsungsem.com/mlcc/CL10A226MO7JZN.do"
			(at 0 0 270)
			(layer "F.Fab")
			(hide yes)
			(effects
				(font
					(size 1.27 1.27)
					(thickness 0.15)
				)
			)
		)
		(property "Author" "Antmicro"
			(at 15.222 279.378 0)
			(layer "B.Fab")
			(hide yes)
			(effects
				(font
					(size 1 1)
					(thickness 0.15)
				)
				(justify mirror)
			)
		)
		(property "Dielectric" ""
			(at 15.222 279.378 0)
			(layer "B.Fab")
			(hide yes)
			(effects
				(font
					(size 1 1)
					(thickness 0.15)
				)
				(justify mirror)
			)
		)
		(property "License" "Apache-2.0"
			(at 15.222 279.378 0)
			(layer "B.Fab")
			(hide yes)
			(effects
				(font
					(size 1 1)
					(thickness 0.15)
				)
				(justify mirror)
			)
		)
		(property "MPN" "CL10A226MO7JZNC"
			(at 15.222 279.378 0)
			(layer "B.Fab")
			(hide yes)
			(effects
				(font
					(size 1 1)
					(thickness 0.15)
				)
				(justify mirror)
			)
		)
		(property "Manufacturer" "Samsung Electro-Mechanics"
			(at 15.222 279.378 0)
			(layer "B.Fab")
			(hide yes)
			(effects
				(font
					(size 1 1)
					(thickness 0.15)
				)
				(justify mirror)
			)
		)
		(property "Public" "False"
			(at 15.222 279.378 0)
			(layer "B.Fab")
			(hide yes)
			(effects
				(font
					(size 1 1)
					(thickness 0.15)
				)
				(justify mirror)
			)
		)
		(property "Val" "22u"
			(at 15.222 279.378 0)
			(layer "B.Fab")
			(hide yes)
			(effects
				(font
					(size 1 1)
					(thickness 0.15)
				)
				(justify mirror)
			)
		)
		(property "Voltage" "16V"
			(at 15.222 279.378 0)
			(layer "B.Fab")
			(hide yes)
			(effects
				(font
					(size 1 1)
					(thickness 0.15)
				)
				(justify mirror)
			)
		)
		(sheetname "KR to SFI #1")
		(sheetfile "kr_sfi.kicad_sch")
		(attr smd)
		(fp_line
			(start 0.15 0.4)
			(end -0.15 0.4)
			(stroke
				(width 0.15)
				(type solid)
			)
			(layer "B.SilkS")
		)
		(fp_line
			(start 0.15 -0.4)
			(end -0.15 -0.4)
			(stroke
				(width 0.15)
				(type solid)
			)
			(layer "B.SilkS")
		)
		(fp_rect
			(start -1.25 0.65)
			(end 1.25 -0.65)
			(stroke
				(width 0.05)
				(type solid)
			)
			(fill no)
			(layer "B.CrtYd")
		)
		(fp_rect
			(start -0.8 0.4)
			(end 0.8 -0.4)
			(stroke
				(width 0.15)
				(type solid)
			)
			(fill no)
			(layer "B.Fab")
		)
		(pad "1" smd roundrect
			(at -0.7 0 270)
			(size 0.8 1)
			(layers "B.Cu" "B.Mask" "B.Paste")
			(roundrect_rratio 0.2)
			(net 1 "GND")
			(pintype "passive")
			(teardrops
				(best_length_ratio 0.2)
				(max_length 1)
				(best_width_ratio 0.9)
				(max_width 2)
				(curved_edges yes)
				(filter_ratio 0.9)
				(enabled yes)
				(allow_two_segments yes)
				(prefer_zone_connections yes)
			)
		)
		(pad "2" smd roundrect
			(at 0.7 0 270)
			(size 0.8 1)
			(layers "B.Cu" "B.Mask" "B.Paste")
			(roundrect_rratio 0.2)
			(net 78 "+1V8")
			(pintype "passive")
			(teardrops
				(best_length_ratio 0.2)
				(max_length 1)
				(best_width_ratio 0.9)
				(max_width 2)
				(curved_edges yes)
				(filter_ratio 0.9)
				(enabled yes)
				(allow_two_segments yes)
				(prefer_zone_connections yes)
			)
		)
	)
	(footprint "antmicro-footprints:R_0402_1005Metric"
		(layer "B.Cu")
		(at 130.7 133.87 180)
		(descr "Resistor SMD 0402")
		(tags "resistor SMD 0402")
		(property "Reference" "R301"
			(at 0.45 4.91 0)
			(layer "B.SilkS")
			(effects
				(font
					(size 0.7 0.7)
					(thickness 0.15)
				)
				(justify left bottom mirror)
			)
		)
		(property "Value" "R_10k_0402"
			(at -1.011843 -1.772047 0)
			(layer "B.Fab")
			(effects
				(font
					(size 0.7 0.7)
					(thickness 0.15)
				)
				(justify left bottom mirror)
			)
		)
		(property "Datasheet" "https://www.bourns.com/docs/product-datasheets/cr.pdf"
			(at 0 0 180)
			(layer "F.Fab")
			(hide yes)
			(effects
				(font
					(size 1.27 1.27)
					(thickness 0.15)
				)
			)
		)
		(property "Author" "Antmicro"
			(at 261.4 267.74 0)
			(layer "B.Fab")
			(hide yes)
			(effects
				(font
					(size 1 1)
					(thickness 0.15)
				)
				(justify mirror)
			)
		)
		(property "License" "Apache-2.0"
			(at 261.4 267.74 0)
			(layer "B.Fab")
			(hide yes)
			(effects
				(font
					(size 1 1)
					(thickness 0.15)
				)
				(justify mirror)
			)
		)
		(property "MPN" "CR0402-FX-1002GLF"
			(at 261.4 267.74 0)
			(layer "B.Fab")
			(hide yes)
			(effects
				(font
					(size 1 1)
					(thickness 0.15)
				)
				(justify mirror)
			)
		)
		(property "Manufacturer" "Bourns"
			(at 261.4 267.74 0)
			(layer "B.Fab")
			(hide yes)
			(effects
				(font
					(size 1 1)
					(thickness 0.15)
				)
				(justify mirror)
			)
		)
		(property "Public" "False"
			(at 261.4 267.74 0)
			(layer "B.Fab")
			(hide yes)
			(effects
				(font
					(size 1 1)
					(thickness 0.15)
				)
				(justify mirror)
			)
		)
		(property "Tolerance" "1%"
			(at 261.4 267.74 0)
			(layer "B.Fab")
			(hide yes)
			(effects
				(font
					(size 1 1)
					(thickness 0.15)
				)
				(justify mirror)
			)
		)
		(property "Val" "10k"
			(at 261.4 267.74 0)
			(layer "B.Fab")
			(hide yes)
			(effects
				(font
					(size 1 1)
					(thickness 0.15)
				)
				(justify mirror)
			)
		)
		(sheetname "KR to SFI #2")
		(sheetfile "kr_sfi.kicad_sch")
		(attr smd)
		(fp_rect
			(start -0.925 0.47)
			(end 0.925 -0.47)
			(stroke
				(width 0.05)
				(type default)
			)
			(fill no)
			(layer "B.CrtYd")
		)
		(fp_rect
			(start -0.5 0.25)
			(end 0.5 -0.25)
			(stroke
				(width 0.15)
				(type solid)
			)
			(fill no)
			(layer "B.Fab")
		)
		(pad "1" smd roundrect
			(at -0.48 0 180)
			(size 0.59 0.64)
			(layers "B.Cu" "B.Mask" "B.Paste")
			(roundrect_rratio 0.25)
			(net 681 "Net-(U45B-~{PDTRXB})")
			(pintype "passive")
			(teardrops
				(best_length_ratio 0.2)
				(max_length 1)
				(best_width_ratio 0.9)
				(max_width 2)
				(curved_edges yes)
				(filter_ratio 0.9)
				(enabled yes)
				(allow_two_segments yes)
				(prefer_zone_connections yes)
			)
		)
		(pad "2" smd roundrect
			(at 0.48 0 180)
			(size 0.59 0.64)
			(layers "B.Cu" "B.Mask" "B.Paste")
			(roundrect_rratio 0.25)
			(net 78 "+1V8")
			(pintype "passive")
			(teardrops
				(best_length_ratio 0.2)
				(max_length 1)
				(best_width_ratio 0.9)
				(max_width 2)
				(curved_edges yes)
				(filter_ratio 0.9)
				(enabled yes)
				(allow_two_segments yes)
				(prefer_zone_connections yes)
			)
		)
	)
	(footprint "antmicro-footprints:C_0402_1005Metric"
		(layer "B.Cu")
		(at 150.45 132.36 -90)
		(descr "Capacitor SMD 0402")
		(tags "capacitor SMD 0402")
		(property "Reference" "C171"
			(at -3.65 -0.45 90)
			(layer "B.SilkS")
			(effects
				(font
					(size 0.7 0.7)
					(thickness 0.15)
				)
				(justify left bottom mirror)
			)
		)
		(property "Value" "C_100n_0402"
			(at -1.022927 -2.155213 90)
			(layer "B.Fab")
			(effects
				(font
					(size 0.7 0.7)
					(thickness 0.15)
				)
				(justify left bottom mirror)
			)
		)
		(property "Datasheet" "https://www.murata.com/products/productdetail?partno=GRM155R61H104KE14%23"
			(at 0 0 270)
			(layer "F.Fab")
			(hide yes)
			(effects
				(font
					(size 1.27 1.27)
					(thickness 0.15)
				)
			)
		)
		(property "Author" "Antmicro"
			(at 18.09 282.81 0)
			(layer "B.Fab")
			(hide yes)
			(effects
				(font
					(size 1 1)
					(thickness 0.15)
				)
				(justify mirror)
			)
		)
		(property "Dielectric" "X5R"
			(at 18.09 282.81 0)
			(layer "B.Fab")
			(hide yes)
			(effects
				(font
					(size 1 1)
					(thickness 0.15)
				)
				(justify mirror)
			)
		)
		(property "License" "Apache-2.0"
			(at 18.09 282.81 0)
			(layer "B.Fab")
			(hide yes)
			(effects
				(font
					(size 1 1)
					(thickness 0.15)
				)
				(justify mirror)
			)
		)
		(property "MPN" "GRM155R61H104KE14D"
			(at 18.09 282.81 0)
			(layer "B.Fab")
			(hide yes)
			(effects
				(font
					(size 1 1)
					(thickness 0.15)
				)
				(justify mirror)
			)
		)
		(property "Manufacturer" "Murata"
			(at 18.09 282.81 0)
			(layer "B.Fab")
			(hide yes)
			(effects
				(font
					(size 1 1)
					(thickness 0.15)
				)
				(justify mirror)
			)
		)
		(property "Public" "False"
			(at 18.09 282.81 0)
			(layer "B.Fab")
			(hide yes)
			(effects
				(font
					(size 1 1)
					(thickness 0.15)
				)
				(justify mirror)
			)
		)
		(property "Val" "100n"
			(at 18.09 282.81 0)
			(layer "B.Fab")
			(hide yes)
			(effects
				(font
					(size 1 1)
					(thickness 0.15)
				)
				(justify mirror)
			)
		)
		(property "Voltage" "50V"
			(at 18.09 282.81 0)
			(layer "B.Fab")
			(hide yes)
			(effects
				(font
					(size 1 1)
					(thickness 0.15)
				)
				(justify mirror)
			)
		)
		(sheetname "KR to SFI #1")
		(sheetfile "kr_sfi.kicad_sch")
		(attr smd)
		(fp_rect
			(start -0.925 0.47)
			(end 0.925 -0.47)
			(stroke
				(width 0.05)
				(type default)
			)
			(fill no)
			(layer "B.CrtYd")
		)
		(fp_line
			(start -0.494 0.25)
			(end -0.494 -0.248)
			(stroke
				(width 0.15)
				(type solid)
			)
			(layer "B.Fab")
		)
		(fp_line
			(start 0.504 0.25)
			(end -0.494 0.25)
			(stroke
				(width 0.15)
				(type solid)
			)
			(layer "B.Fab")
		)
		(fp_line
			(start -0.494 -0.248)
			(end 0.504 -0.248)
			(stroke
				(width 0.15)
				(type solid)
			)
			(layer "B.Fab")
		)
		(fp_line
			(start 0.504 -0.248)
			(end 0.504 0.25)
			(stroke
				(width 0.15)
				(type solid)
			)
			(layer "B.Fab")
		)
		(pad "1" smd roundrect
			(at -0.48 0 270)
			(size 0.59 0.64)
			(layers "B.Cu" "B.Mask" "B.Paste")
			(roundrect_rratio 0.25)
			(net 1 "GND")
			(pintype "passive")
			(teardrops
				(best_length_ratio 0.2)
				(max_length 1)
				(best_width_ratio 0.9)
				(max_width 2)
				(curved_edges yes)
				(filter_ratio 0.9)
				(enabled yes)
				(allow_two_segments yes)
				(prefer_zone_connections yes)
			)
		)
		(pad "2" smd roundrect
			(at 0.48 0 270)
			(size 0.59 0.64)
			(layers "B.Cu" "B.Mask" "B.Paste")
			(roundrect_rratio 0.25)
			(net 74 "+1V0")
			(pintype "passive")
			(teardrops
				(best_length_ratio 0.2)
				(max_length 1)
				(best_width_ratio 0.9)
				(max_width 2)
				(curved_edges yes)
				(filter_ratio 0.9)
				(enabled yes)
				(allow_two_segments yes)
				(prefer_zone_connections yes)
			)
		)
	)
	(footprint "antmicro-footprints:C_0402_1005Metric"
		(layer "B.Cu")
		(at 107.893 165.355571 180)
		(descr "Capacitor SMD 0402")
		(tags "capacitor SMD 0402")
		(property "Reference" "C141"
			(at -3.657 0.045571 0)
			(layer "B.SilkS")
			(effects
				(font
					(size 0.7 0.7)
					(thickness 0.15)
				)
				(justify left bottom mirror)
			)
		)
		(property "Value" "C_220n_0402"
			(at -1.022927 -2.155213 0)
			(layer "B.Fab")
			(effects
				(font
					(size 0.7 0.7)
					(thickness 0.15)
				)
				(justify left bottom mirror)
			)
		)
		(property "Datasheet" "https://www.yageo.com/en/Chart/Download/pdf/CC0402KRX5R6BB224"
			(at 0 0 180)
			(layer "F.Fab")
			(hide yes)
			(effects
				(font
					(size 1.27 1.27)
					(thickness 0.15)
				)
			)
		)
		(property "Author" "Antmicro"
			(at 215.786 330.711142 0)
			(layer "B.Fab")
			(hide yes)
			(effects
				(font
					(size 1 1)
					(thickness 0.15)
				)
				(justify mirror)
			)
		)
		(property "Dielectric" ""
			(at 215.786 330.711142 0)
			(layer "B.Fab")
			(hide yes)
			(effects
				(font
					(size 1 1)
					(thickness 0.15)
				)
				(justify mirror)
			)
		)
		(property "License" "Apache-2.0"
			(at 215.786 330.711142 0)
			(layer "B.Fab")
			(hide yes)
			(effects
				(font
					(size 1 1)
					(thickness 0.15)
				)
				(justify mirror)
			)
		)
		(property "MPN" "CC0402KRX5R6BB224"
			(at 215.786 330.711142 0)
			(layer "B.Fab")
			(hide yes)
			(effects
				(font
					(size 1 1)
					(thickness 0.15)
				)
				(justify mirror)
			)
		)
		(property "Manufacturer" "YAGEO"
			(at 215.786 330.711142 0)
			(layer "B.Fab")
			(hide yes)
			(effects
				(font
					(size 1 1)
					(thickness 0.15)
				)
				(justify mirror)
			)
		)
		(property "Public" "False"
			(at 215.786 330.711142 0)
			(layer "B.Fab")
			(hide yes)
			(effects
				(font
					(size 1 1)
					(thickness 0.15)
				)
				(justify mirror)
			)
		)
		(property "Val" "220n"
			(at 215.786 330.711142 0)
			(layer "B.Fab")
			(hide yes)
			(effects
				(font
					(size 1 1)
					(thickness 0.15)
				)
				(justify mirror)
			)
		)
		(property "Voltage" ""
			(at 215.786 330.711142 0)
			(layer "B.Fab")
			(hide yes)
			(effects
				(font
					(size 1 1)
					(thickness 0.15)
				)
				(justify mirror)
			)
		)
		(sheetname "PCIe redriver")
		(sheetfile "pcie_redriver.kicad_sch")
		(attr smd)
		(fp_rect
			(start -0.925 0.47)
			(end 0.925 -0.47)
			(stroke
				(width 0.05)
				(type default)
			)
			(fill no)
			(layer "B.CrtYd")
		)
		(fp_line
			(start 0.504 0.25)
			(end -0.494 0.25)
			(stroke
				(width 0.15)
				(type solid)
			)
			(layer "B.Fab")
		)
		(fp_line
			(start 0.504 -0.248)
			(end 0.504 0.25)
			(stroke
				(width 0.15)
				(type solid)
			)
			(layer "B.Fab")
		)
		(fp_line
			(start -0.494 0.25)
			(end -0.494 -0.248)
			(stroke
				(width 0.15)
				(type solid)
			)
			(layer "B.Fab")
		)
		(fp_line
			(start -0.494 -0.248)
			(end 0.504 -0.248)
			(stroke
				(width 0.15)
				(type solid)
			)
			(layer "B.Fab")
		)
		(pad "1" smd roundrect
			(at -0.48 0 180)
			(size 0.59 0.64)
			(layers "B.Cu" "B.Mask" "B.Paste")
			(roundrect_rratio 0.25)
			(net 962 "/PCIe redriver/PCIe_{O}_C.TX1+")
			(pintype "passive")
			(teardrops
				(best_length_ratio 0.2)
				(max_length 1)
				(best_width_ratio 0.9)
				(max_width 2)
				(curved_edges yes)
				(filter_ratio 0.9)
				(enabled yes)
				(allow_two_segments yes)
				(prefer_zone_connections yes)
			)
		)
		(pad "2" smd roundrect
			(at 0.48 0 180)
			(size 0.59 0.64)
			(layers "B.Cu" "B.Mask" "B.Paste")
			(roundrect_rratio 0.25)
			(net 102 "/OCuLink/PCIe_{x4}.TX1+")
			(pintype "passive")
			(teardrops
				(best_length_ratio 0.2)
				(max_length 1)
				(best_width_ratio 0.9)
				(max_width 2)
				(curved_edges yes)
				(filter_ratio 0.9)
				(enabled yes)
				(allow_two_segments yes)
				(prefer_zone_connections yes)
			)
		)
	)
	(footprint "antmicro-footprints:R_0402_1005Metric"
		(layer "B.Cu")
		(at 157.9 142.36 180)
		(descr "Resistor SMD 0402")
		(tags "resistor SMD 0402")
		(property "Reference" "R261"
			(at -3.7 -0.4 0)
			(layer "B.SilkS")
			(effects
				(font
					(size 0.7 0.7)
					(thickness 0.15)
				)
				(justify left bottom mirror)
			)
		)
		(property "Value" "R_10k_0402"
			(at -1.011843 -1.772047 0)
			(layer "B.Fab")
			(effects
				(font
					(size 0.7 0.7)
					(thickness 0.15)
				)
				(justify left bottom mirror)
			)
		)
		(property "Datasheet" "https://www.bourns.com/docs/product-datasheets/cr.pdf"
			(at 0 0 180)
			(layer "F.Fab")
			(hide yes)
			(effects
				(font
					(size 1.27 1.27)
					(thickness 0.15)
				)
			)
		)
		(property "Author" "Antmicro"
			(at 315.8 284.72 0)
			(layer "B.Fab")
			(hide yes)
			(effects
				(font
					(size 1 1)
					(thickness 0.15)
				)
				(justify mirror)
			)
		)
		(property "License" "Apache-2.0"
			(at 315.8 284.72 0)
			(layer "B.Fab")
			(hide yes)
			(effects
				(font
					(size 1 1)
					(thickness 0.15)
				)
				(justify mirror)
			)
		)
		(property "MPN" "CR0402-FX-1002GLF"
			(at 315.8 284.72 0)
			(layer "B.Fab")
			(hide yes)
			(effects
				(font
					(size 1 1)
					(thickness 0.15)
				)
				(justify mirror)
			)
		)
		(property "Manufacturer" "Bourns"
			(at 315.8 284.72 0)
			(layer "B.Fab")
			(hide yes)
			(effects
				(font
					(size 1 1)
					(thickness 0.15)
				)
				(justify mirror)
			)
		)
		(property "Public" "False"
			(at 315.8 284.72 0)
			(layer "B.Fab")
			(hide yes)
			(effects
				(font
					(size 1 1)
					(thickness 0.15)
				)
				(justify mirror)
			)
		)
		(property "Tolerance" "1%"
			(at 315.8 284.72 0)
			(layer "B.Fab")
			(hide yes)
			(effects
				(font
					(size 1 1)
					(thickness 0.15)
				)
				(justify mirror)
			)
		)
		(property "Val" "10k"
			(at 315.8 284.72 0)
			(layer "B.Fab")
			(hide yes)
			(effects
				(font
					(size 1 1)
					(thickness 0.15)
				)
				(justify mirror)
			)
		)
		(sheetname "KR to SFI #1")
		(sheetfile "kr_sfi.kicad_sch")
		(attr smd)
		(fp_rect
			(start -0.925 0.47)
			(end 0.925 -0.47)
			(stroke
				(width 0.05)
				(type default)
			)
			(fill no)
			(layer "B.CrtYd")
		)
		(fp_rect
			(start -0.5 0.25)
			(end 0.5 -0.25)
			(stroke
				(width 0.15)
				(type solid)
			)
			(fill no)
			(layer "B.Fab")
		)
		(pad "1" smd roundrect
			(at -0.48 0 180)
			(size 0.59 0.64)
			(layers "B.Cu" "B.Mask" "B.Paste")
			(roundrect_rratio 0.25)
			(net 1 "GND")
			(pintype "passive")
			(teardrops
				(best_length_ratio 0.2)
				(max_length 1)
				(best_width_ratio 0.9)
				(max_width 2)
				(curved_edges yes)
				(filter_ratio 0.9)
				(enabled yes)
				(allow_two_segments yes)
				(prefer_zone_connections yes)
			)
		)
		(pad "2" smd roundrect
			(at 0.48 0 180)
			(size 0.59 0.64)
			(layers "B.Cu" "B.Mask" "B.Paste")
			(roundrect_rratio 0.25)
			(net 655 "Net-(U43C-PRTAD0)")
			(pintype "passive")
			(teardrops
				(best_length_ratio 0.2)
				(max_length 1)
				(best_width_ratio 0.9)
				(max_width 2)
				(curved_edges yes)
				(filter_ratio 0.9)
				(enabled yes)
				(allow_two_segments yes)
				(prefer_zone_connections yes)
			)
		)
	)
	(footprint "antmicro-footprints:C_0603_1608Metric"
		(layer "B.Cu")
		(at 137 161.56)
		(descr "Capacitor SMD 0603")
		(tags "capacitor 0603")
		(property "Reference" "C23"
			(at -3.35 0.45 0)
			(layer "B.SilkS")
			(effects
				(font
					(size 0.7 0.7)
					(thickness 0.15)
				)
				(justify right bottom mirror)
			)
		)
		(property "Value" "C_22u_16V_0603"
			(at -1.42757 -1.770288 0)
			(layer "B.Fab")
			(effects
				(font
					(size 0.7 0.7)
					(thickness 0.15)
				)
				(justify right bottom mirror)
			)
		)
		(property "Datasheet" "https://product.samsungsem.com/mlcc/CL10A226MO7JZN.do"
			(at 0 0 0)
			(layer "F.Fab")
			(hide yes)
			(effects
				(font
					(size 1.27 1.27)
					(thickness 0.15)
				)
			)
		)
		(property "Author" "Antmicro"
			(at 0 0 0)
			(layer "B.Fab")
			(hide yes)
			(effects
				(font
					(size 1 1)
					(thickness 0.15)
				)
				(justify mirror)
			)
		)
		(property "Dielectric" ""
			(at 0 0 0)
			(layer "B.Fab")
			(hide yes)
			(effects
				(font
					(size 1 1)
					(thickness 0.15)
				)
				(justify mirror)
			)
		)
		(property "License" "Apache-2.0"
			(at 0 0 0)
			(layer "B.Fab")
			(hide yes)
			(effects
				(font
					(size 1 1)
					(thickness 0.15)
				)
				(justify mirror)
			)
		)
		(property "MPN" "CL10A226MO7JZNC"
			(at 0 0 0)
			(layer "B.Fab")
			(hide yes)
			(effects
				(font
					(size 1 1)
					(thickness 0.15)
				)
				(justify mirror)
			)
		)
		(property "Manufacturer" "Samsung Electro-Mechanics"
			(at 0 0 0)
			(layer "B.Fab")
			(hide yes)
			(effects
				(font
					(size 1 1)
					(thickness 0.15)
				)
				(justify mirror)
			)
		)
		(property "Public" "False"
			(at 0 0 0)
			(layer "B.Fab")
			(hide yes)
			(effects
				(font
					(size 1 1)
					(thickness 0.15)
				)
				(justify mirror)
			)
		)
		(property "Val" "22u"
			(at 0 0 0)
			(layer "B.Fab")
			(hide yes)
			(effects
				(font
					(size 1 1)
					(thickness 0.15)
				)
				(justify mirror)
			)
		)
		(property "Voltage" "16V"
			(at 0 0 0)
			(layer "B.Fab")
			(hide yes)
			(effects
				(font
					(size 1 1)
					(thickness 0.15)
				)
				(justify mirror)
			)
		)
		(sheetname "2xSFP+")
		(sheetfile "2xSFP+.kicad_sch")
		(attr smd)
		(fp_line
			(start 0.15 -0.4)
			(end -0.15 -0.4)
			(stroke
				(width 0.15)
				(type solid)
			)
			(layer "B.SilkS")
		)
		(fp_line
			(start 0.15 0.4)
			(end -0.15 0.4)
			(stroke
				(width 0.15)
				(type solid)
			)
			(layer "B.SilkS")
		)
		(fp_rect
			(start -1.25 0.65)
			(end 1.25 -0.65)
			(stroke
				(width 0.05)
				(type solid)
			)
			(fill no)
			(layer "B.CrtYd")
		)
		(fp_rect
			(start -0.8 0.4)
			(end 0.8 -0.4)
			(stroke
				(width 0.15)
				(type solid)
			)
			(fill no)
			(layer "B.Fab")
		)
		(pad "1" smd roundrect
			(at -0.7 0)
			(size 0.8 1)
			(layers "B.Cu" "B.Mask" "B.Paste")
			(roundrect_rratio 0.2)
			(net 1 "GND")
			(pintype "passive")
			(teardrops
				(best_length_ratio 0.2)
				(max_length 1)
				(best_width_ratio 0.9)
				(max_width 2)
				(curved_edges yes)
				(filter_ratio 0.9)
				(enabled yes)
				(allow_two_segments yes)
				(prefer_zone_connections yes)
			)
		)
		(pad "2" smd roundrect
			(at 0.7 0)
			(size 0.8 1)
			(layers "B.Cu" "B.Mask" "B.Paste")
			(roundrect_rratio 0.2)
			(net 2 "+3V3")
			(pintype "passive")
			(teardrops
				(best_length_ratio 0.2)
				(max_length 1)
				(best_width_ratio 0.9)
				(max_width 2)
				(curved_edges yes)
				(filter_ratio 0.9)
				(enabled yes)
				(allow_two_segments yes)
				(prefer_zone_connections yes)
			)
		)
	)
	(footprint "antmicro-footprints:TP_SMD_0.75mm"
		(layer "B.Cu")
		(at 223.2 165.25)
		(property "Reference" "TP39"
			(at -0.45 -0.45 90)
			(layer "B.SilkS")
			(effects
				(font
					(size 0.7 0.7)
					(thickness 0.15)
				)
				(justify right top mirror)
			)
		)
		(property "Value" "TP_0.75mm_SMD"
			(at 0 -1.2 0)
			(layer "B.Fab")
			(effects
				(font
					(size 0.7 0.7)
					(thickness 0.15)
				)
				(justify right top mirror)
			)
		)
		(property "Author" "Antmicro"
			(at 364.2 295.32 0)
			(layer "B.Fab")
			(hide yes)
			(effects
				(font
					(size 1 1)
					(thickness 0.15)
				)
				(justify mirror)
			)
		)
		(property "License" "Apache-2.0"
			(at 364.2 295.32 0)
			(layer "B.Fab")
			(hide yes)
			(effects
				(font
					(size 1 1)
					(thickness 0.15)
				)
				(justify mirror)
			)
		)
		(property "MPN" ""
			(at 364.2 295.32 0)
			(layer "B.Fab")
			(hide yes)
			(effects
				(font
					(size 1 1)
					(thickness 0.15)
				)
				(justify mirror)
			)
		)
		(property "Manufacturer" ""
			(at 364.2 295.32 0)
			(layer "B.Fab")
			(hide yes)
			(effects
				(font
					(size 1 1)
					(thickness 0.15)
				)
				(justify mirror)
			)
		)
		(property "Public" "False"
			(at 364.2 295.32 0)
			(layer "B.Fab")
			(hide yes)
			(effects
				(font
					(size 1 1)
					(thickness 0.15)
				)
				(justify mirror)
			)
		)
		(sheetname "Com Express 7 MGMT")
		(sheetfile "com_express_7_mgmt.kicad_sch")
		(attr exclude_from_pos_files exclude_from_bom)
		(fp_circle
			(center 0 0)
			(end 0.475 0)
			(stroke
				(width 0.05)
				(type default)
			)
			(fill no)
			(layer "B.CrtYd")
		)
		(pad "1" smd circle
			(at 0 0)
			(size 0.75 0.75)
			(layers "B.Cu" "B.Mask")
			(net 342 "Net-(J12D-TPM_PP)")
			(pinfunction "1")
			(pintype "passive")
			(teardrops
				(best_length_ratio 0.4)
				(max_length 1)
				(best_width_ratio 0.9)
				(max_width 2)
				(curved_edges yes)
				(filter_ratio 0.9)
				(enabled yes)
				(allow_two_segments yes)
				(prefer_zone_connections yes)
			)
		)
	)
	(footprint "antmicro-footprints:C_0402_1005Metric"
		(layer "B.Cu")
		(at 133.29 141.36 -90)
		(descr "Capacitor SMD 0402")
		(tags "capacitor SMD 0402")
		(property "Reference" "C195"
			(at 0.8 -0.11 90)
			(layer "B.SilkS")
			(effects
				(font
					(size 0.7 0.7)
					(thickness 0.15)
				)
				(justify left bottom mirror)
			)
		)
		(property "Value" "C_100n_0402"
			(at -1.022927 -2.155213 90)
			(layer "B.Fab")
			(effects
				(font
					(size 0.7 0.7)
					(thickness 0.15)
				)
				(justify left bottom mirror)
			)
		)
		(property "Datasheet" "https://www.murata.com/products/productdetail?partno=GRM155R61H104KE14%23"
			(at 0 0 270)
			(layer "F.Fab")
			(hide yes)
			(effects
				(font
					(size 1.27 1.27)
					(thickness 0.15)
				)
			)
		)
		(property "Author" "Antmicro"
			(at -8.07 274.65 0)
			(layer "B.Fab")
			(hide yes)
			(effects
				(font
					(size 1 1)
					(thickness 0.15)
				)
				(justify mirror)
			)
		)
		(property "Dielectric" "X5R"
			(at -8.07 274.65 0)
			(layer "B.Fab")
			(hide yes)
			(effects
				(font
					(size 1 1)
					(thickness 0.15)
				)
				(justify mirror)
			)
		)
		(property "License" "Apache-2.0"
			(at -8.07 274.65 0)
			(layer "B.Fab")
			(hide yes)
			(effects
				(font
					(size 1 1)
					(thickness 0.15)
				)
				(justify mirror)
			)
		)
		(property "MPN" "GRM155R61H104KE14D"
			(at -8.07 274.65 0)
			(layer "B.Fab")
			(hide yes)
			(effects
				(font
					(size 1 1)
					(thickness 0.15)
				)
				(justify mirror)
			)
		)
		(property "Manufacturer" "Murata"
			(at -8.07 274.65 0)
			(layer "B.Fab")
			(hide yes)
			(effects
				(font
					(size 1 1)
					(thickness 0.15)
				)
				(justify mirror)
			)
		)
		(property "Public" "False"
			(at -8.07 274.65 0)
			(layer "B.Fab")
			(hide yes)
			(effects
				(font
					(size 1 1)
					(thickness 0.15)
				)
				(justify mirror)
			)
		)
		(property "Val" "100n"
			(at -8.07 274.65 0)
			(layer "B.Fab")
			(hide yes)
			(effects
				(font
					(size 1 1)
					(thickness 0.15)
				)
				(justify mirror)
			)
		)
		(property "Voltage" "50V"
			(at -8.07 274.65 0)
			(layer "B.Fab")
			(hide yes)
			(effects
				(font
					(size 1 1)
					(thickness 0.15)
				)
				(justify mirror)
			)
		)
		(sheetname "KR to SFI #2")
		(sheetfile "kr_sfi.kicad_sch")
		(attr smd)
		(fp_rect
			(start -0.925 0.47)
			(end 0.925 -0.47)
			(stroke
				(width 0.05)
				(type default)
			)
			(fill no)
			(layer "B.CrtYd")
		)
		(fp_line
			(start -0.494 0.25)
			(end -0.494 -0.248)
			(stroke
				(width 0.15)
				(type solid)
			)
			(layer "B.Fab")
		)
		(fp_line
			(start 0.504 0.25)
			(end -0.494 0.25)
			(stroke
				(width 0.15)
				(type solid)
			)
			(layer "B.Fab")
		)
		(fp_line
			(start -0.494 -0.248)
			(end 0.504 -0.248)
			(stroke
				(width 0.15)
				(type solid)
			)
			(layer "B.Fab")
		)
		(fp_line
			(start 0.504 -0.248)
			(end 0.504 0.25)
			(stroke
				(width 0.15)
				(type solid)
			)
			(layer "B.Fab")
		)
		(pad "1" smd roundrect
			(at -0.48 0 270)
			(size 0.59 0.64)
			(layers "B.Cu" "B.Mask" "B.Paste")
			(roundrect_rratio 0.25)
			(net 1 "GND")
			(pintype "passive")
			(teardrops
				(best_length_ratio 0.2)
				(max_length 1)
				(best_width_ratio 0.9)
				(max_width 2)
				(curved_edges yes)
				(filter_ratio 0.9)
				(enabled yes)
				(allow_two_segments yes)
				(prefer_zone_connections yes)
			)
		)
		(pad "2" smd roundrect
			(at 0.48 0 270)
			(size 0.59 0.64)
			(layers "B.Cu" "B.Mask" "B.Paste")
			(roundrect_rratio 0.25)
			(net 74 "+1V0")
			(pintype "passive")
			(teardrops
				(best_length_ratio 0.2)
				(max_length 1)
				(best_width_ratio 0.9)
				(max_width 2)
				(curved_edges yes)
				(filter_ratio 0.9)
				(enabled yes)
				(allow_two_segments yes)
				(prefer_zone_connections yes)
			)
		)
	)
	(footprint "antmicro-footprints:C_0402_1005Metric"
		(layer "B.Cu")
		(at 151.45 139.36 -90)
		(descr "Capacitor SMD 0402")
		(tags "capacitor SMD 0402")
		(property "Reference" "C163"
			(at -1.05 -1.4 90)
			(layer "B.SilkS")
			(effects
				(font
					(size 0.7 0.7)
					(thickness 0.15)
				)
				(justify left bottom mirror)
			)
		)
		(property "Value" "C_100n_0402"
			(at -1.022927 -2.155213 90)
			(layer "B.Fab")
			(effects
				(font
					(size 0.7 0.7)
					(thickness 0.15)
				)
				(justify left bottom mirror)
			)
		)
		(property "Datasheet" "https://www.murata.com/products/productdetail?partno=GRM155R61H104KE14%23"
			(at 0 0 270)
			(layer "F.Fab")
			(hide yes)
			(effects
				(font
					(size 1.27 1.27)
					(thickness 0.15)
				)
			)
		)
		(property "Author" "Antmicro"
			(at 12.09 290.81 0)
			(layer "B.Fab")
			(hide yes)
			(effects
				(font
					(size 1 1)
					(thickness 0.15)
				)
				(justify mirror)
			)
		)
		(property "Dielectric" "X5R"
			(at 12.09 290.81 0)
			(layer "B.Fab")
			(hide yes)
			(effects
				(font
					(size 1 1)
					(thickness 0.15)
				)
				(justify mirror)
			)
		)
		(property "License" "Apache-2.0"
			(at 12.09 290.81 0)
			(layer "B.Fab")
			(hide yes)
			(effects
				(font
					(size 1 1)
					(thickness 0.15)
				)
				(justify mirror)
			)
		)
		(property "MPN" "GRM155R61H104KE14D"
			(at 12.09 290.81 0)
			(layer "B.Fab")
			(hide yes)
			(effects
				(font
					(size 1 1)
					(thickness 0.15)
				)
				(justify mirror)
			)
		)
		(property "Manufacturer" "Murata"
			(at 12.09 290.81 0)
			(layer "B.Fab")
			(hide yes)
			(effects
				(font
					(size 1 1)
					(thickness 0.15)
				)
				(justify mirror)
			)
		)
		(property "Public" "False"
			(at 12.09 290.81 0)
			(layer "B.Fab")
			(hide yes)
			(effects
				(font
					(size 1 1)
					(thickness 0.15)
				)
				(justify mirror)
			)
		)
		(property "Val" "100n"
			(at 12.09 290.81 0)
			(layer "B.Fab")
			(hide yes)
			(effects
				(font
					(size 1 1)
					(thickness 0.15)
				)
				(justify mirror)
			)
		)
		(property "Voltage" "50V"
			(at 12.09 290.81 0)
			(layer "B.Fab")
			(hide yes)
			(effects
				(font
					(size 1 1)
					(thickness 0.15)
				)
				(justify mirror)
			)
		)
		(sheetname "KR to SFI #1")
		(sheetfile "kr_sfi.kicad_sch")
		(attr smd)
		(fp_rect
			(start -0.925 0.47)
			(end 0.925 -0.47)
			(stroke
				(width 0.05)
				(type default)
			)
			(fill no)
			(layer "B.CrtYd")
		)
		(fp_line
			(start -0.494 0.25)
			(end -0.494 -0.248)
			(stroke
				(width 0.15)
				(type solid)
			)
			(layer "B.Fab")
		)
		(fp_line
			(start 0.504 0.25)
			(end -0.494 0.25)
			(stroke
				(width 0.15)
				(type solid)
			)
			(layer "B.Fab")
		)
		(fp_line
			(start -0.494 -0.248)
			(end 0.504 -0.248)
			(stroke
				(width 0.15)
				(type solid)
			)
			(layer "B.Fab")
		)
		(fp_line
			(start 0.504 -0.248)
			(end 0.504 0.25)
			(stroke
				(width 0.15)
				(type solid)
			)
			(layer "B.Fab")
		)
		(pad "1" smd roundrect
			(at -0.48 0 270)
			(size 0.59 0.64)
			(layers "B.Cu" "B.Mask" "B.Paste")
			(roundrect_rratio 0.25)
			(net 1 "GND")
			(pintype "passive")
			(teardrops
				(best_length_ratio 0.2)
				(max_length 1)
				(best_width_ratio 0.9)
				(max_width 2)
				(curved_edges yes)
				(filter_ratio 0.9)
				(enabled yes)
				(allow_two_segments yes)
				(prefer_zone_connections yes)
			)
		)
		(pad "2" smd roundrect
			(at 0.48 0 270)
			(size 0.59 0.64)
			(layers "B.Cu" "B.Mask" "B.Paste")
			(roundrect_rratio 0.25)
			(net 74 "+1V0")
			(pintype "passive")
			(teardrops
				(best_length_ratio 0.2)
				(max_length 1)
				(best_width_ratio 0.9)
				(max_width 2)
				(curved_edges yes)
				(filter_ratio 0.9)
				(enabled yes)
				(allow_two_segments yes)
				(prefer_zone_connections yes)
			)
		)
	)
	(footprint "antmicro-footprints:R_0805_2012Metric"
		(layer "B.Cu")
		(at 105.04 152.65 180)
		(property "Reference" "R82"
			(at -4 -0.5 0)
			(layer "B.SilkS")
			(effects
				(font
					(size 0.7 0.7)
					(thickness 0.15)
				)
				(justify left bottom mirror)
			)
		)
		(property "Value" "R_0R001_0805"
			(at 0 -1.8 0)
			(layer "B.Fab")
			(effects
				(font
					(size 0.7 0.7)
					(thickness 0.15)
				)
				(justify left bottom mirror)
			)
		)
		(property "Datasheet" "https://www.eaton.com/content/dam/eaton/products/electronic-components/resources/data-sheet/eaton-msma-automotive-smd-current-sense-resistor-metal-strip-data-sheet-elx1179.pdf"
			(at 0 0 180)
			(layer "F.Fab")
			(hide yes)
			(effects
				(font
					(size 1.27 1.27)
					(thickness 0.15)
				)
			)
		)
		(property "Author" "Antmicro"
			(at 210.08 305.67 0)
			(layer "B.Fab")
			(hide yes)
			(effects
				(font
					(size 1 1)
					(thickness 0.15)
				)
				(justify mirror)
			)
		)
		(property "License" "Apache-2.0"
			(at 210.08 305.67 0)
			(layer "B.Fab")
			(hide yes)
			(effects
				(font
					(size 1 1)
					(thickness 0.15)
				)
				(justify mirror)
			)
		)
		(property "MPN" "MSMA0805R0010FSM"
			(at 210.08 305.67 0)
			(layer "B.Fab")
			(hide yes)
			(effects
				(font
					(size 1 1)
					(thickness 0.15)
				)
				(justify mirror)
			)
		)
		(property "Manufacturer" "Eaton"
			(at 210.08 305.67 0)
			(layer "B.Fab")
			(hide yes)
			(effects
				(font
					(size 1 1)
					(thickness 0.15)
				)
				(justify mirror)
			)
		)
		(property "Public" "False"
			(at 210.08 305.67 0)
			(layer "B.Fab")
			(hide yes)
			(effects
				(font
					(size 1 1)
					(thickness 0.15)
				)
				(justify mirror)
			)
		)
		(property "Tolerance" "1%"
			(at 210.08 305.67 0)
			(layer "B.Fab")
			(hide yes)
			(effects
				(font
					(size 1 1)
					(thickness 0.15)
				)
				(justify mirror)
			)
		)
		(property "Val" "0R001"
			(at 210.08 305.67 0)
			(layer "B.Fab")
			(hide yes)
			(effects
				(font
					(size 1 1)
					(thickness 0.15)
				)
				(justify mirror)
			)
		)
		(sheetname "OCuLink")
		(sheetfile "oculink.kicad_sch")
		(attr smd)
		(fp_line
			(start 0.298 0.701)
			(end -0.3 0.701)
			(stroke
				(width 0.15)
				(type solid)
			)
			(layer "B.SilkS")
		)
		(fp_line
			(start 0.28 -0.699)
			(end -0.32 -0.699)
			(stroke
				(width 0.15)
				(type solid)
			)
			(layer "B.SilkS")
		)
		(fp_rect
			(start 1.95 0.9)
			(end -1.95 -0.9)
			(stroke
				(width 0.05)
				(type default)
			)
			(fill no)
			(layer "B.CrtYd")
		)
		(fp_line
			(start 0.949 0.682)
			(end -0.951 0.682)
			(stroke
				(width 0.15)
				(type solid)
			)
			(layer "B.Fab")
		)
		(fp_line
			(start 0.949 -0.675)
			(end 0.949 0.677)
			(stroke
				(width 0.15)
				(type solid)
			)
			(layer "B.Fab")
		)
		(fp_line
			(start 0.949 -0.68)
			(end -0.951 -0.68)
			(stroke
				(width 0.15)
				(type solid)
			)
			(layer "B.Fab")
		)
		(fp_line
			(start -0.951 -0.675)
			(end -0.951 0.677)
			(stroke
				(width 0.15)
				(type solid)
			)
			(layer "B.Fab")
		)
		(pad "1" smd roundrect
			(at -1.1 0 180)
			(size 1.2 1.3)
			(layers "B.Cu" "B.Mask" "B.Paste")
			(roundrect_rratio 0.25)
			(net 52 "+5V")
			(pintype "passive")
			(teardrops
				(best_length_ratio 0.2)
				(max_length 1)
				(best_width_ratio 0.9)
				(max_width 2)
				(curved_edges yes)
				(filter_ratio 0.9)
				(enabled yes)
				(allow_two_segments yes)
				(prefer_zone_connections yes)
			)
		)
		(pad "2" smd roundrect
			(at 1.1 0 180)
			(size 1.2 1.3)
			(layers "B.Cu" "B.Mask" "B.Paste")
			(roundrect_rratio 0.25)
			(net 61 "/OCuLink/5V_CONN0")
			(pintype "passive")
			(teardrops
				(best_length_ratio 0.2)
				(max_length 1)
				(best_width_ratio 0.9)
				(max_width 2)
				(curved_edges yes)
				(filter_ratio 0.9)
				(enabled yes)
				(allow_two_segments yes)
				(prefer_zone_connections yes)
			)
		)
	)
	(footprint "antmicro-footprints:R_0402_1005Metric"
		(layer "B.Cu")
		(at 148.05 169.16 -90)
		(descr "Resistor SMD 0402")
		(tags "resistor SMD 0402")
		(property "Reference" "R57"
			(at -3.9 13.5 270)
			(layer "B.SilkS")
			(effects
				(font
					(size 0.7 0.7)
					(thickness 0.15)
				)
				(justify left bottom mirror)
			)
		)
		(property "Value" "R_0R_0402"
			(at -1.011843 -1.772047 90)
			(layer "B.Fab")
			(effects
				(font
					(size 0.7 0.7)
					(thickness 0.15)
				)
				(justify left bottom mirror)
			)
		)
		(property "Datasheet" "https://industrial.panasonic.com/cdbs/www-data/pdf/RDA0000/AOA0000C301.pdf"
			(at 0 0 270)
			(layer "F.Fab")
			(hide yes)
			(effects
				(font
					(size 1.27 1.27)
					(thickness 0.15)
				)
			)
		)
		(property "Author" "Antmicro"
			(at -21.11 317.21 0)
			(layer "B.Fab")
			(hide yes)
			(effects
				(font
					(size 1 1)
					(thickness 0.15)
				)
				(justify mirror)
			)
		)
		(property "Current" "1A"
			(at -21.11 317.21 0)
			(layer "B.Fab")
			(hide yes)
			(effects
				(font
					(size 1 1)
					(thickness 0.15)
				)
				(justify mirror)
			)
		)
		(property "License" "Apache-2.0"
			(at -21.11 317.21 0)
			(layer "B.Fab")
			(hide yes)
			(effects
				(font
					(size 1 1)
					(thickness 0.15)
				)
				(justify mirror)
			)
		)
		(property "MPN" "ERJ2GE0R00X"
			(at -21.11 317.21 0)
			(layer "B.Fab")
			(hide yes)
			(effects
				(font
					(size 1 1)
					(thickness 0.15)
				)
				(justify mirror)
			)
		)
		(property "Manufacturer" "Panasonic"
			(at -21.11 317.21 0)
			(layer "B.Fab")
			(hide yes)
			(effects
				(font
					(size 1 1)
					(thickness 0.15)
				)
				(justify mirror)
			)
		)
		(property "Public" "False"
			(at -21.11 317.21 0)
			(layer "B.Fab")
			(hide yes)
			(effects
				(font
					(size 1 1)
					(thickness 0.15)
				)
				(justify mirror)
			)
		)
		(property "Tolerance" ""
			(at -21.11 317.21 0)
			(layer "B.Fab")
			(hide yes)
			(effects
				(font
					(size 1 1)
					(thickness 0.15)
				)
				(justify mirror)
			)
		)
		(property "Val" "0R"
			(at -21.11 317.21 0)
			(layer "B.Fab")
			(hide yes)
			(effects
				(font
					(size 1 1)
					(thickness 0.15)
				)
				(justify mirror)
			)
		)
		(sheetname "2xSFP+")
		(sheetfile "2xSFP+.kicad_sch")
		(attr smd)
		(fp_rect
			(start -0.925 0.47)
			(end 0.925 -0.47)
			(stroke
				(width 0.05)
				(type default)
			)
			(fill no)
			(layer "B.CrtYd")
		)
		(fp_rect
			(start -0.5 0.25)
			(end 0.5 -0.25)
			(stroke
				(width 0.15)
				(type solid)
			)
			(fill no)
			(layer "B.Fab")
		)
		(pad "1" smd roundrect
			(at -0.48 0 270)
			(size 0.59 0.64)
			(layers "B.Cu" "B.Mask" "B.Paste")
			(roundrect_rratio 0.25)
			(net 163 "Net-(J2A-TX_{DISABLE})")
			(pintype "passive")
			(teardrops
				(best_length_ratio 0.2)
				(max_length 1)
				(best_width_ratio 0.9)
				(max_width 2)
				(curved_edges yes)
				(filter_ratio 0.9)
				(enabled yes)
				(allow_two_segments yes)
				(prefer_zone_connections yes)
			)
		)
		(pad "2" smd roundrect
			(at 0.48 0 270)
			(size 0.59 0.64)
			(layers "B.Cu" "B.Mask" "B.Paste")
			(roundrect_rratio 0.25)
			(net 1 "GND")
			(pintype "passive")
			(teardrops
				(best_length_ratio 0.2)
				(max_length 1)
				(best_width_ratio 0.9)
				(max_width 2)
				(curved_edges yes)
				(filter_ratio 0.9)
				(enabled yes)
				(allow_two_segments yes)
				(prefer_zone_connections yes)
			)
		)
	)
	(footprint "antmicro-footprints:C_0603_1608Metric"
		(layer "B.Cu")
		(at 286.75 79.12 -90)
		(descr "Capacitor SMD 0603")
		(tags "capacitor 0603")
		(property "Reference" "C75"
			(at -3.36 -0.42 90)
			(layer "B.SilkS")
			(effects
				(font
					(size 0.7 0.7)
					(thickness 0.15)
				)
				(justify left bottom mirror)
			)
		)
		(property "Value" "C_22u_16V_0603"
			(at -1.42757 -1.770288 90)
			(layer "B.Fab")
			(effects
				(font
					(size 0.7 0.7)
					(thickness 0.15)
				)
				(justify left bottom mirror)
			)
		)
		(property "Datasheet" "https://product.samsungsem.com/mlcc/CL10A226MO7JZN.do"
			(at 0 0 270)
			(layer "F.Fab")
			(hide yes)
			(effects
				(font
					(size 1.27 1.27)
					(thickness 0.15)
				)
			)
		)
		(property "Author" "Antmicro"
			(at 207.63 365.87 0)
			(layer "B.Fab")
			(hide yes)
			(effects
				(font
					(size 1 1)
					(thickness 0.15)
				)
				(justify mirror)
			)
		)
		(property "Dielectric" ""
			(at 207.63 365.87 0)
			(layer "B.Fab")
			(hide yes)
			(effects
				(font
					(size 1 1)
					(thickness 0.15)
				)
				(justify mirror)
			)
		)
		(property "License" "Apache-2.0"
			(at 207.63 365.87 0)
			(layer "B.Fab")
			(hide yes)
			(effects
				(font
					(size 1 1)
					(thickness 0.15)
				)
				(justify mirror)
			)
		)
		(property "MPN" "CL10A226MO7JZNC"
			(at 207.63 365.87 0)
			(layer "B.Fab")
			(hide yes)
			(effects
				(font
					(size 1 1)
					(thickness 0.15)
				)
				(justify mirror)
			)
		)
		(property "Manufacturer" "Samsung Electro-Mechanics"
			(at 207.63 365.87 0)
			(layer "B.Fab")
			(hide yes)
			(effects
				(font
					(size 1 1)
					(thickness 0.15)
				)
				(justify mirror)
			)
		)
		(property "Public" "False"
			(at 207.63 365.87 0)
			(layer "B.Fab")
			(hide yes)
			(effects
				(font
					(size 1 1)
					(thickness 0.15)
				)
				(justify mirror)
			)
		)
		(property "Val" "22u"
			(at 207.63 365.87 0)
			(layer "B.Fab")
			(hide yes)
			(effects
				(font
					(size 1 1)
					(thickness 0.15)
				)
				(justify mirror)
			)
		)
		(property "Voltage" "16V"
			(at 207.63 365.87 0)
			(layer "B.Fab")
			(hide yes)
			(effects
				(font
					(size 1 1)
					(thickness 0.15)
				)
				(justify mirror)
			)
		)
		(sheetname "M.2 key M #2")
		(sheetfile "m2keym.kicad_sch")
		(attr smd)
		(fp_line
			(start 0.15 0.4)
			(end -0.15 0.4)
			(stroke
				(width 0.15)
				(type solid)
			)
			(layer "B.SilkS")
		)
		(fp_line
			(start 0.15 -0.4)
			(end -0.15 -0.4)
			(stroke
				(width 0.15)
				(type solid)
			)
			(layer "B.SilkS")
		)
		(fp_rect
			(start -1.25 0.65)
			(end 1.25 -0.65)
			(stroke
				(width 0.05)
				(type solid)
			)
			(fill no)
			(layer "B.CrtYd")
		)
		(fp_rect
			(start -0.8 0.4)
			(end 0.8 -0.4)
			(stroke
				(width 0.15)
				(type solid)
			)
			(fill no)
			(layer "B.Fab")
		)
		(pad "1" smd roundrect
			(at -0.7 0 270)
			(size 0.8 1)
			(layers "B.Cu" "B.Mask" "B.Paste")
			(roundrect_rratio 0.2)
			(net 1 "GND")
			(pintype "passive")
			(teardrops
				(best_length_ratio 0.2)
				(max_length 1)
				(best_width_ratio 0.9)
				(max_width 2)
				(curved_edges yes)
				(filter_ratio 0.9)
				(enabled yes)
				(allow_two_segments yes)
				(prefer_zone_connections yes)
			)
		)
		(pad "2" smd roundrect
			(at 0.7 0 270)
			(size 0.8 1)
			(layers "B.Cu" "B.Mask" "B.Paste")
			(roundrect_rratio 0.2)
			(net 970 "/M.2 key M #2/M2_3V3")
			(pintype "passive")
			(teardrops
				(best_length_ratio 0.2)
				(max_length 1)
				(best_width_ratio 0.9)
				(max_width 2)
				(curved_edges yes)
				(filter_ratio 0.9)
				(enabled yes)
				(allow_two_segments yes)
				(prefer_zone_connections yes)
			)
		)
	)
	(footprint "antmicro-footprints:R_0402_1005Metric"
		(layer "B.Cu")
		(at 121.7 163.56 180)
		(descr "Resistor SMD 0402")
		(tags "resistor SMD 0402")
		(property "Reference" "R76"
			(at -1.1 -1.4 0)
			(layer "B.SilkS")
			(effects
				(font
					(size 0.7 0.7)
					(thickness 0.15)
				)
				(justify left bottom mirror)
			)
		)
		(property "Value" "R_0R_0402"
			(at -1.011843 -1.772047 0)
			(layer "B.Fab")
			(effects
				(font
					(size 0.7 0.7)
					(thickness 0.15)
				)
				(justify left bottom mirror)
			)
		)
		(property "Datasheet" "https://industrial.panasonic.com/cdbs/www-data/pdf/RDA0000/AOA0000C301.pdf"
			(at 0 0 180)
			(layer "F.Fab")
			(hide yes)
			(effects
				(font
					(size 1.27 1.27)
					(thickness 0.15)
				)
			)
		)
		(property "Author" "Antmicro"
			(at 243.4 327.12 0)
			(layer "B.Fab")
			(hide yes)
			(effects
				(font
					(size 1 1)
					(thickness 0.15)
				)
				(justify mirror)
			)
		)
		(property "Current" "1A"
			(at 243.4 327.12 0)
			(layer "B.Fab")
			(hide yes)
			(effects
				(font
					(size 1 1)
					(thickness 0.15)
				)
				(justify mirror)
			)
		)
		(property "License" "Apache-2.0"
			(at 243.4 327.12 0)
			(layer "B.Fab")
			(hide yes)
			(effects
				(font
					(size 1 1)
					(thickness 0.15)
				)
				(justify mirror)
			)
		)
		(property "MPN" "ERJ2GE0R00X"
			(at 243.4 327.12 0)
			(layer "B.Fab")
			(hide yes)
			(effects
				(font
					(size 1 1)
					(thickness 0.15)
				)
				(justify mirror)
			)
		)
		(property "Manufacturer" "Panasonic"
			(at 243.4 327.12 0)
			(layer "B.Fab")
			(hide yes)
			(effects
				(font
					(size 1 1)
					(thickness 0.15)
				)
				(justify mirror)
			)
		)
		(property "Public" "False"
			(at 243.4 327.12 0)
			(layer "B.Fab")
			(hide yes)
			(effects
				(font
					(size 1 1)
					(thickness 0.15)
				)
				(justify mirror)
			)
		)
		(property "Tolerance" ""
			(at 243.4 327.12 0)
			(layer "B.Fab")
			(hide yes)
			(effects
				(font
					(size 1 1)
					(thickness 0.15)
				)
				(justify mirror)
			)
		)
		(property "Val" "0R"
			(at 243.4 327.12 0)
			(layer "B.Fab")
			(hide yes)
			(effects
				(font
					(size 1 1)
					(thickness 0.15)
				)
				(justify mirror)
			)
		)
		(sheetname "OCuLink")
		(sheetfile "oculink.kicad_sch")
		(attr smd)
		(fp_rect
			(start -0.925 0.47)
			(end 0.925 -0.47)
			(stroke
				(width 0.05)
				(type default)
			)
			(fill no)
			(layer "B.CrtYd")
		)
		(fp_rect
			(start -0.5 0.25)
			(end 0.5 -0.25)
			(stroke
				(width 0.15)
				(type solid)
			)
			(fill no)
			(layer "B.Fab")
		)
		(pad "1" smd roundrect
			(at -0.48 0 180)
			(size 0.59 0.64)
			(layers "B.Cu" "B.Mask" "B.Paste")
			(roundrect_rratio 0.25)
			(net 528 "/Backplane/~{PERST}")
			(pintype "passive")
			(teardrops
				(best_length_ratio 0.2)
				(max_length 1)
				(best_width_ratio 0.9)
				(max_width 2)
				(curved_edges yes)
				(filter_ratio 0.9)
				(enabled yes)
				(allow_two_segments yes)
				(prefer_zone_connections yes)
			)
		)
		(pad "2" smd roundrect
			(at 0.48 0 180)
			(size 0.59 0.64)
			(layers "B.Cu" "B.Mask" "B.Paste")
			(roundrect_rratio 0.25)
			(net 200 "/OCuLink/~{PERST_D0}")
			(pintype "passive")
			(teardrops
				(best_length_ratio 0.2)
				(max_length 1)
				(best_width_ratio 0.9)
				(max_width 2)
				(curved_edges yes)
				(filter_ratio 0.9)
				(enabled yes)
				(allow_two_segments yes)
				(prefer_zone_connections yes)
			)
		)
	)
	(footprint "antmicro-footprints:USON-10_2.5x1mm_P0.5mm"
		(layer "B.Cu")
		(at 104.77 165.61)
		(descr "USON-10 2.5x1mm_ Pitch 0.5mm")
		(tags "USON-10 2.5x1mm Pitch 0.5mm")
		(property "Reference" "U10"
			(at 1.72 1.05 90)
			(layer "B.SilkS")
			(effects
				(font
					(size 0.7 0.7)
					(thickness 0.15)
				)
				(justify right bottom mirror)
			)
		)
		(property "Value" "ESD204DQAR"
			(at 0.018 -2.499 0)
			(layer "B.Fab")
			(effects
				(font
					(size 0.7 0.7)
					(thickness 0.15)
				)
				(justify right bottom mirror)
			)
		)
		(property "Datasheet" "https://www.ti.com/lit/ds/symlink/esd204.pdf?ts=1706004844383&ref_url=https%253A%252F%252Fwww.ti.com%252Finterface%252Fdiodes%252Fesd-protection-diodes%252Fproducts.html"
			(at 0 0 0)
			(layer "F.Fab")
			(hide yes)
			(effects
				(font
					(size 1.27 1.27)
					(thickness 0.15)
				)
			)
		)
		(property "Author" "Antmicro"
			(at 0 0 0)
			(layer "B.Fab")
			(hide yes)
			(effects
				(font
					(size 1 1)
					(thickness 0.15)
				)
				(justify mirror)
			)
		)
		(property "License" "Apache-2.0"
			(at 0 0 0)
			(layer "B.Fab")
			(hide yes)
			(effects
				(font
					(size 1 1)
					(thickness 0.15)
				)
				(justify mirror)
			)
		)
		(property "MPN" "ESD204DQAR"
			(at 0 0 0)
			(layer "B.Fab")
			(hide yes)
			(effects
				(font
					(size 1 1)
					(thickness 0.15)
				)
				(justify mirror)
			)
		)
		(property "Manufacturer" "Texas Instruments"
			(at 0 0 0)
			(layer "B.Fab")
			(hide yes)
			(effects
				(font
					(size 1 1)
					(thickness 0.15)
				)
				(justify mirror)
			)
		)
		(sheetname "OCuLink")
		(sheetfile "oculink.kicad_sch")
		(attr smd)
		(fp_line
			(start -0.5 -1.398)
			(end 0.498 -1.398)
			(stroke
				(width 0.15)
				(type solid)
			)
			(layer "B.SilkS")
		)
		(fp_line
			(start -0.5 1.401)
			(end 0.498 1.401)
			(stroke
				(width 0.15)
				(type solid)
			)
			(layer "B.SilkS")
		)
		(fp_circle
			(center -0.68 1.27)
			(end -0.63 1.27)
			(stroke
				(width 0.15)
				(type solid)
			)
			(fill yes)
			(layer "B.SilkS")
		)
		(fp_rect
			(start -0.8 1.5)
			(end 0.8 -1.499)
			(stroke
				(width 0.05)
				(type solid)
			)
			(fill no)
			(layer "B.CrtYd")
		)
		(fp_line
			(start -0.5 -1.249)
			(end -0.5 1)
			(stroke
				(width 0.15)
				(type solid)
			)
			(layer "B.Fab")
		)
		(fp_line
			(start -0.5 1)
			(end -0.25 1.25)
			(stroke
				(width 0.15)
				(type solid)
			)
			(layer "B.Fab")
		)
		(fp_line
			(start -0.25 1.25)
			(end 0.498 1.25)
			(stroke
				(width 0.15)
				(type solid)
			)
			(layer "B.Fab")
		)
		(fp_line
			(start 0.498 -1.249)
			(end -0.5 -1.249)
			(stroke
				(width 0.15)
				(type solid)
			)
			(layer "B.Fab")
		)
		(fp_line
			(start 0.498 -1.249)
			(end 0.498 1.25)
			(stroke
				(width 0.15)
				(type solid)
			)
			(layer "B.Fab")
		)
		(pad "1" smd roundrect
			(at -0.387 1 90)
			(size 0.25 0.55)
			(layers "B.Cu" "B.Mask" "B.Paste")
			(roundrect_rratio 0.25)
			(net 100 "/OCuLink/PCIe_{x4}.TX0+")
			(pintype "passive")
			(teardrops
				(best_length_ratio 0.2)
				(max_length 1)
				(best_width_ratio 0.9)
				(max_width 2)
				(curved_edges yes)
				(filter_ratio 0.9)
				(enabled yes)
				(allow_two_segments yes)
				(prefer_zone_connections yes)
			)
		)
		(pad "2" smd roundrect
			(at -0.387 0.5 90)
			(size 0.25 0.55)
			(layers "B.Cu" "B.Mask" "B.Paste")
			(roundrect_rratio 0.25)
			(net 95 "/OCuLink/PCIe_{x4}.TX0-")
			(pintype "passive")
			(teardrops
				(best_length_ratio 0.2)
				(max_length 1)
				(best_width_ratio 0.9)
				(max_width 2)
				(curved_edges yes)
				(filter_ratio 0.9)
				(enabled yes)
				(allow_two_segments yes)
				(prefer_zone_connections yes)
			)
		)
		(pad "3" smd roundrect
			(at -0.387 0 90)
			(size 0.4 0.55)
			(layers "B.Cu" "B.Mask" "B.Paste")
			(roundrect_rratio 0.25)
			(net 1 "GND")
			(pintype "power_in")
			(teardrops
				(best_length_ratio 0.2)
				(max_length 1)
				(best_width_ratio 0.9)
				(max_width 2)
				(curved_edges yes)
				(filter_ratio 0.9)
				(enabled yes)
				(allow_two_segments yes)
				(prefer_zone_connections yes)
			)
		)
		(pad "4" smd roundrect
			(at -0.387 -0.498 90)
			(size 0.25 0.55)
			(layers "B.Cu" "B.Mask" "B.Paste")
			(roundrect_rratio 0.25)
			(net 102 "/OCuLink/PCIe_{x4}.TX1+")
			(pintype "passive")
			(teardrops
				(best_length_ratio 0.2)
				(max_length 1)
				(best_width_ratio 0.9)
				(max_width 2)
				(curved_edges yes)
				(filter_ratio 0.9)
				(enabled yes)
				(allow_two_segments yes)
				(prefer_zone_connections yes)
			)
		)
		(pad "5" smd roundrect
			(at -0.387 -0.998 90)
			(size 0.25 0.55)
			(layers "B.Cu" "B.Mask" "B.Paste")
			(roundrect_rratio 0.25)
			(net 96 "/OCuLink/PCIe_{x4}.TX1-")
			(pintype "passive")
			(teardrops
				(best_length_ratio 0.2)
				(max_length 1)
				(best_width_ratio 0.9)
				(max_width 2)
				(curved_edges yes)
				(filter_ratio 0.9)
				(enabled yes)
				(allow_two_segments yes)
				(prefer_zone_connections yes)
			)
		)
		(pad "6" smd roundrect
			(at 0.385 -0.998 90)
			(size 0.25 0.55)
			(layers "B.Cu" "B.Mask" "B.Paste")
			(roundrect_rratio 0.25)
			(net 96 "/OCuLink/PCIe_{x4}.TX1-")
			(pintype "passive")
			(teardrops
				(best_length_ratio 0.2)
				(max_length 1)
				(best_width_ratio 0.9)
				(max_width 2)
				(curved_edges yes)
				(filter_ratio 0.9)
				(enabled yes)
				(allow_two_segments yes)
				(prefer_zone_connections yes)
			)
		)
		(pad "7" smd roundrect
			(at 0.385 -0.498 90)
			(size 0.25 0.55)
			(layers "B.Cu" "B.Mask" "B.Paste")
			(roundrect_rratio 0.25)
			(net 102 "/OCuLink/PCIe_{x4}.TX1+")
			(pintype "passive")
			(teardrops
				(best_length_ratio 0.2)
				(max_length 1)
				(best_width_ratio 0.9)
				(max_width 2)
				(curved_edges yes)
				(filter_ratio 0.9)
				(enabled yes)
				(allow_two_segments yes)
				(prefer_zone_connections yes)
			)
		)
		(pad "8" smd roundrect
			(at 0.385 0 90)
			(size 0.4 0.55)
			(layers "B.Cu" "B.Mask" "B.Paste")
			(roundrect_rratio 0.25)
			(net 1 "GND")
			(pintype "passive")
			(teardrops
				(best_length_ratio 0.2)
				(max_length 1)
				(best_width_ratio 0.9)
				(max_width 2)
				(curved_edges yes)
				(filter_ratio 0.9)
				(enabled yes)
				(allow_two_segments yes)
				(prefer_zone_connections yes)
			)
		)
		(pad "9" smd roundrect
			(at 0.385 0.5 90)
			(size 0.25 0.55)
			(layers "B.Cu" "B.Mask" "B.Paste")
			(roundrect_rratio 0.25)
			(net 95 "/OCuLink/PCIe_{x4}.TX0-")
			(pintype "passive")
			(teardrops
				(best_length_ratio 0.2)
				(max_length 1)
				(best_width_ratio 0.9)
				(max_width 2)
				(curved_edges yes)
				(filter_ratio 0.9)
				(enabled yes)
				(allow_two_segments yes)
				(prefer_zone_connections yes)
			)
		)
		(pad "10" smd roundrect
			(at 0.385 1 90)
			(size 0.25 0.55)
			(layers "B.Cu" "B.Mask" "B.Paste")
			(roundrect_rratio 0.25)
			(net 100 "/OCuLink/PCIe_{x4}.TX0+")
			(pintype "passive")
			(teardrops
				(best_length_ratio 0.2)
				(max_length 1)
				(best_width_ratio 0.9)
				(max_width 2)
				(curved_edges yes)
				(filter_ratio 0.9)
				(enabled yes)
				(allow_two_segments yes)
				(prefer_zone_connections yes)
			)
		)
	)
	(footprint "antmicro-footprints:R_0402_1005Metric"
		(layer "B.Cu")
		(at 112.4 69.86 -90)
		(descr "Resistor SMD 0402")
		(tags "resistor SMD 0402")
		(property "Reference" "R72"
			(at 0.8 -0.45 90)
			(layer "B.SilkS")
			(effects
				(font
					(size 0.7 0.7)
					(thickness 0.15)
				)
				(justify left bottom mirror)
			)
		)
		(property "Value" "R_220R_0402"
			(at -1.011843 -1.772047 90)
			(layer "B.Fab")
			(effects
				(font
					(size 0.7 0.7)
					(thickness 0.15)
				)
				(justify left bottom mirror)
			)
		)
		(property "Datasheet" "https://www.bourns.com/docs/product-datasheets/cr.pdf"
			(at 0 0 270)
			(layer "F.Fab")
			(hide yes)
			(effects
				(font
					(size 1.27 1.27)
					(thickness 0.15)
				)
			)
		)
		(property "Author" "Antmicro"
			(at 42.54 182.26 0)
			(layer "B.Fab")
			(hide yes)
			(effects
				(font
					(size 1 1)
					(thickness 0.15)
				)
				(justify mirror)
			)
		)
		(property "License" "Apache-2.0"
			(at 42.54 182.26 0)
			(layer "B.Fab")
			(hide yes)
			(effects
				(font
					(size 1 1)
					(thickness 0.15)
				)
				(justify mirror)
			)
		)
		(property "MPN" "CR0402-FX-2200GLF"
			(at 42.54 182.26 0)
			(layer "B.Fab")
			(hide yes)
			(effects
				(font
					(size 1 1)
					(thickness 0.15)
				)
				(justify mirror)
			)
		)
		(property "Manufacturer" "Bourns"
			(at 42.54 182.26 0)
			(layer "B.Fab")
			(hide yes)
			(effects
				(font
					(size 1 1)
					(thickness 0.15)
				)
				(justify mirror)
			)
		)
		(property "Public" "False"
			(at 42.54 182.26 0)
			(layer "B.Fab")
			(hide yes)
			(effects
				(font
					(size 1 1)
					(thickness 0.15)
				)
				(justify mirror)
			)
		)
		(property "Tolerance" "1%"
			(at 42.54 182.26 0)
			(layer "B.Fab")
			(hide yes)
			(effects
				(font
					(size 1 1)
					(thickness 0.15)
				)
				(justify mirror)
			)
		)
		(property "Val" "220R"
			(at 42.54 182.26 0)
			(layer "B.Fab")
			(hide yes)
			(effects
				(font
					(size 1 1)
					(thickness 0.15)
				)
				(justify mirror)
			)
		)
		(sheetname "USB-C console")
		(sheetfile "usb-c_console.kicad_sch")
		(attr smd)
		(fp_rect
			(start -0.925 0.47)
			(end 0.925 -0.47)
			(stroke
				(width 0.05)
				(type default)
			)
			(fill no)
			(layer "B.CrtYd")
		)
		(fp_rect
			(start -0.5 0.25)
			(end 0.5 -0.25)
			(stroke
				(width 0.15)
				(type solid)
			)
			(fill no)
			(layer "B.Fab")
		)
		(pad "1" smd roundrect
			(at -0.48 0 270)
			(size 0.59 0.64)
			(layers "B.Cu" "B.Mask" "B.Paste")
			(roundrect_rratio 0.25)
			(net 933 "Net-(D11-A)")
			(pintype "passive")
			(teardrops
				(best_length_ratio 0.2)
				(max_length 1)
				(best_width_ratio 0.9)
				(max_width 2)
				(curved_edges yes)
				(filter_ratio 0.9)
				(enabled yes)
				(allow_two_segments yes)
				(prefer_zone_connections yes)
			)
		)
		(pad "2" smd roundrect
			(at 0.48 0 270)
			(size 0.59 0.64)
			(layers "B.Cu" "B.Mask" "B.Paste")
			(roundrect_rratio 0.25)
			(net 57 "/USB-C console/FTDI_VCCIO")
			(pintype "passive")
			(teardrops
				(best_length_ratio 0.2)
				(max_length 1)
				(best_width_ratio 0.9)
				(max_width 2)
				(curved_edges yes)
				(filter_ratio 0.9)
				(enabled yes)
				(allow_two_segments yes)
				(prefer_zone_connections yes)
			)
		)
	)
	(footprint "antmicro-footprints:SOT-23-3"
		(layer "B.Cu")
		(at 140.7 135.81)
		(property "Reference" "D23"
			(at -3.8 1.95 0)
			(layer "B.SilkS")
			(effects
				(font
					(size 0.7 0.7)
					(thickness 0.15)
				)
				(justify right bottom mirror)
			)
		)
		(property "Value" "BAT54C"
			(at -1.9 -2.7 0)
			(layer "B.Fab")
			(effects
				(font
					(size 0.7 0.7)
					(thickness 0.15)
				)
				(justify right bottom mirror)
			)
		)
		(property "Datasheet" "https://diotec.com/request/datasheet/bat54.pdf"
			(at 0 0 0)
			(layer "F.Fab")
			(hide yes)
			(effects
				(font
					(size 1.27 1.27)
					(thickness 0.15)
				)
			)
		)
		(property "Author" "Antmicro"
			(at 0 0 0)
			(layer "B.Fab")
			(hide yes)
			(effects
				(font
					(size 1 1)
					(thickness 0.15)
				)
				(justify mirror)
			)
		)
		(property "License" "Apache-2.0"
			(at 0 0 0)
			(layer "B.Fab")
			(hide yes)
			(effects
				(font
					(size 1 1)
					(thickness 0.15)
				)
				(justify mirror)
			)
		)
		(property "MPN" "BAT54C"
			(at 0 0 0)
			(layer "B.Fab")
			(hide yes)
			(effects
				(font
					(size 1 1)
					(thickness 0.15)
				)
				(justify mirror)
			)
		)
		(property "Manufacturer" "Diotec Semiconductor"
			(at 0 0 0)
			(layer "B.Fab")
			(hide yes)
			(effects
				(font
					(size 1 1)
					(thickness 0.15)
				)
				(justify mirror)
			)
		)
		(sheetname "KR to SFI #2")
		(sheetfile "kr_sfi.kicad_sch")
		(attr smd)
		(fp_line
			(start -0.85 1.35)
			(end -1.45 1.35)
			(stroke
				(width 0.15)
				(type solid)
			)
			(layer "B.SilkS")
		)
		(fp_line
			(start -0.7 -1.5)
			(end 0.7 -1.5)
			(stroke
				(width 0.15)
				(type solid)
			)
			(layer "B.SilkS")
		)
		(fp_line
			(start -0.7 -1.35)
			(end -0.7 -1.5)
			(stroke
				(width 0.15)
				(type solid)
			)
			(layer "B.SilkS")
		)
		(fp_line
			(start -0.7 1.5)
			(end -0.85 1.35)
			(stroke
				(width 0.15)
				(type solid)
			)
			(layer "B.SilkS")
		)
		(fp_line
			(start -0.7 1.5)
			(end 0.7 1.5)
			(stroke
				(width 0.15)
				(type solid)
			)
			(layer "B.SilkS")
		)
		(fp_line
			(start 0.7 -1.5)
			(end 0.7 -0.4)
			(stroke
				(width 0.15)
				(type solid)
			)
			(layer "B.SilkS")
		)
		(fp_line
			(start 0.7 1.5)
			(end 0.7 0.4)
			(stroke
				(width 0.15)
				(type solid)
			)
			(layer "B.SilkS")
		)
		(fp_line
			(start -1.75 -1.4)
			(end -0.85 -1.4)
			(stroke
				(width 0.05)
				(type solid)
			)
			(layer "B.CrtYd")
		)
		(fp_line
			(start -1.75 -0.5)
			(end -1.75 -1.4)
			(stroke
				(width 0.05)
				(type solid)
			)
			(layer "B.CrtYd")
		)
		(fp_line
			(start -1.75 0.5)
			(end -0.85 0.5)
			(stroke
				(width 0.05)
				(type solid)
			)
			(layer "B.CrtYd")
		)
		(fp_line
			(start -1.75 1.4)
			(end -1.75 0.5)
			(stroke
				(width 0.05)
				(type solid)
			)
			(layer "B.CrtYd")
		)
		(fp_line
			(start -1.75 1.4)
			(end -0.9 1.4)
			(stroke
				(width 0.05)
				(type solid)
			)
			(layer "B.CrtYd")
		)
		(fp_line
			(start -0.9 1.4)
			(end -0.9 1.6)
			(stroke
				(width 0.05)
				(type solid)
			)
			(layer "B.CrtYd")
		)
		(fp_line
			(start -0.85 -1.65)
			(end 0.85 -1.65)
			(stroke
				(width 0.05)
				(type solid)
			)
			(layer "B.CrtYd")
		)
		(fp_line
			(start -0.85 -1.4)
			(end -0.85 -1.65)
			(stroke
				(width 0.05)
				(type solid)
			)
			(layer "B.CrtYd")
		)
		(fp_line
			(start -0.85 -0.5)
			(end -1.75 -0.5)
			(stroke
				(width 0.05)
				(type solid)
			)
			(layer "B.CrtYd")
		)
		(fp_line
			(start -0.85 0.5)
			(end -0.85 -0.5)
			(stroke
				(width 0.05)
				(type solid)
			)
			(layer "B.CrtYd")
		)
		(fp_line
			(start 0.825 0.45)
			(end 0.825 1.6)
			(stroke
				(width 0.05)
				(type solid)
			)
			(layer "B.CrtYd")
		)
		(fp_line
			(start 0.825 1.6)
			(end -0.9 1.6)
			(stroke
				(width 0.05)
				(type solid)
			)
			(layer "B.CrtYd")
		)
		(fp_line
			(start 0.85 -1.65)
			(end 0.85 -0.45)
			(stroke
				(width 0.05)
				(type solid)
			)
			(layer "B.CrtYd")
		)
		(fp_line
			(start 0.85 -0.45)
			(end 1.75 -0.45)
			(stroke
				(width 0.05)
				(type solid)
			)
			(layer "B.CrtYd")
		)
		(fp_line
			(start 1.75 -0.45)
			(end 1.75 0.45)
			(stroke
				(width 0.05)
				(type solid)
			)
			(layer "B.CrtYd")
		)
		(fp_line
			(start 1.75 0.45)
			(end 0.825 0.45)
			(stroke
				(width 0.05)
				(type solid)
			)
			(layer "B.CrtYd")
		)
		(fp_line
			(start -0.712 -1.523)
			(end -0.712 1.325)
			(stroke
				(width 0.15)
				(type solid)
			)
			(layer "B.Fab")
		)
		(fp_line
			(start -0.712 1.325)
			(end -0.437 1.526)
			(stroke
				(width 0.15)
				(type solid)
			)
			(layer "B.Fab")
		)
		(fp_line
			(start 0.688 -1.519)
			(end -0.712 -1.519)
			(stroke
				(width 0.15)
				(type solid)
			)
			(layer "B.Fab")
		)
		(fp_line
			(start 0.688 1.52)
			(end 0.688 -1.519)
			(stroke
				(width 0.15)
				(type solid)
			)
			(layer "B.Fab")
		)
		(fp_line
			(start 0.688 1.526)
			(end -0.437 1.526)
			(stroke
				(width 0.15)
				(type solid)
			)
			(layer "B.Fab")
		)
		(pad "1" smd roundrect
			(at -1.1 0.951)
			(size 1 0.6)
			(layers "B.Cu" "B.Mask" "B.Paste")
			(roundrect_rratio 0.15)
			(net 143 "/2xSFP+/KR to SFI #2/~{RESET}")
			(pinfunction "1")
			(pintype "passive")
			(teardrops
				(best_length_ratio 0.2)
				(max_length 1)
				(best_width_ratio 0.9)
				(max_width 2)
				(curved_edges yes)
				(filter_ratio 0.9)
				(enabled yes)
				(allow_two_segments yes)
				(prefer_zone_connections yes)
			)
		)
		(pad "2" smd roundrect
			(at -1.1 -0.949)
			(size 1 0.6)
			(layers "B.Cu" "B.Mask" "B.Paste")
			(roundrect_rratio 0.15)
			(net 143 "/2xSFP+/KR to SFI #2/~{RESET}")
			(pinfunction "2")
			(pintype "passive")
			(teardrops
				(best_length_ratio 0.2)
				(max_length 1)
				(best_width_ratio 0.9)
				(max_width 2)
				(curved_edges yes)
				(filter_ratio 0.9)
				(enabled yes)
				(allow_two_segments yes)
				(prefer_zone_connections yes)
			)
		)
		(pad "3" smd roundrect
			(at 1.1 0.0005)
			(size 1 0.6)
			(layers "B.Cu" "B.Mask" "B.Paste")
			(roundrect_rratio 0.15)
			(net 142 "/2xSFP+/PHY0_{RESET}")
			(pinfunction "3")
			(pintype "passive")
			(teardrops
				(best_length_ratio 0.2)
				(max_length 1)
				(best_width_ratio 0.9)
				(max_width 2)
				(curved_edges yes)
				(filter_ratio 0.9)
				(enabled yes)
				(allow_two_segments yes)
				(prefer_zone_connections yes)
			)
		)
	)
	(footprint "antmicro-footprints:R_0402_1005Metric"
		(layer "B.Cu")
		(at 123.4 99.86)
		(descr "Resistor SMD 0402")
		(tags "resistor SMD 0402")
		(property "Reference" "R9"
			(at 0.9 0.45 0)
			(layer "B.SilkS")
			(effects
				(font
					(size 0.7 0.7)
					(thickness 0.15)
				)
				(justify right bottom mirror)
			)
		)
		(property "Value" "R_470R_0402"
			(at -1.011843 -1.772047 0)
			(layer "B.Fab")
			(effects
				(font
					(size 0.7 0.7)
					(thickness 0.15)
				)
				(justify right bottom mirror)
			)
		)
		(property "Datasheet" "https://www.bourns.com/docs/product-datasheets/cr.pdf"
			(at 0 0 0)
			(layer "F.Fab")
			(hide yes)
			(effects
				(font
					(size 1.27 1.27)
					(thickness 0.15)
				)
			)
		)
		(property "Author" "Antmicro"
			(at 0 0 0)
			(layer "B.Fab")
			(hide yes)
			(effects
				(font
					(size 1 1)
					(thickness 0.15)
				)
				(justify mirror)
			)
		)
		(property "License" "Apache-2.0"
			(at 0 0 0)
			(layer "B.Fab")
			(hide yes)
			(effects
				(font
					(size 1 1)
					(thickness 0.15)
				)
				(justify mirror)
			)
		)
		(property "MPN" "CR0402-FX-4700GLF"
			(at 0 0 0)
			(layer "B.Fab")
			(hide yes)
			(effects
				(font
					(size 1 1)
					(thickness 0.15)
				)
				(justify mirror)
			)
		)
		(property "Manufacturer" "Bourns"
			(at 0 0 0)
			(layer "B.Fab")
			(hide yes)
			(effects
				(font
					(size 1 1)
					(thickness 0.15)
				)
				(justify mirror)
			)
		)
		(property "Public" "False"
			(at 0 0 0)
			(layer "B.Fab")
			(hide yes)
			(effects
				(font
					(size 1 1)
					(thickness 0.15)
				)
				(justify mirror)
			)
		)
		(property "Tolerance" "1%"
			(at 0 0 0)
			(layer "B.Fab")
			(hide yes)
			(effects
				(font
					(size 1 1)
					(thickness 0.15)
				)
				(justify mirror)
			)
		)
		(property "Val" "470R"
			(at 0 0 0)
			(layer "B.Fab")
			(hide yes)
			(effects
				(font
					(size 1 1)
					(thickness 0.15)
				)
				(justify mirror)
			)
		)
		(sheetname "2xUSB3.0+RJ45")
		(sheetfile "usb3+rj45.kicad_sch")
		(attr smd dnp)
		(fp_rect
			(start -0.925 0.47)
			(end 0.925 -0.47)
			(stroke
				(width 0.05)
				(type default)
			)
			(fill no)
			(layer "B.CrtYd")
		)
		(fp_rect
			(start -0.5 0.25)
			(end 0.5 -0.25)
			(stroke
				(width 0.15)
				(type solid)
			)
			(fill no)
			(layer "B.Fab")
		)
		(pad "1" smd roundrect
			(at -0.48 0)
			(size 0.59 0.64)
			(layers "B.Cu" "B.Mask" "B.Paste")
			(roundrect_rratio 0.25)
			(net 155 "Net-(J1A-LED_D2)")
			(pintype "passive")
			(teardrops
				(best_length_ratio 0.2)
				(max_length 1)
				(best_width_ratio 0.9)
				(max_width 2)
				(curved_edges yes)
				(filter_ratio 0.9)
				(enabled yes)
				(allow_two_segments yes)
				(prefer_zone_connections yes)
			)
		)
		(pad "2" smd roundrect
			(at 0.48 0)
			(size 0.59 0.64)
			(layers "B.Cu" "B.Mask" "B.Paste")
			(roundrect_rratio 0.25)
			(net 2 "+3V3")
			(pintype "passive")
			(teardrops
				(best_length_ratio 0.2)
				(max_length 1)
				(best_width_ratio 0.9)
				(max_width 2)
				(curved_edges yes)
				(filter_ratio 0.9)
				(enabled yes)
				(allow_two_segments yes)
				(prefer_zone_connections yes)
			)
		)
	)
	(footprint "antmicro-footprints:R_0402_1005Metric"
		(layer "B.Cu")
		(at 107.5 162.06 180)
		(descr "Resistor SMD 0402")
		(tags "resistor SMD 0402")
		(property "Reference" "R84"
			(at -3 -0.43 0)
			(layer "B.SilkS")
			(effects
				(font
					(size 0.7 0.7)
					(thickness 0.15)
				)
				(justify left bottom mirror)
			)
		)
		(property "Value" "R_0R_0402"
			(at -1.011843 -1.772047 0)
			(layer "B.Fab")
			(effects
				(font
					(size 0.7 0.7)
					(thickness 0.15)
				)
				(justify left bottom mirror)
			)
		)
		(property "Datasheet" "https://industrial.panasonic.com/cdbs/www-data/pdf/RDA0000/AOA0000C301.pdf"
			(at 0 0 180)
			(layer "F.Fab")
			(hide yes)
			(effects
				(font
					(size 1.27 1.27)
					(thickness 0.15)
				)
			)
		)
		(property "Author" "Antmicro"
			(at 215 324.12 0)
			(layer "B.Fab")
			(hide yes)
			(effects
				(font
					(size 1 1)
					(thickness 0.15)
				)
				(justify mirror)
			)
		)
		(property "Current" "1A"
			(at 215 324.12 0)
			(layer "B.Fab")
			(hide yes)
			(effects
				(font
					(size 1 1)
					(thickness 0.15)
				)
				(justify mirror)
			)
		)
		(property "License" "Apache-2.0"
			(at 215 324.12 0)
			(layer "B.Fab")
			(hide yes)
			(effects
				(font
					(size 1 1)
					(thickness 0.15)
				)
				(justify mirror)
			)
		)
		(property "MPN" "ERJ2GE0R00X"
			(at 215 324.12 0)
			(layer "B.Fab")
			(hide yes)
			(effects
				(font
					(size 1 1)
					(thickness 0.15)
				)
				(justify mirror)
			)
		)
		(property "Manufacturer" "Panasonic"
			(at 215 324.12 0)
			(layer "B.Fab")
			(hide yes)
			(effects
				(font
					(size 1 1)
					(thickness 0.15)
				)
				(justify mirror)
			)
		)
		(property "Public" "False"
			(at 215 324.12 0)
			(layer "B.Fab")
			(hide yes)
			(effects
				(font
					(size 1 1)
					(thickness 0.15)
				)
				(justify mirror)
			)
		)
		(property "Tolerance" ""
			(at 215 324.12 0)
			(layer "B.Fab")
			(hide yes)
			(effects
				(font
					(size 1 1)
					(thickness 0.15)
				)
				(justify mirror)
			)
		)
		(property "Val" "0R"
			(at 215 324.12 0)
			(layer "B.Fab")
			(hide yes)
			(effects
				(font
					(size 1 1)
					(thickness 0.15)
				)
				(justify mirror)
			)
		)
		(sheetname "OCuLink")
		(sheetfile "oculink.kicad_sch")
		(attr smd)
		(fp_rect
			(start -0.925 0.47)
			(end 0.925 -0.47)
			(stroke
				(width 0.05)
				(type default)
			)
			(fill no)
			(layer "B.CrtYd")
		)
		(fp_rect
			(start -0.5 0.25)
			(end 0.5 -0.25)
			(stroke
				(width 0.15)
				(type solid)
			)
			(fill no)
			(layer "B.Fab")
		)
		(pad "1" smd roundrect
			(at -0.48 0 180)
			(size 0.59 0.64)
			(layers "B.Cu" "B.Mask" "B.Paste")
			(roundrect_rratio 0.25)
			(net 358 "/Com Express 7 MGMT/SMBus.SDA")
			(pintype "passive")
			(teardrops
				(best_length_ratio 0.2)
				(max_length 1)
				(best_width_ratio 0.9)
				(max_width 2)
				(curved_edges yes)
				(filter_ratio 0.9)
				(enabled yes)
				(allow_two_segments yes)
				(prefer_zone_connections yes)
			)
		)
		(pad "2" smd roundrect
			(at 0.48 0 180)
			(size 0.59 0.64)
			(layers "B.Cu" "B.Mask" "B.Paste")
			(roundrect_rratio 0.25)
			(net 199 "/OCuLink/SDA")
			(pintype "passive")
			(teardrops
				(best_length_ratio 0.2)
				(max_length 1)
				(best_width_ratio 0.9)
				(max_width 2)
				(curved_edges yes)
				(filter_ratio 0.9)
				(enabled yes)
				(allow_two_segments yes)
				(prefer_zone_connections yes)
			)
		)
	)
	(footprint "antmicro-footprints:C_1210_3225Metric"
		(layer "B.Cu")
		(at 140.6 105.2 180)
		(descr "Capacitor SMD 1210")
		(tags "capacitor SMD 1210")
		(property "Reference" "C12"
			(at -1.105 2.7 0)
			(layer "B.SilkS")
			(effects
				(font
					(size 0.7 0.7)
					(thickness 0.15)
				)
				(justify left top mirror)
			)
		)
		(property "Value" "C_1n_1210_2kV"
			(at 0 -2.749001 0)
			(layer "B.Fab")
			(effects
				(font
					(size 0.7 0.7)
					(thickness 0.15)
				)
				(justify left top mirror)
			)
		)
		(property "Datasheet" "https://www.kemet.com/en/us/capacitors/product/C1210C102KGRACTU.html"
			(at 0 0 0)
			(layer "B.Fab")
			(hide yes)
			(effects
				(font
					(size 1.27 1.27)
					(thickness 0.15)
				)
				(justify mirror)
			)
		)
		(property "Author" "Antmicro"
			(at 279.39 -214.52 0)
			(layer "B.Fab")
			(hide yes)
			(effects
				(font
					(size 1 1)
					(thickness 0.15)
				)
				(justify mirror)
			)
		)
		(property "Dielectric" ""
			(at 279.39 -214.52 0)
			(layer "B.Fab")
			(hide yes)
			(effects
				(font
					(size 1 1)
					(thickness 0.15)
				)
				(justify mirror)
			)
		)
		(property "License" "Apache-2.0"
			(at 279.39 -214.52 0)
			(layer "B.Fab")
			(hide yes)
			(effects
				(font
					(size 1 1)
					(thickness 0.15)
				)
				(justify mirror)
			)
		)
		(property "MPN" "C1210C102KGRACTU"
			(at 279.39 -214.52 0)
			(layer "B.Fab")
			(hide yes)
			(effects
				(font
					(size 1 1)
					(thickness 0.15)
				)
				(justify mirror)
			)
		)
		(property "Manufacturer" "KEMET"
			(at 279.39 -214.52 0)
			(layer "B.Fab")
			(hide yes)
			(effects
				(font
					(size 1 1)
					(thickness 0.15)
				)
				(justify mirror)
			)
		)
		(property "Public" "False"
			(at 279.39 -214.52 0)
			(layer "B.Fab")
			(hide yes)
			(effects
				(font
					(size 1 1)
					(thickness 0.15)
				)
				(justify mirror)
			)
		)
		(property "Val" "1n"
			(at 279.39 -214.52 0)
			(layer "B.Fab")
			(hide yes)
			(effects
				(font
					(size 1 1)
					(thickness 0.15)
				)
				(justify mirror)
			)
		)
		(property "Voltage" "2kV"
			(at 279.39 -214.52 0)
			(layer "B.Fab")
			(hide yes)
			(effects
				(font
					(size 1 1)
					(thickness 0.15)
				)
				(justify mirror)
			)
		)
		(sheetname "2xUSB3.0+RJ45")
		(sheetfile "usb3+rj45.kicad_sch")
		(attr smd)
		(fp_line
			(start 0.3 1.39)
			(end -0.3 1.39)
			(stroke
				(width 0.15)
				(type solid)
			)
			(layer "B.SilkS")
		)
		(fp_line
			(start 0.3 -1.39)
			(end -0.3 -1.39)
			(stroke
				(width 0.15)
				(type solid)
			)
			(layer "B.SilkS")
		)
		(fp_rect
			(start -2.1 1.75)
			(end 2.1 -1.75)
			(stroke
				(width 0.05)
				(type solid)
			)
			(fill no)
			(layer "B.CrtYd")
		)
		(fp_rect
			(start -1.6 1.25)
			(end 1.6 -1.25)
			(stroke
				(width 0.15)
				(type solid)
			)
			(fill no)
			(layer "B.Fab")
		)
		(pad "1" smd rect
			(at -1.145 0 180)
			(size 1.52 3.05)
			(layers "B.Cu" "B.Mask" "B.Paste")
			(net 1 "GND")
			(pintype "passive")
			(teardrops
				(best_length_ratio 0.2)
				(max_length 1)
				(best_width_ratio 0.9)
				(max_width 2)
				(curved_edges yes)
				(filter_ratio 0.9)
				(enabled yes)
				(allow_two_segments yes)
				(prefer_zone_connections yes)
			)
		)
		(pad "2" smd rect
			(at 1.145 0 180)
			(size 1.52 3.05)
			(layers "B.Cu" "B.Mask" "B.Paste")
			(net 50 "Net-(C12-Pad2)")
			(pintype "passive")
			(teardrops
				(best_length_ratio 0.2)
				(max_length 1)
				(best_width_ratio 0.9)
				(max_width 2)
				(curved_edges yes)
				(filter_ratio 0.9)
				(enabled yes)
				(allow_two_segments yes)
				(prefer_zone_connections yes)
			)
		)
	)
	(footprint "antmicro-footprints:C_0402_1005Metric"
		(layer "B.Cu")
		(at 100.25 96.56 180)
		(descr "Capacitor SMD 0402")
		(tags "capacitor SMD 0402")
		(property "Reference" "C5"
			(at -0.775 -1.36 0)
			(layer "B.SilkS")
			(effects
				(font
					(size 0.7 0.7)
					(thickness 0.15)
				)
				(justify left bottom mirror)
			)
		)
		(property "Value" "C_100n_0402"
			(at -1.022927 -2.155213 0)
			(layer "B.Fab")
			(effects
				(font
					(size 0.7 0.7)
					(thickness 0.15)
				)
				(justify left bottom mirror)
			)
		)
		(property "Datasheet" "https://www.murata.com/products/productdetail?partno=GRM155R61H104KE14%23"
			(at 0 0 180)
			(layer "F.Fab")
			(hide yes)
			(effects
				(font
					(size 1.27 1.27)
					(thickness 0.15)
				)
			)
		)
		(property "Author" "Antmicro"
			(at 200.5 193.12 0)
			(layer "B.Fab")
			(hide yes)
			(effects
				(font
					(size 1 1)
					(thickness 0.15)
				)
				(justify mirror)
			)
		)
		(property "Dielectric" "X5R"
			(at 200.5 193.12 0)
			(layer "B.Fab")
			(hide yes)
			(effects
				(font
					(size 1 1)
					(thickness 0.15)
				)
				(justify mirror)
			)
		)
		(property "License" "Apache-2.0"
			(at 200.5 193.12 0)
			(layer "B.Fab")
			(hide yes)
			(effects
				(font
					(size 1 1)
					(thickness 0.15)
				)
				(justify mirror)
			)
		)
		(property "MPN" "GRM155R61H104KE14D"
			(at 200.5 193.12 0)
			(layer "B.Fab")
			(hide yes)
			(effects
				(font
					(size 1 1)
					(thickness 0.15)
				)
				(justify mirror)
			)
		)
		(property "Manufacturer" "Murata"
			(at 200.5 193.12 0)
			(layer "B.Fab")
			(hide yes)
			(effects
				(font
					(size 1 1)
					(thickness 0.15)
				)
				(justify mirror)
			)
		)
		(property "Public" "False"
			(at 200.5 193.12 0)
			(layer "B.Fab")
			(hide yes)
			(effects
				(font
					(size 1 1)
					(thickness 0.15)
				)
				(justify mirror)
			)
		)
		(property "Val" "100n"
			(at 200.5 193.12 0)
			(layer "B.Fab")
			(hide yes)
			(effects
				(font
					(size 1 1)
					(thickness 0.15)
				)
				(justify mirror)
			)
		)
		(property "Voltage" "50V"
			(at 200.5 193.12 0)
			(layer "B.Fab")
			(hide yes)
			(effects
				(font
					(size 1 1)
					(thickness 0.15)
				)
				(justify mirror)
			)
		)
		(sheetname "2xUSB3.0+RJ45")
		(sheetfile "usb3+rj45.kicad_sch")
		(attr smd)
		(fp_rect
			(start -0.925 0.47)
			(end 0.925 -0.47)
			(stroke
				(width 0.05)
				(type default)
			)
			(fill no)
			(layer "B.CrtYd")
		)
		(fp_line
			(start 0.504 0.25)
			(end -0.494 0.25)
			(stroke
				(width 0.15)
				(type solid)
			)
			(layer "B.Fab")
		)
		(fp_line
			(start 0.504 -0.248)
			(end 0.504 0.25)
			(stroke
				(width 0.15)
				(type solid)
			)
			(layer "B.Fab")
		)
		(fp_line
			(start -0.494 0.25)
			(end -0.494 -0.248)
			(stroke
				(width 0.15)
				(type solid)
			)
			(layer "B.Fab")
		)
		(fp_line
			(start -0.494 -0.248)
			(end 0.504 -0.248)
			(stroke
				(width 0.15)
				(type solid)
			)
			(layer "B.Fab")
		)
		(pad "1" smd roundrect
			(at -0.48 0 180)
			(size 0.59 0.64)
			(layers "B.Cu" "B.Mask" "B.Paste")
			(roundrect_rratio 0.25)
			(net 579 "/2xUSB3.0+RJ45/SH")
			(pintype "passive")
			(teardrops
				(best_length_ratio 0.2)
				(max_length 1)
				(best_width_ratio 0.9)
				(max_width 2)
				(curved_edges yes)
				(filter_ratio 0.9)
				(enabled yes)
				(allow_two_segments yes)
				(prefer_zone_connections yes)
			)
		)
		(pad "2" smd roundrect
			(at 0.48 0 180)
			(size 0.59 0.64)
			(layers "B.Cu" "B.Mask" "B.Paste")
			(roundrect_rratio 0.25)
			(net 1 "GND")
			(pintype "passive")
			(teardrops
				(best_length_ratio 0.2)
				(max_length 1)
				(best_width_ratio 0.9)
				(max_width 2)
				(curved_edges yes)
				(filter_ratio 0.9)
				(enabled yes)
				(allow_two_segments yes)
				(prefer_zone_connections yes)
			)
		)
	)
	(footprint "antmicro-footprints:C_0402_1005Metric"
		(layer "B.Cu")
		(at 152.95 141.86 180)
		(descr "Capacitor SMD 0402")
		(tags "capacitor SMD 0402")
		(property "Reference" "C169"
			(at -3.7 -0.4 0)
			(layer "B.SilkS")
			(effects
				(font
					(size 0.7 0.7)
					(thickness 0.15)
				)
				(justify left bottom mirror)
			)
		)
		(property "Value" "C_100n_0402"
			(at -1.022927 -2.155213 0)
			(layer "B.Fab")
			(effects
				(font
					(size 0.7 0.7)
					(thickness 0.15)
				)
				(justify left bottom mirror)
			)
		)
		(property "Datasheet" "https://www.murata.com/products/productdetail?partno=GRM155R61H104KE14%23"
			(at 0 0 180)
			(layer "F.Fab")
			(hide yes)
			(effects
				(font
					(size 1.27 1.27)
					(thickness 0.15)
				)
			)
		)
		(property "Author" "Antmicro"
			(at 305.9 283.72 0)
			(layer "B.Fab")
			(hide yes)
			(effects
				(font
					(size 1 1)
					(thickness 0.15)
				)
				(justify mirror)
			)
		)
		(property "Dielectric" "X5R"
			(at 305.9 283.72 0)
			(layer "B.Fab")
			(hide yes)
			(effects
				(font
					(size 1 1)
					(thickness 0.15)
				)
				(justify mirror)
			)
		)
		(property "License" "Apache-2.0"
			(at 305.9 283.72 0)
			(layer "B.Fab")
			(hide yes)
			(effects
				(font
					(size 1 1)
					(thickness 0.15)
				)
				(justify mirror)
			)
		)
		(property "MPN" "GRM155R61H104KE14D"
			(at 305.9 283.72 0)
			(layer "B.Fab")
			(hide yes)
			(effects
				(font
					(size 1 1)
					(thickness 0.15)
				)
				(justify mirror)
			)
		)
		(property "Manufacturer" "Murata"
			(at 305.9 283.72 0)
			(layer "B.Fab")
			(hide yes)
			(effects
				(font
					(size 1 1)
					(thickness 0.15)
				)
				(justify mirror)
			)
		)
		(property "Public" "False"
			(at 305.9 283.72 0)
			(layer "B.Fab")
			(hide yes)
			(effects
				(font
					(size 1 1)
					(thickness 0.15)
				)
				(justify mirror)
			)
		)
		(property "Val" "100n"
			(at 305.9 283.72 0)
			(layer "B.Fab")
			(hide yes)
			(effects
				(font
					(size 1 1)
					(thickness 0.15)
				)
				(justify mirror)
			)
		)
		(property "Voltage" "50V"
			(at 305.9 283.72 0)
			(layer "B.Fab")
			(hide yes)
			(effects
				(font
					(size 1 1)
					(thickness 0.15)
				)
				(justify mirror)
			)
		)
		(sheetname "KR to SFI #1")
		(sheetfile "kr_sfi.kicad_sch")
		(attr smd)
		(fp_rect
			(start -0.925 0.47)
			(end 0.925 -0.47)
			(stroke
				(width 0.05)
				(type default)
			)
			(fill no)
			(layer "B.CrtYd")
		)
		(fp_line
			(start 0.504 0.25)
			(end -0.494 0.25)
			(stroke
				(width 0.15)
				(type solid)
			)
			(layer "B.Fab")
		)
		(fp_line
			(start 0.504 -0.248)
			(end 0.504 0.25)
			(stroke
				(width 0.15)
				(type solid)
			)
			(layer "B.Fab")
		)
		(fp_line
			(start -0.494 0.25)
			(end -0.494 -0.248)
			(stroke
				(width 0.15)
				(type solid)
			)
			(layer "B.Fab")
		)
		(fp_line
			(start -0.494 -0.248)
			(end 0.504 -0.248)
			(stroke
				(width 0.15)
				(type solid)
			)
			(layer "B.Fab")
		)
		(pad "1" smd roundrect
			(at -0.48 0 180)
			(size 0.59 0.64)
			(layers "B.Cu" "B.Mask" "B.Paste")
			(roundrect_rratio 0.25)
			(net 1 "GND")
			(pintype "passive")
			(teardrops
				(best_length_ratio 0.2)
				(max_length 1)
				(best_width_ratio 0.9)
				(max_width 2)
				(curved_edges yes)
				(filter_ratio 0.9)
				(enabled yes)
				(allow_two_segments yes)
				(prefer_zone_connections yes)
			)
		)
		(pad "2" smd roundrect
			(at 0.48 0 180)
			(size 0.59 0.64)
			(layers "B.Cu" "B.Mask" "B.Paste")
			(roundrect_rratio 0.25)
			(net 78 "+1V8")
			(pintype "passive")
			(teardrops
				(best_length_ratio 0.2)
				(max_length 1)
				(best_width_ratio 0.9)
				(max_width 2)
				(curved_edges yes)
				(filter_ratio 0.9)
				(enabled yes)
				(allow_two_segments yes)
				(prefer_zone_connections yes)
			)
		)
	)
	(footprint "antmicro-footprints:USON-10_2.5x1mm_P0.5mm"
		(layer "B.Cu")
		(at 104.77 159.61)
		(descr "USON-10 2.5x1mm_ Pitch 0.5mm")
		(tags "USON-10 2.5x1mm Pitch 0.5mm")
		(property "Reference" "U11"
			(at 1.73 1.15 90)
			(layer "B.SilkS")
			(effects
				(font
					(size 0.7 0.7)
					(thickness 0.15)
				)
				(justify right bottom mirror)
			)
		)
		(property "Value" "ESD204DQAR"
			(at 0.018 -2.499 0)
			(layer "B.Fab")
			(effects
				(font
					(size 0.7 0.7)
					(thickness 0.15)
				)
				(justify right bottom mirror)
			)
		)
		(property "Datasheet" "https://www.ti.com/lit/ds/symlink/esd204.pdf?ts=1706004844383&ref_url=https%253A%252F%252Fwww.ti.com%252Finterface%252Fdiodes%252Fesd-protection-diodes%252Fproducts.html"
			(at 0 0 0)
			(layer "F.Fab")
			(hide yes)
			(effects
				(font
					(size 1.27 1.27)
					(thickness 0.15)
				)
			)
		)
		(property "Author" "Antmicro"
			(at 0 0 0)
			(layer "B.Fab")
			(hide yes)
			(effects
				(font
					(size 1 1)
					(thickness 0.15)
				)
				(justify mirror)
			)
		)
		(property "License" "Apache-2.0"
			(at 0 0 0)
			(layer "B.Fab")
			(hide yes)
			(effects
				(font
					(size 1 1)
					(thickness 0.15)
				)
				(justify mirror)
			)
		)
		(property "MPN" "ESD204DQAR"
			(at 0 0 0)
			(layer "B.Fab")
			(hide yes)
			(effects
				(font
					(size 1 1)
					(thickness 0.15)
				)
				(justify mirror)
			)
		)
		(property "Manufacturer" "Texas Instruments"
			(at 0 0 0)
			(layer "B.Fab")
			(hide yes)
			(effects
				(font
					(size 1 1)
					(thickness 0.15)
				)
				(justify mirror)
			)
		)
		(sheetname "OCuLink")
		(sheetfile "oculink.kicad_sch")
		(attr smd)
		(fp_line
			(start -0.5 -1.398)
			(end 0.498 -1.398)
			(stroke
				(width 0.15)
				(type solid)
			)
			(layer "B.SilkS")
		)
		(fp_line
			(start -0.5 1.401)
			(end 0.498 1.401)
			(stroke
				(width 0.15)
				(type solid)
			)
			(layer "B.SilkS")
		)
		(fp_circle
			(center -0.68 1.27)
			(end -0.63 1.27)
			(stroke
				(width 0.15)
				(type solid)
			)
			(fill yes)
			(layer "B.SilkS")
		)
		(fp_rect
			(start -0.8 1.5)
			(end 0.8 -1.499)
			(stroke
				(width 0.05)
				(type solid)
			)
			(fill no)
			(layer "B.CrtYd")
		)
		(fp_line
			(start -0.5 -1.249)
			(end -0.5 1)
			(stroke
				(width 0.15)
				(type solid)
			)
			(layer "B.Fab")
		)
		(fp_line
			(start -0.5 1)
			(end -0.25 1.25)
			(stroke
				(width 0.15)
				(type solid)
			)
			(layer "B.Fab")
		)
		(fp_line
			(start -0.25 1.25)
			(end 0.498 1.25)
			(stroke
				(width 0.15)
				(type solid)
			)
			(layer "B.Fab")
		)
		(fp_line
			(start 0.498 -1.249)
			(end -0.5 -1.249)
			(stroke
				(width 0.15)
				(type solid)
			)
			(layer "B.Fab")
		)
		(fp_line
			(start 0.498 -1.249)
			(end 0.498 1.25)
			(stroke
				(width 0.15)
				(type solid)
			)
			(layer "B.Fab")
		)
		(pad "1" smd roundrect
			(at -0.387 1 90)
			(size 0.25 0.55)
			(layers "B.Cu" "B.Mask" "B.Paste")
			(roundrect_rratio 0.25)
			(net 104 "/OCuLink/PCIe_{x4}.TX2+")
			(pintype "passive")
			(teardrops
				(best_length_ratio 0.2)
				(max_length 1)
				(best_width_ratio 0.9)
				(max_width 2)
				(curved_edges yes)
				(filter_ratio 0.9)
				(enabled yes)
				(allow_two_segments yes)
				(prefer_zone_connections yes)
			)
		)
		(pad "2" smd roundrect
			(at -0.387 0.5 90)
			(size 0.25 0.55)
			(layers "B.Cu" "B.Mask" "B.Paste")
			(roundrect_rratio 0.25)
			(net 97 "/OCuLink/PCIe_{x4}.TX2-")
			(pintype "passive")
			(teardrops
				(best_length_ratio 0.2)
				(max_length 1)
				(best_width_ratio 0.9)
				(max_width 2)
				(curved_edges yes)
				(filter_ratio 0.9)
				(enabled yes)
				(allow_two_segments yes)
				(prefer_zone_connections yes)
			)
		)
		(pad "3" smd roundrect
			(at -0.387 0 90)
			(size 0.4 0.55)
			(layers "B.Cu" "B.Mask" "B.Paste")
			(roundrect_rratio 0.25)
			(net 1 "GND")
			(pintype "power_in")
			(teardrops
				(best_length_ratio 0.2)
				(max_length 1)
				(best_width_ratio 0.9)
				(max_width 2)
				(curved_edges yes)
				(filter_ratio 0.9)
				(enabled yes)
				(allow_two_segments yes)
				(prefer_zone_connections yes)
			)
		)
		(pad "4" smd roundrect
			(at -0.387 -0.498 90)
			(size 0.25 0.55)
			(layers "B.Cu" "B.Mask" "B.Paste")
			(roundrect_rratio 0.25)
			(net 106 "/OCuLink/PCIe_{x4}.TX3+")
			(pintype "passive")
			(teardrops
				(best_length_ratio 0.2)
				(max_length 1)
				(best_width_ratio 0.9)
				(max_width 2)
				(curved_edges yes)
				(filter_ratio 0.9)
				(enabled yes)
				(allow_two_segments yes)
				(prefer_zone_connections yes)
			)
		)
		(pad "5" smd roundrect
			(at -0.387 -0.998 90)
			(size 0.25 0.55)
			(layers "B.Cu" "B.Mask" "B.Paste")
			(roundrect_rratio 0.25)
			(net 98 "/OCuLink/PCIe_{x4}.TX3-")
			(pintype "passive")
			(teardrops
				(best_length_ratio 0.2)
				(max_length 1)
				(best_width_ratio 0.9)
				(max_width 2)
				(curved_edges yes)
				(filter_ratio 0.9)
				(enabled yes)
				(allow_two_segments yes)
				(prefer_zone_connections yes)
			)
		)
		(pad "6" smd roundrect
			(at 0.385 -0.998 90)
			(size 0.25 0.55)
			(layers "B.Cu" "B.Mask" "B.Paste")
			(roundrect_rratio 0.25)
			(net 98 "/OCuLink/PCIe_{x4}.TX3-")
			(pintype "passive")
			(teardrops
				(best_length_ratio 0.2)
				(max_length 1)
				(best_width_ratio 0.9)
				(max_width 2)
				(curved_edges yes)
				(filter_ratio 0.9)
				(enabled yes)
				(allow_two_segments yes)
				(prefer_zone_connections yes)
			)
		)
		(pad "7" smd roundrect
			(at 0.385 -0.498 90)
			(size 0.25 0.55)
			(layers "B.Cu" "B.Mask" "B.Paste")
			(roundrect_rratio 0.25)
			(net 106 "/OCuLink/PCIe_{x4}.TX3+")
			(pintype "passive")
			(teardrops
				(best_length_ratio 0.2)
				(max_length 1)
				(best_width_ratio 0.9)
				(max_width 2)
				(curved_edges yes)
				(filter_ratio 0.9)
				(enabled yes)
				(allow_two_segments yes)
				(prefer_zone_connections yes)
			)
		)
		(pad "8" smd roundrect
			(at 0.385 0 90)
			(size 0.4 0.55)
			(layers "B.Cu" "B.Mask" "B.Paste")
			(roundrect_rratio 0.25)
			(net 1 "GND")
			(pintype "passive")
			(teardrops
				(best_length_ratio 0.2)
				(max_length 1)
				(best_width_ratio 0.9)
				(max_width 2)
				(curved_edges yes)
				(filter_ratio 0.9)
				(enabled yes)
				(allow_two_segments yes)
				(prefer_zone_connections yes)
			)
		)
		(pad "9" smd roundrect
			(at 0.385 0.5 90)
			(size 0.25 0.55)
			(layers "B.Cu" "B.Mask" "B.Paste")
			(roundrect_rratio 0.25)
			(net 97 "/OCuLink/PCIe_{x4}.TX2-")
			(pintype "passive")
			(teardrops
				(best_length_ratio 0.2)
				(max_length 1)
				(best_width_ratio 0.9)
				(max_width 2)
				(curved_edges yes)
				(filter_ratio 0.9)
				(enabled yes)
				(allow_two_segments yes)
				(prefer_zone_connections yes)
			)
		)
		(pad "10" smd roundrect
			(at 0.385 1 90)
			(size 0.25 0.55)
			(layers "B.Cu" "B.Mask" "B.Paste")
			(roundrect_rratio 0.25)
			(net 104 "/OCuLink/PCIe_{x4}.TX2+")
			(pintype "passive")
			(teardrops
				(best_length_ratio 0.2)
				(max_length 1)
				(best_width_ratio 0.9)
				(max_width 2)
				(curved_edges yes)
				(filter_ratio 0.9)
				(enabled yes)
				(allow_two_segments yes)
				(prefer_zone_connections yes)
			)
		)
	)
	(footprint "antmicro-footprints:TP_SMD_0.75mm"
		(layer "B.Cu")
		(at 258.949999 87.01 180)
		(property "Reference" "TP14"
			(at 0.399999 -0.45 0)
			(layer "B.SilkS")
			(effects
				(font
					(size 0.7 0.7)
					(thickness 0.15)
				)
				(justify left bottom mirror)
			)
		)
		(property "Value" "TP_0.75mm_SMD"
			(at 0 -1.2 0)
			(layer "B.Fab")
			(effects
				(font
					(size 0.7 0.7)
					(thickness 0.15)
				)
				(justify left bottom mirror)
			)
		)
		(property "Author" "Antmicro"
			(at 517.899998 174.02 0)
			(layer "B.Fab")
			(hide yes)
			(effects
				(font
					(size 1 1)
					(thickness 0.15)
				)
				(justify mirror)
			)
		)
		(property "License" "Apache-2.0"
			(at 517.899998 174.02 0)
			(layer "B.Fab")
			(hide yes)
			(effects
				(font
					(size 1 1)
					(thickness 0.15)
				)
				(justify mirror)
			)
		)
		(property "MPN" ""
			(at 517.899998 174.02 0)
			(layer "B.Fab")
			(hide yes)
			(effects
				(font
					(size 1 1)
					(thickness 0.15)
				)
				(justify mirror)
			)
		)
		(property "Manufacturer" ""
			(at 517.899998 174.02 0)
			(layer "B.Fab")
			(hide yes)
			(effects
				(font
					(size 1 1)
					(thickness 0.15)
				)
				(justify mirror)
			)
		)
		(property "Public" "False"
			(at 517.899998 174.02 0)
			(layer "B.Fab")
			(hide yes)
			(effects
				(font
					(size 1 1)
					(thickness 0.15)
				)
				(justify mirror)
			)
		)
		(sheetname "Misc")
		(sheetfile "misc.kicad_sch")
		(attr exclude_from_pos_files exclude_from_bom)
		(fp_circle
			(center 0 0)
			(end 0.475 0)
			(stroke
				(width 0.05)
				(type default)
			)
			(fill no)
			(layer "B.CrtYd")
		)
		(pad "1" smd circle
			(at 0 0 180)
			(size 0.75 0.75)
			(layers "B.Cu" "B.Mask")
			(net 706 "Net-(U24-GPIO0)")
			(pinfunction "1")
			(pintype "passive")
			(teardrops
				(best_length_ratio 0.4)
				(max_length 1)
				(best_width_ratio 0.9)
				(max_width 2)
				(curved_edges yes)
				(filter_ratio 0.9)
				(enabled yes)
				(allow_two_segments yes)
				(prefer_zone_connections yes)
			)
		)
	)
	(footprint "antmicro-footprints:TP_SMD_0.75mm"
		(layer "B.Cu")
		(at 196.6 163.325)
		(property "Reference" "TP27"
			(at -0.15 -0.825 90)
			(layer "B.SilkS")
			(effects
				(font
					(size 0.7 0.7)
					(thickness 0.15)
				)
				(justify right top mirror)
			)
		)
		(property "Value" "TP_0.75mm_SMD"
			(at 3.225 -53.865 0)
			(layer "B.Fab")
			(hide yes)
			(effects
				(font
					(size 0.7 0.7)
					(thickness 0.15)
				)
				(justify right top mirror)
			)
		)
		(property "Author" "Antmicro"
			(at 413.9 313.02 0)
			(layer "B.Fab")
			(hide yes)
			(effects
				(font
					(size 1 1)
					(thickness 0.15)
				)
				(justify mirror)
			)
		)
		(property "License" "Apache-2.0"
			(at 413.9 313.02 0)
			(layer "B.Fab")
			(hide yes)
			(effects
				(font
					(size 1 1)
					(thickness 0.15)
				)
				(justify mirror)
			)
		)
		(property "MPN" ""
			(at 413.9 313.02 0)
			(layer "B.Fab")
			(hide yes)
			(effects
				(font
					(size 1 1)
					(thickness 0.15)
				)
				(justify mirror)
			)
		)
		(property "Manufacturer" ""
			(at 413.9 313.02 0)
			(layer "B.Fab")
			(hide yes)
			(effects
				(font
					(size 1 1)
					(thickness 0.15)
				)
				(justify mirror)
			)
		)
		(property "Public" "False"
			(at 413.9 313.02 0)
			(layer "B.Fab")
			(hide yes)
			(effects
				(font
					(size 1 1)
					(thickness 0.15)
				)
				(justify mirror)
			)
		)
		(sheetname "Com Express 7 MGMT")
		(sheetfile "com_express_7_mgmt.kicad_sch")
		(attr exclude_from_pos_files exclude_from_bom)
		(fp_circle
			(center 0 0)
			(end 0.475 0)
			(stroke
				(width 0.05)
				(type default)
			)
			(fill no)
			(layer "B.CrtYd")
		)
		(pad "1" smd circle
			(at 0 0)
			(size 0.75 0.75)
			(layers "B.Cu" "B.Mask")
			(net 318 "Net-(J12D-LPC_SERIRQ{slash}~{ESPI_CS1})")
			(pinfunction "1")
			(pintype "passive")
			(teardrops
				(best_length_ratio 0.4)
				(max_length 1)
				(best_width_ratio 0.9)
				(max_width 2)
				(curved_edges yes)
				(filter_ratio 0.9)
				(enabled yes)
				(allow_two_segments yes)
				(prefer_zone_connections yes)
			)
		)
	)
	(footprint "antmicro-footprints:C_0402_1005Metric"
		(layer "B.Cu")
		(at 125.22 149.26 -90)
		(descr "Capacitor SMD 0402")
		(tags "capacitor SMD 0402")
		(property "Reference" "C176"
			(at -1.3 1.47 90)
			(layer "B.SilkS")
			(effects
				(font
					(size 0.7 0.7)
					(thickness 0.15)
				)
				(justify left bottom mirror)
			)
		)
		(property "Value" "C_100n_0402"
			(at -1.022927 -2.155213 90)
			(layer "B.Fab")
			(effects
				(font
					(size 0.7 0.7)
					(thickness 0.15)
				)
				(justify left bottom mirror)
			)
		)
		(property "Datasheet" "https://www.murata.com/products/productdetail?partno=GRM155R61H104KE14%23"
			(at 0 0 270)
			(layer "F.Fab")
			(hide yes)
			(effects
				(font
					(size 1.27 1.27)
					(thickness 0.15)
				)
			)
		)
		(property "Author" "Antmicro"
			(at -24.04 274.48 0)
			(layer "B.Fab")
			(hide yes)
			(effects
				(font
					(size 1 1)
					(thickness 0.15)
				)
				(justify mirror)
			)
		)
		(property "Dielectric" "X5R"
			(at -24.04 274.48 0)
			(layer "B.Fab")
			(hide yes)
			(effects
				(font
					(size 1 1)
					(thickness 0.15)
				)
				(justify mirror)
			)
		)
		(property "License" "Apache-2.0"
			(at -24.04 274.48 0)
			(layer "B.Fab")
			(hide yes)
			(effects
				(font
					(size 1 1)
					(thickness 0.15)
				)
				(justify mirror)
			)
		)
		(property "MPN" "GRM155R61H104KE14D"
			(at -24.04 274.48 0)
			(layer "B.Fab")
			(hide yes)
			(effects
				(font
					(size 1 1)
					(thickness 0.15)
				)
				(justify mirror)
			)
		)
		(property "Manufacturer" "Murata"
			(at -24.04 274.48 0)
			(layer "B.Fab")
			(hide yes)
			(effects
				(font
					(size 1 1)
					(thickness 0.15)
				)
				(justify mirror)
			)
		)
		(property "Public" "False"
			(at -24.04 274.48 0)
			(layer "B.Fab")
			(hide yes)
			(effects
				(font
					(size 1 1)
					(thickness 0.15)
				)
				(justify mirror)
			)
		)
		(property "Val" "100n"
			(at -24.04 274.48 0)
			(layer "B.Fab")
			(hide yes)
			(effects
				(font
					(size 1 1)
					(thickness 0.15)
				)
				(justify mirror)
			)
		)
		(property "Voltage" "50V"
			(at -24.04 274.48 0)
			(layer "B.Fab")
			(hide yes)
			(effects
				(font
					(size 1 1)
					(thickness 0.15)
				)
				(justify mirror)
			)
		)
		(sheetname "KR to SFI #2")
		(sheetfile "kr_sfi.kicad_sch")
		(attr smd)
		(fp_rect
			(start -0.925 0.47)
			(end 0.925 -0.47)
			(stroke
				(width 0.05)
				(type default)
			)
			(fill no)
			(layer "B.CrtYd")
		)
		(fp_line
			(start -0.494 0.25)
			(end -0.494 -0.248)
			(stroke
				(width 0.15)
				(type solid)
			)
			(layer "B.Fab")
		)
		(fp_line
			(start 0.504 0.25)
			(end -0.494 0.25)
			(stroke
				(width 0.15)
				(type solid)
			)
			(layer "B.Fab")
		)
		(fp_line
			(start -0.494 -0.248)
			(end 0.504 -0.248)
			(stroke
				(width 0.15)
				(type solid)
			)
			(layer "B.Fab")
		)
		(fp_line
			(start 0.504 -0.248)
			(end 0.504 0.25)
			(stroke
				(width 0.15)
				(type solid)
			)
			(layer "B.Fab")
		)
		(pad "1" smd roundrect
			(at -0.48 0 270)
			(size 0.59 0.64)
			(layers "B.Cu" "B.Mask" "B.Paste")
			(roundrect_rratio 0.25)
			(net 1 "GND")
			(pintype "passive")
			(teardrops
				(best_length_ratio 0.2)
				(max_length 1)
				(best_width_ratio 0.9)
				(max_width 2)
				(curved_edges yes)
				(filter_ratio 0.9)
				(enabled yes)
				(allow_two_segments yes)
				(prefer_zone_connections yes)
			)
		)
		(pad "2" smd roundrect
			(at 0.48 0 270)
			(size 0.59 0.64)
			(layers "B.Cu" "B.Mask" "B.Paste")
			(roundrect_rratio 0.25)
			(net 2 "+3V3")
			(pintype "passive")
			(teardrops
				(best_length_ratio 0.2)
				(max_length 1)
				(best_width_ratio 0.9)
				(max_width 2)
				(curved_edges yes)
				(filter_ratio 0.9)
				(enabled yes)
				(allow_two_segments yes)
				(prefer_zone_connections yes)
			)
		)
	)
	(footprint "antmicro-footprints:C_0603_1608Metric"
		(layer "B.Cu")
		(at 148.7 88.58 180)
		(descr "Capacitor SMD 0603")
		(tags "capacitor 0603")
		(property "Reference" "C82"
			(at -3.3 -0.48 0)
			(layer "B.SilkS")
			(effects
				(font
					(size 0.7 0.7)
					(thickness 0.15)
				)
				(justify left bottom mirror)
			)
		)
		(property "Value" "C_22u_16V_0603"
			(at -1.42757 -1.770288 0)
			(layer "B.Fab")
			(effects
				(font
					(size 0.7 0.7)
					(thickness 0.15)
				)
				(justify left bottom mirror)
			)
		)
		(property "Datasheet" "https://product.samsungsem.com/mlcc/CL10A226MO7JZN.do"
			(at 0 0 180)
			(layer "F.Fab")
			(hide yes)
			(effects
				(font
					(size 1.27 1.27)
					(thickness 0.15)
				)
			)
		)
		(property "Author" "Antmicro"
			(at 297.4 177.16 0)
			(layer "B.Fab")
			(hide yes)
			(effects
				(font
					(size 1 1)
					(thickness 0.15)
				)
				(justify mirror)
			)
		)
		(property "Dielectric" ""
			(at 297.4 177.16 0)
			(layer "B.Fab")
			(hide yes)
			(effects
				(font
					(size 1 1)
					(thickness 0.15)
				)
				(justify mirror)
			)
		)
		(property "License" "Apache-2.0"
			(at 297.4 177.16 0)
			(layer "B.Fab")
			(hide yes)
			(effects
				(font
					(size 1 1)
					(thickness 0.15)
				)
				(justify mirror)
			)
		)
		(property "MPN" "CL10A226MO7JZNC"
			(at 297.4 177.16 0)
			(layer "B.Fab")
			(hide yes)
			(effects
				(font
					(size 1 1)
					(thickness 0.15)
				)
				(justify mirror)
			)
		)
		(property "Manufacturer" "Samsung Electro-Mechanics"
			(at 297.4 177.16 0)
			(layer "B.Fab")
			(hide yes)
			(effects
				(font
					(size 1 1)
					(thickness 0.15)
				)
				(justify mirror)
			)
		)
		(property "Public" "False"
			(at 297.4 177.16 0)
			(layer "B.Fab")
			(hide yes)
			(effects
				(font
					(size 1 1)
					(thickness 0.15)
				)
				(justify mirror)
			)
		)
		(property "Val" "22u"
			(at 297.4 177.16 0)
			(layer "B.Fab")
			(hide yes)
			(effects
				(font
					(size 1 1)
					(thickness 0.15)
				)
				(justify mirror)
			)
		)
		(property "Voltage" "16V"
			(at 297.4 177.16 0)
			(layer "B.Fab")
			(hide yes)
			(effects
				(font
					(size 1 1)
					(thickness 0.15)
				)
				(justify mirror)
			)
		)
		(sheetname "M.2 key E")
		(sheetfile "m2keye.kicad_sch")
		(attr smd)
		(fp_line
			(start 0.15 0.4)
			(end -0.15 0.4)
			(stroke
				(width 0.15)
				(type solid)
			)
			(layer "B.SilkS")
		)
		(fp_line
			(start 0.15 -0.4)
			(end -0.15 -0.4)
			(stroke
				(width 0.15)
				(type solid)
			)
			(layer "B.SilkS")
		)
		(fp_rect
			(start -1.25 0.65)
			(end 1.25 -0.65)
			(stroke
				(width 0.05)
				(type solid)
			)
			(fill no)
			(layer "B.CrtYd")
		)
		(fp_rect
			(start -0.8 0.4)
			(end 0.8 -0.4)
			(stroke
				(width 0.15)
				(type solid)
			)
			(fill no)
			(layer "B.Fab")
		)
		(pad "1" smd roundrect
			(at -0.7 0 180)
			(size 0.8 1)
			(layers "B.Cu" "B.Mask" "B.Paste")
			(roundrect_rratio 0.2)
			(net 1 "GND")
			(pintype "passive")
			(teardrops
				(best_length_ratio 0.2)
				(max_length 1)
				(best_width_ratio 0.9)
				(max_width 2)
				(curved_edges yes)
				(filter_ratio 0.9)
				(enabled yes)
				(allow_two_segments yes)
				(prefer_zone_connections yes)
			)
		)
		(pad "2" smd roundrect
			(at 0.7 0 180)
			(size 0.8 1)
			(layers "B.Cu" "B.Mask" "B.Paste")
			(roundrect_rratio 0.2)
			(net 2 "+3V3")
			(pintype "passive")
			(teardrops
				(best_length_ratio 0.2)
				(max_length 1)
				(best_width_ratio 0.9)
				(max_width 2)
				(curved_edges yes)
				(filter_ratio 0.9)
				(enabled yes)
				(allow_two_segments yes)
				(prefer_zone_connections yes)
			)
		)
	)
	(footprint "antmicro-footprints:C_0402_1005Metric"
		(layer "B.Cu")
		(at 150.25 160.23 -90)
		(descr "Capacitor SMD 0402")
		(tags "capacitor SMD 0402")
		(property "Reference" "C26"
			(at -2.97 -0.45 90)
			(layer "B.SilkS")
			(effects
				(font
					(size 0.7 0.7)
					(thickness 0.15)
				)
				(justify left bottom mirror)
			)
		)
		(property "Value" "C_100n_0402"
			(at -1.022927 -2.155213 90)
			(layer "B.Fab")
			(effects
				(font
					(size 0.7 0.7)
					(thickness 0.15)
				)
				(justify left bottom mirror)
			)
		)
		(property "Datasheet" "https://www.murata.com/products/productdetail?partno=GRM155R61H104KE14%23"
			(at 0 0 270)
			(layer "F.Fab")
			(hide yes)
			(effects
				(font
					(size 1.27 1.27)
					(thickness 0.15)
				)
			)
		)
		(property "Author" "Antmicro"
			(at -9.98 310.48 0)
			(layer "B.Fab")
			(hide yes)
			(effects
				(font
					(size 1 1)
					(thickness 0.15)
				)
				(justify mirror)
			)
		)
		(property "Dielectric" "X5R"
			(at -9.98 310.48 0)
			(layer "B.Fab")
			(hide yes)
			(effects
				(font
					(size 1 1)
					(thickness 0.15)
				)
				(justify mirror)
			)
		)
		(property "License" "Apache-2.0"
			(at -9.98 310.48 0)
			(layer "B.Fab")
			(hide yes)
			(effects
				(font
					(size 1 1)
					(thickness 0.15)
				)
				(justify mirror)
			)
		)
		(property "MPN" "GRM155R61H104KE14D"
			(at -9.98 310.48 0)
			(layer "B.Fab")
			(hide yes)
			(effects
				(font
					(size 1 1)
					(thickness 0.15)
				)
				(justify mirror)
			)
		)
		(property "Manufacturer" "Murata"
			(at -9.98 310.48 0)
			(layer "B.Fab")
			(hide yes)
			(effects
				(font
					(size 1 1)
					(thickness 0.15)
				)
				(justify mirror)
			)
		)
		(property "Public" "False"
			(at -9.98 310.48 0)
			(layer "B.Fab")
			(hide yes)
			(effects
				(font
					(size 1 1)
					(thickness 0.15)
				)
				(justify mirror)
			)
		)
		(property "Val" "100n"
			(at -9.98 310.48 0)
			(layer "B.Fab")
			(hide yes)
			(effects
				(font
					(size 1 1)
					(thickness 0.15)
				)
				(justify mirror)
			)
		)
		(property "Voltage" "50V"
			(at -9.98 310.48 0)
			(layer "B.Fab")
			(hide yes)
			(effects
				(font
					(size 1 1)
					(thickness 0.15)
				)
				(justify mirror)
			)
		)
		(sheetname "2xSFP+")
		(sheetfile "2xSFP+.kicad_sch")
		(attr smd)
		(fp_rect
			(start -0.925 0.47)
			(end 0.925 -0.47)
			(stroke
				(width 0.05)
				(type default)
			)
			(fill no)
			(layer "B.CrtYd")
		)
		(fp_line
			(start -0.494 0.25)
			(end -0.494 -0.248)
			(stroke
				(width 0.15)
				(type solid)
			)
			(layer "B.Fab")
		)
		(fp_line
			(start 0.504 0.25)
			(end -0.494 0.25)
			(stroke
				(width 0.15)
				(type solid)
			)
			(layer "B.Fab")
		)
		(fp_line
			(start -0.494 -0.248)
			(end 0.504 -0.248)
			(stroke
				(width 0.15)
				(type solid)
			)
			(layer "B.Fab")
		)
		(fp_line
			(start 0.504 -0.248)
			(end 0.504 0.25)
			(stroke
				(width 0.15)
				(type solid)
			)
			(layer "B.Fab")
		)
		(pad "1" smd roundrect
			(at -0.48 0 270)
			(size 0.59 0.64)
			(layers "B.Cu" "B.Mask" "B.Paste")
			(roundrect_rratio 0.25)
			(net 1 "GND")
			(pintype "passive")
			(teardrops
				(best_length_ratio 0.2)
				(max_length 1)
				(best_width_ratio 0.9)
				(max_width 2)
				(curved_edges yes)
				(filter_ratio 0.9)
				(enabled yes)
				(allow_two_segments yes)
				(prefer_zone_connections yes)
			)
		)
		(pad "2" smd roundrect
			(at 0.48 0 270)
			(size 0.59 0.64)
			(layers "B.Cu" "B.Mask" "B.Paste")
			(roundrect_rratio 0.25)
			(net 2 "+3V3")
			(pintype "passive")
			(teardrops
				(best_length_ratio 0.2)
				(max_length 1)
				(best_width_ratio 0.9)
				(max_width 2)
				(curved_edges yes)
				(filter_ratio 0.9)
				(enabled yes)
				(allow_two_segments yes)
				(prefer_zone_connections yes)
			)
		)
	)
	(footprint "antmicro-footprints:C_0402_1005Metric"
		(layer "B.Cu")
		(at 109.811 165.869 180)
		(descr "Capacitor SMD 0402")
		(tags "capacitor SMD 0402")
		(property "Reference" "C146"
			(at -3.689 -0.441 0)
			(layer "B.SilkS")
			(effects
				(font
					(size 0.7 0.7)
					(thickness 0.15)
				)
				(justify left bottom mirror)
			)
		)
		(property "Value" "C_220n_0402"
			(at -1.022927 -2.155213 0)
			(layer "B.Fab")
			(effects
				(font
					(size 0.7 0.7)
					(thickness 0.15)
				)
				(justify left bottom mirror)
			)
		)
		(property "Datasheet" "https://www.yageo.com/en/Chart/Download/pdf/CC0402KRX5R6BB224"
			(at 0 0 180)
			(layer "F.Fab")
			(hide yes)
			(effects
				(font
					(size 1.27 1.27)
					(thickness 0.15)
				)
			)
		)
		(property "Author" "Antmicro"
			(at 219.622 331.738 0)
			(layer "B.Fab")
			(hide yes)
			(effects
				(font
					(size 1 1)
					(thickness 0.15)
				)
				(justify mirror)
			)
		)
		(property "Dielectric" ""
			(at 219.622 331.738 0)
			(layer "B.Fab")
			(hide yes)
			(effects
				(font
					(size 1 1)
					(thickness 0.15)
				)
				(justify mirror)
			)
		)
		(property "License" "Apache-2.0"
			(at 219.622 331.738 0)
			(layer "B.Fab")
			(hide yes)
			(effects
				(font
					(size 1 1)
					(thickness 0.15)
				)
				(justify mirror)
			)
		)
		(property "MPN" "CC0402KRX5R6BB224"
			(at 219.622 331.738 0)
			(layer "B.Fab")
			(hide yes)
			(effects
				(font
					(size 1 1)
					(thickness 0.15)
				)
				(justify mirror)
			)
		)
		(property "Manufacturer" "YAGEO"
			(at 219.622 331.738 0)
			(layer "B.Fab")
			(hide yes)
			(effects
				(font
					(size 1 1)
					(thickness 0.15)
				)
				(justify mirror)
			)
		)
		(property "Public" "False"
			(at 219.622 331.738 0)
			(layer "B.Fab")
			(hide yes)
			(effects
				(font
					(size 1 1)
					(thickness 0.15)
				)
				(justify mirror)
			)
		)
		(property "Val" "220n"
			(at 219.622 331.738 0)
			(layer "B.Fab")
			(hide yes)
			(effects
				(font
					(size 1 1)
					(thickness 0.15)
				)
				(justify mirror)
			)
		)
		(property "Voltage" ""
			(at 219.622 331.738 0)
			(layer "B.Fab")
			(hide yes)
			(effects
				(font
					(size 1 1)
					(thickness 0.15)
				)
				(justify mirror)
			)
		)
		(sheetname "PCIe redriver")
		(sheetfile "pcie_redriver.kicad_sch")
		(attr smd)
		(fp_rect
			(start -0.925 0.47)
			(end 0.925 -0.47)
			(stroke
				(width 0.05)
				(type default)
			)
			(fill no)
			(layer "B.CrtYd")
		)
		(fp_line
			(start 0.504 0.25)
			(end -0.494 0.25)
			(stroke
				(width 0.15)
				(type solid)
			)
			(layer "B.Fab")
		)
		(fp_line
			(start 0.504 -0.248)
			(end 0.504 0.25)
			(stroke
				(width 0.15)
				(type solid)
			)
			(layer "B.Fab")
		)
		(fp_line
			(start -0.494 0.25)
			(end -0.494 -0.248)
			(stroke
				(width 0.15)
				(type solid)
			)
			(layer "B.Fab")
		)
		(fp_line
			(start -0.494 -0.248)
			(end 0.504 -0.248)
			(stroke
				(width 0.15)
				(type solid)
			)
			(layer "B.Fab")
		)
		(pad "1" smd roundrect
			(at -0.48 0 180)
			(size 0.59 0.64)
			(layers "B.Cu" "B.Mask" "B.Paste")
			(roundrect_rratio 0.25)
			(net 966 "/PCIe redriver/PCIe_{O}_C.TX0-")
			(pintype "passive")
			(teardrops
				(best_length_ratio 0.2)
				(max_length 1)
				(best_width_ratio 0.9)
				(max_width 2)
				(curved_edges yes)
				(filter_ratio 0.9)
				(enabled yes)
				(allow_two_segments yes)
				(prefer_zone_connections yes)
			)
		)
		(pad "2" smd roundrect
			(at 0.48 0 180)
			(size 0.59 0.64)
			(layers "B.Cu" "B.Mask" "B.Paste")
			(roundrect_rratio 0.25)
			(net 95 "/OCuLink/PCIe_{x4}.TX0-")
			(pintype "passive")
			(teardrops
				(best_length_ratio 0.2)
				(max_length 1)
				(best_width_ratio 0.9)
				(max_width 2)
				(curved_edges yes)
				(filter_ratio 0.9)
				(enabled yes)
				(allow_two_segments yes)
				(prefer_zone_connections yes)
			)
		)
	)
	(footprint "antmicro-footprints:R_0402_1005Metric"
		(layer "B.Cu")
		(at 145.05 169.16 -90)
		(descr "Resistor SMD 0402")
		(tags "resistor SMD 0402")
		(property "Reference" "R53"
			(at -3.9 13.5 90)
			(layer "B.SilkS")
			(effects
				(font
					(size 0.7 0.7)
					(thickness 0.15)
				)
				(justify left bottom mirror)
			)
		)
		(property "Value" "R_1k_0402"
			(at -1.011843 -1.772047 90)
			(layer "B.Fab")
			(effects
				(font
					(size 0.7 0.7)
					(thickness 0.15)
				)
				(justify left bottom mirror)
			)
		)
		(property "Datasheet" "https://www.bourns.com/docs/product-datasheets/cr.pdf"
			(at 0 0 270)
			(layer "F.Fab")
			(hide yes)
			(effects
				(font
					(size 1.27 1.27)
					(thickness 0.15)
				)
			)
		)
		(property "Author" "Antmicro"
			(at -24.11 314.21 0)
			(layer "B.Fab")
			(hide yes)
			(effects
				(font
					(size 1 1)
					(thickness 0.15)
				)
				(justify mirror)
			)
		)
		(property "License" "Apache-2.0"
			(at -24.11 314.21 0)
			(layer "B.Fab")
			(hide yes)
			(effects
				(font
					(size 1 1)
					(thickness 0.15)
				)
				(justify mirror)
			)
		)
		(property "MPN" "CR0402-FX-1001GLF"
			(at -24.11 314.21 0)
			(layer "B.Fab")
			(hide yes)
			(effects
				(font
					(size 1 1)
					(thickness 0.15)
				)
				(justify mirror)
			)
		)
		(property "Manufacturer" "Bourns"
			(at -24.11 314.21 0)
			(layer "B.Fab")
			(hide yes)
			(effects
				(font
					(size 1 1)
					(thickness 0.15)
				)
				(justify mirror)
			)
		)
		(property "Public" "False"
			(at -24.11 314.21 0)
			(layer "B.Fab")
			(hide yes)
			(effects
				(font
					(size 1 1)
					(thickness 0.15)
				)
				(justify mirror)
			)
		)
		(property "Tolerance" "1%"
			(at -24.11 314.21 0)
			(layer "B.Fab")
			(hide yes)
			(effects
				(font
					(size 1 1)
					(thickness 0.15)
				)
				(justify mirror)
			)
		)
		(property "Val" "1k"
			(at -24.11 314.21 0)
			(layer "B.Fab")
			(hide yes)
			(effects
				(font
					(size 1 1)
					(thickness 0.15)
				)
				(justify mirror)
			)
		)
		(sheetname "2xSFP+")
		(sheetfile "2xSFP+.kicad_sch")
		(attr smd)
		(fp_rect
			(start -0.925 0.47)
			(end 0.925 -0.47)
			(stroke
				(width 0.05)
				(type default)
			)
			(fill no)
			(layer "B.CrtYd")
		)
		(fp_rect
			(start -0.5 0.25)
			(end 0.5 -0.25)
			(stroke
				(width 0.15)
				(type solid)
			)
			(fill no)
			(layer "B.Fab")
		)
		(pad "1" smd roundrect
			(at -0.48 0 270)
			(size 0.59 0.64)
			(layers "B.Cu" "B.Mask" "B.Paste")
			(roundrect_rratio 0.25)
			(net 168 "Net-(J2A-RX_{LOS})")
			(pintype "passive")
			(teardrops
				(best_length_ratio 0.2)
				(max_length 1)
				(best_width_ratio 0.9)
				(max_width 2)
				(curved_edges yes)
				(filter_ratio 0.9)
				(enabled yes)
				(allow_two_segments yes)
				(prefer_zone_connections yes)
			)
		)
		(pad "2" smd roundrect
			(at 0.48 0 270)
			(size 0.59 0.64)
			(layers "B.Cu" "B.Mask" "B.Paste")
			(roundrect_rratio 0.25)
			(net 2 "+3V3")
			(pintype "passive")
			(teardrops
				(best_length_ratio 0.2)
				(max_length 1)
				(best_width_ratio 0.9)
				(max_width 2)
				(curved_edges yes)
				(filter_ratio 0.9)
				(enabled yes)
				(allow_two_segments yes)
				(prefer_zone_connections yes)
			)
		)
	)
	(footprint "antmicro-footprints:R_0402_1005Metric"
		(layer "B.Cu")
		(at 309.824999 101.76 90)
		(descr "Resistor SMD 0402")
		(tags "resistor SMD 0402")
		(property "Reference" "R86"
			(at 3.06 0.455001 270)
			(layer "B.SilkS")
			(effects
				(font
					(size 0.7 0.7)
					(thickness 0.15)
				)
				(justify left bottom mirror)
			)
		)
		(property "Value" "R_10k_0402"
			(at -1.011843 -1.772047 90)
			(layer "B.Fab")
			(effects
				(font
					(size 0.7 0.7)
					(thickness 0.15)
				)
				(justify right bottom mirror)
			)
		)
		(property "Datasheet" "https://www.bourns.com/docs/product-datasheets/cr.pdf"
			(at 0 0 90)
			(layer "F.Fab")
			(hide yes)
			(effects
				(font
					(size 1.27 1.27)
					(thickness 0.15)
				)
			)
		)
		(property "Author" "Antmicro"
			(at 411.584999 -208.064999 0)
			(layer "B.Fab")
			(hide yes)
			(effects
				(font
					(size 1 1)
					(thickness 0.15)
				)
				(justify mirror)
			)
		)
		(property "License" "Apache-2.0"
			(at 411.584999 -208.064999 0)
			(layer "B.Fab")
			(hide yes)
			(effects
				(font
					(size 1 1)
					(thickness 0.15)
				)
				(justify mirror)
			)
		)
		(property "MPN" "CR0402-FX-1002GLF"
			(at 411.584999 -208.064999 0)
			(layer "B.Fab")
			(hide yes)
			(effects
				(font
					(size 1 1)
					(thickness 0.15)
				)
				(justify mirror)
			)
		)
		(property "Manufacturer" "Bourns"
			(at 411.584999 -208.064999 0)
			(layer "B.Fab")
			(hide yes)
			(effects
				(font
					(size 1 1)
					(thickness 0.15)
				)
				(justify mirror)
			)
		)
		(property "Public" "False"
			(at 411.584999 -208.064999 0)
			(layer "B.Fab")
			(hide yes)
			(effects
				(font
					(size 1 1)
					(thickness 0.15)
				)
				(justify mirror)
			)
		)
		(property "Tolerance" "1%"
			(at 411.584999 -208.064999 0)
			(layer "B.Fab")
			(hide yes)
			(effects
				(font
					(size 1 1)
					(thickness 0.15)
				)
				(justify mirror)
			)
		)
		(property "Val" "10k"
			(at 411.584999 -208.064999 0)
			(layer "B.Fab")
			(hide yes)
			(effects
				(font
					(size 1 1)
					(thickness 0.15)
				)
				(justify mirror)
			)
		)
		(sheetname "Power")
		(sheetfile "power.kicad_sch")
		(attr smd)
		(fp_rect
			(start -0.925 0.47)
			(end 0.925 -0.47)
			(stroke
				(width 0.05)
				(type default)
			)
			(fill no)
			(layer "B.CrtYd")
		)
		(fp_rect
			(start -0.5 0.25)
			(end 0.5 -0.25)
			(stroke
				(width 0.15)
				(type solid)
			)
			(fill no)
			(layer "B.Fab")
		)
		(pad "1" smd roundrect
			(at -0.48 0 90)
			(size 0.59 0.64)
			(layers "B.Cu" "B.Mask" "B.Paste")
			(roundrect_rratio 0.25)
			(net 574 "Net-(U19-EN)")
			(pintype "passive")
			(teardrops
				(best_length_ratio 0.2)
				(max_length 1)
				(best_width_ratio 0.9)
				(max_width 2)
				(curved_edges yes)
				(filter_ratio 0.9)
				(enabled yes)
				(allow_two_segments yes)
				(prefer_zone_connections yes)
			)
		)
		(pad "2" smd roundrect
			(at 0.48 0 90)
			(size 0.59 0.64)
			(layers "B.Cu" "B.Mask" "B.Paste")
			(roundrect_rratio 0.25)
			(net 52 "+5V")
			(pintype "passive")
			(teardrops
				(best_length_ratio 0.2)
				(max_length 1)
				(best_width_ratio 0.9)
				(max_width 2)
				(curved_edges yes)
				(filter_ratio 0.9)
				(enabled yes)
				(allow_two_segments yes)
				(prefer_zone_connections yes)
			)
		)
	)
	(footprint "antmicro-footprints:R_0402_1005Metric"
		(layer "B.Cu")
		(at 123.4 109.81 180)
		(descr "Resistor SMD 0402")
		(tags "resistor SMD 0402")
		(property "Reference" "R3"
			(at -2.35 -0.4 0)
			(layer "B.SilkS")
			(effects
				(font
					(size 0.7 0.7)
					(thickness 0.15)
				)
				(justify left bottom mirror)
			)
		)
		(property "Value" "R_0R_0402"
			(at -1.011843 -1.772047 0)
			(layer "B.Fab")
			(effects
				(font
					(size 0.7 0.7)
					(thickness 0.15)
				)
				(justify left bottom mirror)
			)
		)
		(property "Datasheet" "https://industrial.panasonic.com/cdbs/www-data/pdf/RDA0000/AOA0000C301.pdf"
			(at 0 0 180)
			(layer "F.Fab")
			(hide yes)
			(effects
				(font
					(size 1.27 1.27)
					(thickness 0.15)
				)
			)
		)
		(property "Author" "Antmicro"
			(at 246.8 219.62 0)
			(layer "B.Fab")
			(hide yes)
			(effects
				(font
					(size 1 1)
					(thickness 0.15)
				)
				(justify mirror)
			)
		)
		(property "Current" "1A"
			(at 246.8 219.62 0)
			(layer "B.Fab")
			(hide yes)
			(effects
				(font
					(size 1 1)
					(thickness 0.15)
				)
				(justify mirror)
			)
		)
		(property "License" "Apache-2.0"
			(at 246.8 219.62 0)
			(layer "B.Fab")
			(hide yes)
			(effects
				(font
					(size 1 1)
					(thickness 0.15)
				)
				(justify mirror)
			)
		)
		(property "MPN" "ERJ2GE0R00X"
			(at 246.8 219.62 0)
			(layer "B.Fab")
			(hide yes)
			(effects
				(font
					(size 1 1)
					(thickness 0.15)
				)
				(justify mirror)
			)
		)
		(property "Manufacturer" "Panasonic"
			(at 246.8 219.62 0)
			(layer "B.Fab")
			(hide yes)
			(effects
				(font
					(size 1 1)
					(thickness 0.15)
				)
				(justify mirror)
			)
		)
		(property "Public" "False"
			(at 246.8 219.62 0)
			(layer "B.Fab")
			(hide yes)
			(effects
				(font
					(size 1 1)
					(thickness 0.15)
				)
				(justify mirror)
			)
		)
		(property "Tolerance" ""
			(at 246.8 219.62 0)
			(layer "B.Fab")
			(hide yes)
			(effects
				(font
					(size 1 1)
					(thickness 0.15)
				)
				(justify mirror)
			)
		)
		(property "Val" "0R"
			(at 246.8 219.62 0)
			(layer "B.Fab")
			(hide yes)
			(effects
				(font
					(size 1 1)
					(thickness 0.15)
				)
				(justify mirror)
			)
		)
		(sheetname "2xUSB3.0+RJ45")
		(sheetfile "usb3+rj45.kicad_sch")
		(attr smd dnp)
		(fp_rect
			(start -0.925 0.47)
			(end 0.925 -0.47)
			(stroke
				(width 0.05)
				(type default)
			)
			(fill no)
			(layer "B.CrtYd")
		)
		(fp_rect
			(start -0.5 0.25)
			(end 0.5 -0.25)
			(stroke
				(width 0.15)
				(type solid)
			)
			(fill no)
			(layer "B.Fab")
		)
		(pad "1" smd roundrect
			(at -0.48 0 180)
			(size 0.59 0.64)
			(layers "B.Cu" "B.Mask" "B.Paste")
			(roundrect_rratio 0.25)
			(net 288 "/2xUSB3.0+RJ45/~{GBE0_LINK_1000}")
			(pintype "passive")
			(teardrops
				(best_length_ratio 0.2)
				(max_length 1)
				(best_width_ratio 0.9)
				(max_width 2)
				(curved_edges yes)
				(filter_ratio 0.9)
				(enabled yes)
				(allow_two_segments yes)
				(prefer_zone_connections yes)
			)
		)
		(pad "2" smd roundrect
			(at 0.48 0 180)
			(size 0.59 0.64)
			(layers "B.Cu" "B.Mask" "B.Paste")
			(roundrect_rratio 0.25)
			(net 156 "Net-(J1A-LED_D3)")
			(pintype "passive")
			(teardrops
				(best_length_ratio 0.2)
				(max_length 1)
				(best_width_ratio 0.9)
				(max_width 2)
				(curved_edges yes)
				(filter_ratio 0.9)
				(enabled yes)
				(allow_two_segments yes)
				(prefer_zone_connections yes)
			)
		)
	)
	(footprint "antmicro-footprints:C_0402_1005Metric"
		(layer "B.Cu")
		(at 130.79 132.87 180)
		(descr "Capacitor SMD 0402")
		(tags "capacitor SMD 0402")
		(property "Reference" "C197"
			(at 0.49 4.96 0)
			(layer "B.SilkS")
			(effects
				(font
					(size 0.7 0.7)
					(thickness 0.15)
				)
				(justify left bottom mirror)
			)
		)
		(property "Value" "C_100n_0402"
			(at -1.022927 -2.155213 0)
			(layer "B.Fab")
			(effects
				(font
					(size 0.7 0.7)
					(thickness 0.15)
				)
				(justify left bottom mirror)
			)
		)
		(property "Datasheet" "https://www.murata.com/products/productdetail?partno=GRM155R61H104KE14%23"
			(at 0 0 180)
			(layer "F.Fab")
			(hide yes)
			(effects
				(font
					(size 1.27 1.27)
					(thickness 0.15)
				)
			)
		)
		(property "Author" "Antmicro"
			(at 261.58 265.74 0)
			(layer "B.Fab")
			(hide yes)
			(effects
				(font
					(size 1 1)
					(thickness 0.15)
				)
				(justify mirror)
			)
		)
		(property "Dielectric" "X5R"
			(at 261.58 265.74 0)
			(layer "B.Fab")
			(hide yes)
			(effects
				(font
					(size 1 1)
					(thickness 0.15)
				)
				(justify mirror)
			)
		)
		(property "License" "Apache-2.0"
			(at 261.58 265.74 0)
			(layer "B.Fab")
			(hide yes)
			(effects
				(font
					(size 1 1)
					(thickness 0.15)
				)
				(justify mirror)
			)
		)
		(property "MPN" "GRM155R61H104KE14D"
			(at 261.58 265.74 0)
			(layer "B.Fab")
			(hide yes)
			(effects
				(font
					(size 1 1)
					(thickness 0.15)
				)
				(justify mirror)
			)
		)
		(property "Manufacturer" "Murata"
			(at 261.58 265.74 0)
			(layer "B.Fab")
			(hide yes)
			(effects
				(font
					(size 1 1)
					(thickness 0.15)
				)
				(justify mirror)
			)
		)
		(property "Public" "False"
			(at 261.58 265.74 0)
			(layer "B.Fab")
			(hide yes)
			(effects
				(font
					(size 1 1)
					(thickness 0.15)
				)
				(justify mirror)
			)
		)
		(property "Val" "100n"
			(at 261.58 265.74 0)
			(layer "B.Fab")
			(hide yes)
			(effects
				(font
					(size 1 1)
					(thickness 0.15)
				)
				(justify mirror)
			)
		)
		(property "Voltage" "50V"
			(at 261.58 265.74 0)
			(layer "B.Fab")
			(hide yes)
			(effects
				(font
					(size 1 1)
					(thickness 0.15)
				)
				(justify mirror)
			)
		)
		(sheetname "KR to SFI #2")
		(sheetfile "kr_sfi.kicad_sch")
		(attr smd)
		(fp_rect
			(start -0.925 0.47)
			(end 0.925 -0.47)
			(stroke
				(width 0.05)
				(type default)
			)
			(fill no)
			(layer "B.CrtYd")
		)
		(fp_line
			(start 0.504 0.25)
			(end -0.494 0.25)
			(stroke
				(width 0.15)
				(type solid)
			)
			(layer "B.Fab")
		)
		(fp_line
			(start 0.504 -0.248)
			(end 0.504 0.25)
			(stroke
				(width 0.15)
				(type solid)
			)
			(layer "B.Fab")
		)
		(fp_line
			(start -0.494 0.25)
			(end -0.494 -0.248)
			(stroke
				(width 0.15)
				(type solid)
			)
			(layer "B.Fab")
		)
		(fp_line
			(start -0.494 -0.248)
			(end 0.504 -0.248)
			(stroke
				(width 0.15)
				(type solid)
			)
			(layer "B.Fab")
		)
		(pad "1" smd roundrect
			(at -0.48 0 180)
			(size 0.59 0.64)
			(layers "B.Cu" "B.Mask" "B.Paste")
			(roundrect_rratio 0.25)
			(net 1 "GND")
			(pintype "passive")
			(teardrops
				(best_length_ratio 0.2)
				(max_length 1)
				(best_width_ratio 0.9)
				(max_width 2)
				(curved_edges yes)
				(filter_ratio 0.9)
				(enabled yes)
				(allow_two_segments yes)
				(prefer_zone_connections yes)
			)
		)
		(pad "2" smd roundrect
			(at 0.48 0 180)
			(size 0.59 0.64)
			(layers "B.Cu" "B.Mask" "B.Paste")
			(roundrect_rratio 0.25)
			(net 74 "+1V0")
			(pintype "passive")
			(teardrops
				(best_length_ratio 0.2)
				(max_length 1)
				(best_width_ratio 0.9)
				(max_width 2)
				(curved_edges yes)
				(filter_ratio 0.9)
				(enabled yes)
				(allow_two_segments yes)
				(prefer_zone_connections yes)
			)
		)
	)
	(footprint "antmicro-footprints:C_0402_1005Metric"
		(layer "B.Cu")
		(at 109.811 159.869 180)
		(descr "Capacitor SMD 0402")
		(tags "capacitor SMD 0402")
		(property "Reference" "C144"
			(at -3.739 -0.481 0)
			(layer "B.SilkS")
			(effects
				(font
					(size 0.7 0.7)
					(thickness 0.15)
				)
				(justify left bottom mirror)
			)
		)
		(property "Value" "C_220n_0402"
			(at -1.022927 -2.155213 0)
			(layer "B.Fab")
			(effects
				(font
					(size 0.7 0.7)
					(thickness 0.15)
				)
				(justify left bottom mirror)
			)
		)
		(property "Datasheet" "https://www.yageo.com/en/Chart/Download/pdf/CC0402KRX5R6BB224"
			(at 0 0 180)
			(layer "F.Fab")
			(hide yes)
			(effects
				(font
					(size 1.27 1.27)
					(thickness 0.15)
				)
			)
		)
		(property "Author" "Antmicro"
			(at 219.622 319.738 0)
			(layer "B.Fab")
			(hide yes)
			(effects
				(font
					(size 1 1)
					(thickness 0.15)
				)
				(justify mirror)
			)
		)
		(property "Dielectric" ""
			(at 219.622 319.738 0)
			(layer "B.Fab")
			(hide yes)
			(effects
				(font
					(size 1 1)
					(thickness 0.15)
				)
				(justify mirror)
			)
		)
		(property "License" "Apache-2.0"
			(at 219.622 319.738 0)
			(layer "B.Fab")
			(hide yes)
			(effects
				(font
					(size 1 1)
					(thickness 0.15)
				)
				(justify mirror)
			)
		)
		(property "MPN" "CC0402KRX5R6BB224"
			(at 219.622 319.738 0)
			(layer "B.Fab")
			(hide yes)
			(effects
				(font
					(size 1 1)
					(thickness 0.15)
				)
				(justify mirror)
			)
		)
		(property "Manufacturer" "YAGEO"
			(at 219.622 319.738 0)
			(layer "B.Fab")
			(hide yes)
			(effects
				(font
					(size 1 1)
					(thickness 0.15)
				)
				(justify mirror)
			)
		)
		(property "Public" "False"
			(at 219.622 319.738 0)
			(layer "B.Fab")
			(hide yes)
			(effects
				(font
					(size 1 1)
					(thickness 0.15)
				)
				(justify mirror)
			)
		)
		(property "Val" "220n"
			(at 219.622 319.738 0)
			(layer "B.Fab")
			(hide yes)
			(effects
				(font
					(size 1 1)
					(thickness 0.15)
				)
				(justify mirror)
			)
		)
		(property "Voltage" ""
			(at 219.622 319.738 0)
			(layer "B.Fab")
			(hide yes)
			(effects
				(font
					(size 1 1)
					(thickness 0.15)
				)
				(justify mirror)
			)
		)
		(sheetname "PCIe redriver")
		(sheetfile "pcie_redriver.kicad_sch")
		(attr smd)
		(fp_rect
			(start -0.925 0.47)
			(end 0.925 -0.47)
			(stroke
				(width 0.05)
				(type default)
			)
			(fill no)
			(layer "B.CrtYd")
		)
		(fp_line
			(start 0.504 0.25)
			(end -0.494 0.25)
			(stroke
				(width 0.15)
				(type solid)
			)
			(layer "B.Fab")
		)
		(fp_line
			(start 0.504 -0.248)
			(end 0.504 0.25)
			(stroke
				(width 0.15)
				(type solid)
			)
			(layer "B.Fab")
		)
		(fp_line
			(start -0.494 0.25)
			(end -0.494 -0.248)
			(stroke
				(width 0.15)
				(type solid)
			)
			(layer "B.Fab")
		)
		(fp_line
			(start -0.494 -0.248)
			(end 0.504 -0.248)
			(stroke
				(width 0.15)
				(type solid)
			)
			(layer "B.Fab")
		)
		(pad "1" smd roundrect
			(at -0.48 0 180)
			(size 0.59 0.64)
			(layers "B.Cu" "B.Mask" "B.Paste")
			(roundrect_rratio 0.25)
			(net 964 "/PCIe redriver/PCIe_{O}_C.TX2-")
			(pintype "passive")
			(teardrops
				(best_length_ratio 0.2)
				(max_length 1)
				(best_width_ratio 0.9)
				(max_width 2)
				(curved_edges yes)
				(filter_ratio 0.9)
				(enabled yes)
				(allow_two_segments yes)
				(prefer_zone_connections yes)
			)
		)
		(pad "2" smd roundrect
			(at 0.48 0 180)
			(size 0.59 0.64)
			(layers "B.Cu" "B.Mask" "B.Paste")
			(roundrect_rratio 0.25)
			(net 97 "/OCuLink/PCIe_{x4}.TX2-")
			(pintype "passive")
			(teardrops
				(best_length_ratio 0.2)
				(max_length 1)
				(best_width_ratio 0.9)
				(max_width 2)
				(curved_edges yes)
				(filter_ratio 0.9)
				(enabled yes)
				(allow_two_segments yes)
				(prefer_zone_connections yes)
			)
		)
	)
	(footprint "antmicro-footprints:R_0402_1005Metric"
		(layer "B.Cu")
		(at 144.25 137.06 180)
		(descr "Resistor SMD 0402")
		(tags "resistor SMD 0402")
		(property "Reference" "R262"
			(at -1.3 1.5 0)
			(layer "B.SilkS")
			(effects
				(font
					(size 0.7 0.7)
					(thickness 0.15)
				)
				(justify left bottom mirror)
			)
		)
		(property "Value" "R_10k_0402"
			(at -1.011843 -1.772047 0)
			(layer "B.Fab")
			(effects
				(font
					(size 0.7 0.7)
					(thickness 0.15)
				)
				(justify left bottom mirror)
			)
		)
		(property "Datasheet" "https://www.bourns.com/docs/product-datasheets/cr.pdf"
			(at 0 0 180)
			(layer "F.Fab")
			(hide yes)
			(effects
				(font
					(size 1.27 1.27)
					(thickness 0.15)
				)
			)
		)
		(property "Author" "Antmicro"
			(at 288.5 274.12 0)
			(layer "B.Fab")
			(hide yes)
			(effects
				(font
					(size 1 1)
					(thickness 0.15)
				)
				(justify mirror)
			)
		)
		(property "License" "Apache-2.0"
			(at 288.5 274.12 0)
			(layer "B.Fab")
			(hide yes)
			(effects
				(font
					(size 1 1)
					(thickness 0.15)
				)
				(justify mirror)
			)
		)
		(property "MPN" "CR0402-FX-1002GLF"
			(at 288.5 274.12 0)
			(layer "B.Fab")
			(hide yes)
			(effects
				(font
					(size 1 1)
					(thickness 0.15)
				)
				(justify mirror)
			)
		)
		(property "Manufacturer" "Bourns"
			(at 288.5 274.12 0)
			(layer "B.Fab")
			(hide yes)
			(effects
				(font
					(size 1 1)
					(thickness 0.15)
				)
				(justify mirror)
			)
		)
		(property "Public" "False"
			(at 288.5 274.12 0)
			(layer "B.Fab")
			(hide yes)
			(effects
				(font
					(size 1 1)
					(thickness 0.15)
				)
				(justify mirror)
			)
		)
		(property "Tolerance" "1%"
			(at 288.5 274.12 0)
			(layer "B.Fab")
			(hide yes)
			(effects
				(font
					(size 1 1)
					(thickness 0.15)
				)
				(justify mirror)
			)
		)
		(property "Val" "10k"
			(at 288.5 274.12 0)
			(layer "B.Fab")
			(hide yes)
			(effects
				(font
					(size 1 1)
					(thickness 0.15)
				)
				(justify mirror)
			)
		)
		(sheetname "KR to SFI #1")
		(sheetfile "kr_sfi.kicad_sch")
		(attr smd dnp)
		(fp_rect
			(start -0.925 0.47)
			(end 0.925 -0.47)
			(stroke
				(width 0.05)
				(type default)
			)
			(fill no)
			(layer "B.CrtYd")
		)
		(fp_rect
			(start -0.5 0.25)
			(end 0.5 -0.25)
			(stroke
				(width 0.15)
				(type solid)
			)
			(fill no)
			(layer "B.Fab")
		)
		(pad "1" smd roundrect
			(at -0.48 0 180)
			(size 0.59 0.64)
			(layers "B.Cu" "B.Mask" "B.Paste")
			(roundrect_rratio 0.25)
			(net 656 "Net-(U43C-PRTAD1)")
			(pintype "passive")
			(teardrops
				(best_length_ratio 0.2)
				(max_length 1)
				(best_width_ratio 0.9)
				(max_width 2)
				(curved_edges yes)
				(filter_ratio 0.9)
				(enabled yes)
				(allow_two_segments yes)
				(prefer_zone_connections yes)
			)
		)
		(pad "2" smd roundrect
			(at 0.48 0 180)
			(size 0.59 0.64)
			(layers "B.Cu" "B.Mask" "B.Paste")
			(roundrect_rratio 0.25)
			(net 78 "+1V8")
			(pintype "passive")
			(teardrops
				(best_length_ratio 0.2)
				(max_length 1)
				(best_width_ratio 0.9)
				(max_width 2)
				(curved_edges yes)
				(filter_ratio 0.9)
				(enabled yes)
				(allow_two_segments yes)
				(prefer_zone_connections yes)
			)
		)
	)
	(footprint "antmicro-footprints:TP_SMD_0.75mm"
		(layer "B.Cu")
		(at 123.4 144.66 180)
		(property "Reference" "TP52"
			(at -3.15 -0.4 0)
			(layer "B.SilkS")
			(effects
				(font
					(size 0.7 0.7)
					(thickness 0.15)
				)
				(justify left bottom mirror)
			)
		)
		(property "Value" "TP_0.75mm_SMD"
			(at 0 -1.2 0)
			(layer "B.Fab")
			(effects
				(font
					(size 0.7 0.7)
					(thickness 0.15)
				)
				(justify left bottom mirror)
			)
		)
		(property "Author" "Antmicro"
			(at 246.8 289.32 0)
			(layer "B.Fab")
			(hide yes)
			(effects
				(font
					(size 1 1)
					(thickness 0.15)
				)
				(justify mirror)
			)
		)
		(property "License" "Apache-2.0"
			(at 246.8 289.32 0)
			(layer "B.Fab")
			(hide yes)
			(effects
				(font
					(size 1 1)
					(thickness 0.15)
				)
				(justify mirror)
			)
		)
		(property "MPN" ""
			(at 246.8 289.32 0)
			(layer "B.Fab")
			(hide yes)
			(effects
				(font
					(size 1 1)
					(thickness 0.15)
				)
				(justify mirror)
			)
		)
		(property "Manufacturer" ""
			(at 246.8 289.32 0)
			(layer "B.Fab")
			(hide yes)
			(effects
				(font
					(size 1 1)
					(thickness 0.15)
				)
				(justify mirror)
			)
		)
		(property "Public" "False"
			(at 246.8 289.32 0)
			(layer "B.Fab")
			(hide yes)
			(effects
				(font
					(size 1 1)
					(thickness 0.15)
				)
				(justify mirror)
			)
		)
		(sheetname "PCIe redriver")
		(sheetfile "pcie_redriver.kicad_sch")
		(attr exclude_from_pos_files exclude_from_bom)
		(fp_circle
			(center 0 0)
			(end 0.475 0)
			(stroke
				(width 0.05)
				(type default)
			)
			(fill no)
			(layer "B.CrtYd")
		)
		(pad "1" smd circle
			(at 0 0 180)
			(size 0.75 0.75)
			(layers "B.Cu" "B.Mask")
			(net 715 "Net-(U39-~{I2C_{RESET}})")
			(pinfunction "1")
			(pintype "passive")
			(teardrops
				(best_length_ratio 0.4)
				(max_length 1)
				(best_width_ratio 0.9)
				(max_width 2)
				(curved_edges yes)
				(filter_ratio 0.9)
				(enabled yes)
				(allow_two_segments yes)
				(prefer_zone_connections yes)
			)
		)
	)
	(footprint "antmicro-footprints:SC70-3"
		(layer "B.Cu")
		(at 113.63 105.2 90)
		(property "Reference" "D3"
			(at 1.46 -0.79 180)
			(layer "B.SilkS")
			(effects
				(font
					(size 0.7 0.7)
					(thickness 0.15)
				)
				(justify right bottom mirror)
			)
		)
		(property "Value" "TPD2E2U06_SC70"
			(at 0 -2.3 90)
			(layer "B.Fab")
			(effects
				(font
					(size 0.7 0.7)
					(thickness 0.15)
				)
				(justify right bottom mirror)
			)
		)
		(property "Datasheet" "https://www.ti.com/lit/ds/symlink/tpd2e2u06.pdf?ts=1706006131823&ref_url=https%253A%252F%252Fwww.ti.com%252Finterface%252Fdiodes%252Fesd-protection-diodes%252Fproducts.html"
			(at 0 0 90)
			(layer "F.Fab")
			(hide yes)
			(effects
				(font
					(size 1.27 1.27)
					(thickness 0.15)
				)
			)
		)
		(property "Author" "Antmicro"
			(at 218.41 -8.67 0)
			(layer "B.Fab")
			(hide yes)
			(effects
				(font
					(size 1 1)
					(thickness 0.15)
				)
				(justify mirror)
			)
		)
		(property "License" "Apache-2.0"
			(at 218.41 -8.67 0)
			(layer "B.Fab")
			(hide yes)
			(effects
				(font
					(size 1 1)
					(thickness 0.15)
				)
				(justify mirror)
			)
		)
		(property "MPN" "TPD2E2U06DCKR"
			(at 218.41 -8.67 0)
			(layer "B.Fab")
			(hide yes)
			(effects
				(font
					(size 1 1)
					(thickness 0.15)
				)
				(justify mirror)
			)
		)
		(property "Manufacturer" "Texas Instruments"
			(at 218.41 -8.67 0)
			(layer "B.Fab")
			(hide yes)
			(effects
				(font
					(size 1 1)
					(thickness 0.15)
				)
				(justify mirror)
			)
		)
		(sheetname "2xUSB3.0+RJ45")
		(sheetfile "usb3+rj45.kicad_sch")
		(attr smd)
		(fp_line
			(start 0.627 -1.001)
			(end -0.3 -1)
			(stroke
				(width 0.15)
				(type solid)
			)
			(layer "B.SilkS")
		)
		(fp_line
			(start 0.627 -1.001)
			(end 0.627 -0.6)
			(stroke
				(width 0.15)
				(type solid)
			)
			(layer "B.SilkS")
		)
		(fp_line
			(start 0.627 0.999)
			(end 0.627 0.6)
			(stroke
				(width 0.15)
				(type solid)
			)
			(layer "B.SilkS")
		)
		(fp_line
			(start 0.627 0.999)
			(end -0.3 1)
			(stroke
				(width 0.15)
				(type solid)
			)
			(layer "B.SilkS")
		)
		(fp_line
			(start 0.9 -1.3)
			(end 0.9 -0.4)
			(stroke
				(width 0.05)
				(type solid)
			)
			(layer "B.CrtYd")
		)
		(fp_line
			(start -0.9 -1.3)
			(end 0.9 -1.3)
			(stroke
				(width 0.05)
				(type solid)
			)
			(layer "B.CrtYd")
		)
		(fp_line
			(start -0.9 -1)
			(end -0.9 -1.3)
			(stroke
				(width 0.05)
				(type solid)
			)
			(layer "B.CrtYd")
		)
		(fp_line
			(start -1.4 -1)
			(end -0.9 -1)
			(stroke
				(width 0.05)
				(type solid)
			)
			(layer "B.CrtYd")
		)
		(fp_line
			(start 1.4 -0.4)
			(end 1.4 0.4)
			(stroke
				(width 0.05)
				(type solid)
			)
			(layer "B.CrtYd")
		)
		(fp_line
			(start 0.9 -0.4)
			(end 1.4 -0.4)
			(stroke
				(width 0.05)
				(type solid)
			)
			(layer "B.CrtYd")
		)
		(fp_line
			(start 1.4 0.4)
			(end 0.9 0.4)
			(stroke
				(width 0.05)
				(type solid)
			)
			(layer "B.CrtYd")
		)
		(fp_line
			(start 0.9 0.4)
			(end 0.9 1.3)
			(stroke
				(width 0.05)
				(type solid)
			)
			(layer "B.CrtYd")
		)
		(fp_line
			(start -0.9 1)
			(end -0.9 1.3)
			(stroke
				(width 0.05)
				(type solid)
			)
			(layer "B.CrtYd")
		)
		(fp_line
			(start -1.4 1)
			(end -1.4 -1)
			(stroke
				(width 0.05)
				(type solid)
			)
			(layer "B.CrtYd")
		)
		(fp_line
			(start -1.4 1)
			(end -0.9 1)
			(stroke
				(width 0.05)
				(type solid)
			)
			(layer "B.CrtYd")
		)
		(fp_line
			(start 0.9 1.3)
			(end -0.9 1.3)
			(stroke
				(width 0.05)
				(type solid)
			)
			(layer "B.CrtYd")
		)
		(fp_rect
			(start -0.623 0.999)
			(end 0.627 -1.001)
			(stroke
				(width 0.15)
				(type solid)
			)
			(fill no)
			(layer "B.Fab")
		)
		(pad "1" smd rect
			(at -1.051 0.65)
			(size 0.6 0.6)
			(layers "B.Cu" "B.Mask" "B.Paste")
			(net 125 "/2xUSB3.0+RJ45/P2_D-")
			(pinfunction "1")
			(pintype "passive")
			(teardrops
				(best_length_ratio 0.2)
				(max_length 1)
				(best_width_ratio 0.9)
				(max_width 2)
				(curved_edges yes)
				(filter_ratio 0.9)
				(enabled yes)
				(allow_two_segments yes)
				(prefer_zone_connections yes)
			)
		)
		(pad "2" smd rect
			(at -1.051 -0.65)
			(size 0.6 0.6)
			(layers "B.Cu" "B.Mask" "B.Paste")
			(net 126 "/2xUSB3.0+RJ45/P2_D+")
			(pinfunction "2")
			(pintype "passive")
			(teardrops
				(best_length_ratio 0.2)
				(max_length 1)
				(best_width_ratio 0.9)
				(max_width 2)
				(curved_edges yes)
				(filter_ratio 0.9)
				(enabled yes)
				(allow_two_segments yes)
				(prefer_zone_connections yes)
			)
		)
		(pad "3" smd rect
			(at 1.05 0)
			(size 0.6 0.6)
			(layers "B.Cu" "B.Mask" "B.Paste")
			(net 1 "GND")
			(pinfunction "3")
			(pintype "passive")
			(teardrops
				(best_length_ratio 0.2)
				(max_length 1)
				(best_width_ratio 0.9)
				(max_width 2)
				(curved_edges yes)
				(filter_ratio 0.9)
				(enabled yes)
				(allow_two_segments yes)
				(prefer_zone_connections yes)
			)
		)
	)
	(footprint "antmicro-footprints:C_0603_1608Metric"
		(layer "B.Cu")
		(at 116.9 92.01)
		(descr "Capacitor SMD 0603")
		(tags "capacitor 0603")
		(property "Reference" "C19"
			(at -1.1 1.55 0)
			(layer "B.SilkS")
			(effects
				(font
					(size 0.7 0.7)
					(thickness 0.15)
				)
				(justify right bottom mirror)
			)
		)
		(property "Value" "C_22u_16V_0603"
			(at -1.42757 -1.770288 0)
			(layer "B.Fab")
			(effects
				(font
					(size 0.7 0.7)
					(thickness 0.15)
				)
				(justify right bottom mirror)
			)
		)
		(property "Datasheet" "https://product.samsungsem.com/mlcc/CL10A226MO7JZN.do"
			(at 0 0 0)
			(layer "F.Fab")
			(hide yes)
			(effects
				(font
					(size 1.27 1.27)
					(thickness 0.15)
				)
			)
		)
		(property "Author" "Antmicro"
			(at 0 0 0)
			(layer "B.Fab")
			(hide yes)
			(effects
				(font
					(size 1 1)
					(thickness 0.15)
				)
				(justify mirror)
			)
		)
		(property "Dielectric" ""
			(at 0 0 0)
			(layer "B.Fab")
			(hide yes)
			(effects
				(font
					(size 1 1)
					(thickness 0.15)
				)
				(justify mirror)
			)
		)
		(property "License" "Apache-2.0"
			(at 0 0 0)
			(layer "B.Fab")
			(hide yes)
			(effects
				(font
					(size 1 1)
					(thickness 0.15)
				)
				(justify mirror)
			)
		)
		(property "MPN" "CL10A226MO7JZNC"
			(at 0 0 0)
			(layer "B.Fab")
			(hide yes)
			(effects
				(font
					(size 1 1)
					(thickness 0.15)
				)
				(justify mirror)
			)
		)
		(property "Manufacturer" "Samsung Electro-Mechanics"
			(at 0 0 0)
			(layer "B.Fab")
			(hide yes)
			(effects
				(font
					(size 1 1)
					(thickness 0.15)
				)
				(justify mirror)
			)
		)
		(property "Public" "False"
			(at 0 0 0)
			(layer "B.Fab")
			(hide yes)
			(effects
				(font
					(size 1 1)
					(thickness 0.15)
				)
				(justify mirror)
			)
		)
		(property "Val" "22u"
			(at 0 0 0)
			(layer "B.Fab")
			(hide yes)
			(effects
				(font
					(size 1 1)
					(thickness 0.15)
				)
				(justify mirror)
			)
		)
		(property "Voltage" "16V"
			(at 0 0 0)
			(layer "B.Fab")
			(hide yes)
			(effects
				(font
					(size 1 1)
					(thickness 0.15)
				)
				(justify mirror)
			)
		)
		(sheetname "2xUSB3.0+RJ45")
		(sheetfile "usb3+rj45.kicad_sch")
		(attr smd)
		(fp_line
			(start 0.15 -0.4)
			(end -0.15 -0.4)
			(stroke
				(width 0.15)
				(type solid)
			)
			(layer "B.SilkS")
		)
		(fp_line
			(start 0.15 0.4)
			(end -0.15 0.4)
			(stroke
				(width 0.15)
				(type solid)
			)
			(layer "B.SilkS")
		)
		(fp_rect
			(start -1.25 0.65)
			(end 1.25 -0.65)
			(stroke
				(width 0.05)
				(type solid)
			)
			(fill no)
			(layer "B.CrtYd")
		)
		(fp_rect
			(start -0.8 0.4)
			(end 0.8 -0.4)
			(stroke
				(width 0.15)
				(type solid)
			)
			(fill no)
			(layer "B.Fab")
		)
		(pad "1" smd roundrect
			(at -0.7 0)
			(size 0.8 1)
			(layers "B.Cu" "B.Mask" "B.Paste")
			(roundrect_rratio 0.2)
			(net 1 "GND")
			(pintype "passive")
			(teardrops
				(best_length_ratio 0.2)
				(max_length 1)
				(best_width_ratio 0.9)
				(max_width 2)
				(curved_edges yes)
				(filter_ratio 0.9)
				(enabled yes)
				(allow_two_segments yes)
				(prefer_zone_connections yes)
			)
		)
		(pad "2" smd roundrect
			(at 0.7 0)
			(size 0.8 1)
			(layers "B.Cu" "B.Mask" "B.Paste")
			(roundrect_rratio 0.2)
			(net 52 "+5V")
			(pintype "passive")
			(teardrops
				(best_length_ratio 0.2)
				(max_length 1)
				(best_width_ratio 0.9)
				(max_width 2)
				(curved_edges yes)
				(filter_ratio 0.9)
				(enabled yes)
				(allow_two_segments yes)
				(prefer_zone_connections yes)
			)
		)
	)
	(footprint "antmicro-footprints:R_0402_1005Metric"
		(layer "B.Cu")
		(at 139.74 138.36 180)
		(descr "Resistor SMD 0402")
		(tags "resistor SMD 0402")
		(property "Reference" "R287"
			(at 0.79 -0.75 0)
			(layer "B.SilkS")
			(effects
				(font
					(size 0.7 0.7)
					(thickness 0.15)
				)
				(justify left bottom mirror)
			)
		)
		(property "Value" "R_10k_0402"
			(at -1.011843 -1.772047 0)
			(layer "B.Fab")
			(effects
				(font
					(size 0.7 0.7)
					(thickness 0.15)
				)
				(justify left bottom mirror)
			)
		)
		(property "Datasheet" "https://www.bourns.com/docs/product-datasheets/cr.pdf"
			(at 0 0 180)
			(layer "F.Fab")
			(hide yes)
			(effects
				(font
					(size 1.27 1.27)
					(thickness 0.15)
				)
			)
		)
		(property "Author" "Antmicro"
			(at 279.48 276.72 0)
			(layer "B.Fab")
			(hide yes)
			(effects
				(font
					(size 1 1)
					(thickness 0.15)
				)
				(justify mirror)
			)
		)
		(property "License" "Apache-2.0"
			(at 279.48 276.72 0)
			(layer "B.Fab")
			(hide yes)
			(effects
				(font
					(size 1 1)
					(thickness 0.15)
				)
				(justify mirror)
			)
		)
		(property "MPN" "CR0402-FX-1002GLF"
			(at 279.48 276.72 0)
			(layer "B.Fab")
			(hide yes)
			(effects
				(font
					(size 1 1)
					(thickness 0.15)
				)
				(justify mirror)
			)
		)
		(property "Manufacturer" "Bourns"
			(at 279.48 276.72 0)
			(layer "B.Fab")
			(hide yes)
			(effects
				(font
					(size 1 1)
					(thickness 0.15)
				)
				(justify mirror)
			)
		)
		(property "Public" "False"
			(at 279.48 276.72 0)
			(layer "B.Fab")
			(hide yes)
			(effects
				(font
					(size 1 1)
					(thickness 0.15)
				)
				(justify mirror)
			)
		)
		(property "Tolerance" "1%"
			(at 279.48 276.72 0)
			(layer "B.Fab")
			(hide yes)
			(effects
				(font
					(size 1 1)
					(thickness 0.15)
				)
				(justify mirror)
			)
		)
		(property "Val" "10k"
			(at 279.48 276.72 0)
			(layer "B.Fab")
			(hide yes)
			(effects
				(font
					(size 1 1)
					(thickness 0.15)
				)
				(justify mirror)
			)
		)
		(sheetname "KR to SFI #2")
		(sheetfile "kr_sfi.kicad_sch")
		(attr smd)
		(fp_rect
			(start -0.925 0.47)
			(end 0.925 -0.47)
			(stroke
				(width 0.05)
				(type default)
			)
			(fill no)
			(layer "B.CrtYd")
		)
		(fp_rect
			(start -0.5 0.25)
			(end 0.5 -0.25)
			(stroke
				(width 0.15)
				(type solid)
			)
			(fill no)
			(layer "B.Fab")
		)
		(pad "1" smd roundrect
			(at -0.48 0 180)
			(size 0.59 0.64)
			(layers "B.Cu" "B.Mask" "B.Paste")
			(roundrect_rratio 0.25)
			(net 1 "GND")
			(pintype "passive")
			(teardrops
				(best_length_ratio 0.2)
				(max_length 1)
				(best_width_ratio 0.9)
				(max_width 2)
				(curved_edges yes)
				(filter_ratio 0.9)
				(enabled yes)
				(allow_two_segments yes)
				(prefer_zone_connections yes)
			)
		)
		(pad "2" smd roundrect
			(at 0.48 0 180)
			(size 0.59 0.64)
			(layers "B.Cu" "B.Mask" "B.Paste")
			(roundrect_rratio 0.25)
			(net 673 "/2xSFP+/KR to SFI #2/PRBSEN")
			(pintype "passive")
			(teardrops
				(best_length_ratio 0.2)
				(max_length 1)
				(best_width_ratio 0.9)
				(max_width 2)
				(curved_edges yes)
				(filter_ratio 0.9)
				(enabled yes)
				(allow_two_segments yes)
				(prefer_zone_connections yes)
			)
		)
	)
	(footprint "antmicro-footprints:C_0603_1608Metric"
		(layer "B.Cu")
		(at 148.7 73.16 180)
		(descr "Capacitor SMD 0603")
		(tags "capacitor 0603")
		(property "Reference" "C80"
			(at -3.3 -0.5 0)
			(layer "B.SilkS")
			(effects
				(font
					(size 0.7 0.7)
					(thickness 0.15)
				)
				(justify left bottom mirror)
			)
		)
		(property "Value" "C_22u_16V_0603"
			(at -1.42757 -1.770288 0)
			(layer "B.Fab")
			(effects
				(font
					(size 0.7 0.7)
					(thickness 0.15)
				)
				(justify left bottom mirror)
			)
		)
		(property "Datasheet" "https://product.samsungsem.com/mlcc/CL10A226MO7JZN.do"
			(at 0 0 180)
			(layer "F.Fab")
			(hide yes)
			(effects
				(font
					(size 1.27 1.27)
					(thickness 0.15)
				)
			)
		)
		(property "Author" "Antmicro"
			(at 297.4 146.32 0)
			(layer "B.Fab")
			(hide yes)
			(effects
				(font
					(size 1 1)
					(thickness 0.15)
				)
				(justify mirror)
			)
		)
		(property "Dielectric" ""
			(at 297.4 146.32 0)
			(layer "B.Fab")
			(hide yes)
			(effects
				(font
					(size 1 1)
					(thickness 0.15)
				)
				(justify mirror)
			)
		)
		(property "License" "Apache-2.0"
			(at 297.4 146.32 0)
			(layer "B.Fab")
			(hide yes)
			(effects
				(font
					(size 1 1)
					(thickness 0.15)
				)
				(justify mirror)
			)
		)
		(property "MPN" "CL10A226MO7JZNC"
			(at 297.4 146.32 0)
			(layer "B.Fab")
			(hide yes)
			(effects
				(font
					(size 1 1)
					(thickness 0.15)
				)
				(justify mirror)
			)
		)
		(property "Manufacturer" "Samsung Electro-Mechanics"
			(at 297.4 146.32 0)
			(layer "B.Fab")
			(hide yes)
			(effects
				(font
					(size 1 1)
					(thickness 0.15)
				)
				(justify mirror)
			)
		)
		(property "Public" "False"
			(at 297.4 146.32 0)
			(layer "B.Fab")
			(hide yes)
			(effects
				(font
					(size 1 1)
					(thickness 0.15)
				)
				(justify mirror)
			)
		)
		(property "Val" "22u"
			(at 297.4 146.32 0)
			(layer "B.Fab")
			(hide yes)
			(effects
				(font
					(size 1 1)
					(thickness 0.15)
				)
				(justify mirror)
			)
		)
		(property "Voltage" "16V"
			(at 297.4 146.32 0)
			(layer "B.Fab")
			(hide yes)
			(effects
				(font
					(size 1 1)
					(thickness 0.15)
				)
				(justify mirror)
			)
		)
		(sheetname "M.2 key E")
		(sheetfile "m2keye.kicad_sch")
		(attr smd)
		(fp_line
			(start 0.15 0.4)
			(end -0.15 0.4)
			(stroke
				(width 0.15)
				(type solid)
			)
			(layer "B.SilkS")
		)
		(fp_line
			(start 0.15 -0.4)
			(end -0.15 -0.4)
			(stroke
				(width 0.15)
				(type solid)
			)
			(layer "B.SilkS")
		)
		(fp_rect
			(start -1.25 0.65)
			(end 1.25 -0.65)
			(stroke
				(width 0.05)
				(type solid)
			)
			(fill no)
			(layer "B.CrtYd")
		)
		(fp_rect
			(start -0.8 0.4)
			(end 0.8 -0.4)
			(stroke
				(width 0.15)
				(type solid)
			)
			(fill no)
			(layer "B.Fab")
		)
		(pad "1" smd roundrect
			(at -0.7 0 180)
			(size 0.8 1)
			(layers "B.Cu" "B.Mask" "B.Paste")
			(roundrect_rratio 0.2)
			(net 1 "GND")
			(pintype "passive")
			(teardrops
				(best_length_ratio 0.2)
				(max_length 1)
				(best_width_ratio 0.9)
				(max_width 2)
				(curved_edges yes)
				(filter_ratio 0.9)
				(enabled yes)
				(allow_two_segments yes)
				(prefer_zone_connections yes)
			)
		)
		(pad "2" smd roundrect
			(at 0.7 0 180)
			(size 0.8 1)
			(layers "B.Cu" "B.Mask" "B.Paste")
			(roundrect_rratio 0.2)
			(net 2 "+3V3")
			(pintype "passive")
			(teardrops
				(best_length_ratio 0.2)
				(max_length 1)
				(best_width_ratio 0.9)
				(max_width 2)
				(curved_edges yes)
				(filter_ratio 0.9)
				(enabled yes)
				(allow_two_segments yes)
				(prefer_zone_connections yes)
			)
		)
	)
	(footprint "antmicro-footprints:C_0402_1005Metric"
		(layer "B.Cu")
		(at 148.95 132.87 180)
		(descr "Capacitor SMD 0402")
		(tags "capacitor SMD 0402")
		(property "Reference" "C170"
			(at 0.45 5.01 0)
			(layer "B.SilkS")
			(effects
				(font
					(size 0.7 0.7)
					(thickness 0.15)
				)
				(justify left bottom mirror)
			)
		)
		(property "Value" "C_100n_0402"
			(at -1.022927 -2.155213 0)
			(layer "B.Fab")
			(effects
				(font
					(size 0.7 0.7)
					(thickness 0.15)
				)
				(justify left bottom mirror)
			)
		)
		(property "Datasheet" "https://www.murata.com/products/productdetail?partno=GRM155R61H104KE14%23"
			(at 0 0 180)
			(layer "F.Fab")
			(hide yes)
			(effects
				(font
					(size 1.27 1.27)
					(thickness 0.15)
				)
			)
		)
		(property "Author" "Antmicro"
			(at 297.9 265.74 0)
			(layer "B.Fab")
			(hide yes)
			(effects
				(font
					(size 1 1)
					(thickness 0.15)
				)
				(justify mirror)
			)
		)
		(property "Dielectric" "X5R"
			(at 297.9 265.74 0)
			(layer "B.Fab")
			(hide yes)
			(effects
				(font
					(size 1 1)
					(thickness 0.15)
				)
				(justify mirror)
			)
		)
		(property "License" "Apache-2.0"
			(at 297.9 265.74 0)
			(layer "B.Fab")
			(hide yes)
			(effects
				(font
					(size 1 1)
					(thickness 0.15)
				)
				(justify mirror)
			)
		)
		(property "MPN" "GRM155R61H104KE14D"
			(at 297.9 265.74 0)
			(layer "B.Fab")
			(hide yes)
			(effects
				(font
					(size 1 1)
					(thickness 0.15)
				)
				(justify mirror)
			)
		)
		(property "Manufacturer" "Murata"
			(at 297.9 265.74 0)
			(layer "B.Fab")
			(hide yes)
			(effects
				(font
					(size 1 1)
					(thickness 0.15)
				)
				(justify mirror)
			)
		)
		(property "Public" "False"
			(at 297.9 265.74 0)
			(layer "B.Fab")
			(hide yes)
			(effects
				(font
					(size 1 1)
					(thickness 0.15)
				)
				(justify mirror)
			)
		)
		(property "Val" "100n"
			(at 297.9 265.74 0)
			(layer "B.Fab")
			(hide yes)
			(effects
				(font
					(size 1 1)
					(thickness 0.15)
				)
				(justify mirror)
			)
		)
		(property "Voltage" "50V"
			(at 297.9 265.74 0)
			(layer "B.Fab")
			(hide yes)
			(effects
				(font
					(size 1 1)
					(thickness 0.15)
				)
				(justify mirror)
			)
		)
		(sheetname "KR to SFI #1")
		(sheetfile "kr_sfi.kicad_sch")
		(attr smd)
		(fp_rect
			(start -0.925 0.47)
			(end 0.925 -0.47)
			(stroke
				(width 0.05)
				(type default)
			)
			(fill no)
			(layer "B.CrtYd")
		)
		(fp_line
			(start 0.504 0.25)
			(end -0.494 0.25)
			(stroke
				(width 0.15)
				(type solid)
			)
			(layer "B.Fab")
		)
		(fp_line
			(start 0.504 -0.248)
			(end 0.504 0.25)
			(stroke
				(width 0.15)
				(type solid)
			)
			(layer "B.Fab")
		)
		(fp_line
			(start -0.494 0.25)
			(end -0.494 -0.248)
			(stroke
				(width 0.15)
				(type solid)
			)
			(layer "B.Fab")
		)
		(fp_line
			(start -0.494 -0.248)
			(end 0.504 -0.248)
			(stroke
				(width 0.15)
				(type solid)
			)
			(layer "B.Fab")
		)
		(pad "1" smd roundrect
			(at -0.48 0 180)
			(size 0.59 0.64)
			(layers "B.Cu" "B.Mask" "B.Paste")
			(roundrect_rratio 0.25)
			(net 1 "GND")
			(pintype "passive")
			(teardrops
				(best_length_ratio 0.2)
				(max_length 1)
				(best_width_ratio 0.9)
				(max_width 2)
				(curved_edges yes)
				(filter_ratio 0.9)
				(enabled yes)
				(allow_two_segments yes)
				(prefer_zone_connections yes)
			)
		)
		(pad "2" smd roundrect
			(at 0.48 0 180)
			(size 0.59 0.64)
			(layers "B.Cu" "B.Mask" "B.Paste")
			(roundrect_rratio 0.25)
			(net 74 "+1V0")
			(pintype "passive")
			(teardrops
				(best_length_ratio 0.2)
				(max_length 1)
				(best_width_ratio 0.9)
				(max_width 2)
				(curved_edges yes)
				(filter_ratio 0.9)
				(enabled yes)
				(allow_two_segments yes)
				(prefer_zone_connections yes)
			)
		)
	)
	(footprint "antmicro-footprints:R_0402_1005Metric"
		(layer "B.Cu")
		(at 124.702 147.8)
		(descr "Resistor SMD 0402")
		(tags "resistor SMD 0402")
		(property "Reference" "R214"
			(at 0.848 0.41 0)
			(layer "B.SilkS")
			(effects
				(font
					(size 0.7 0.7)
					(thickness 0.15)
				)
				(justify right bottom mirror)
			)
		)
		(property "Value" "R_0R_0402"
			(at -1.011843 -1.772047 0)
			(layer "B.Fab")
			(effects
				(font
					(size 0.7 0.7)
					(thickness 0.15)
				)
				(justify right bottom mirror)
			)
		)
		(property "Datasheet" "https://industrial.panasonic.com/cdbs/www-data/pdf/RDA0000/AOA0000C301.pdf"
			(at 0 0 0)
			(layer "F.Fab")
			(hide yes)
			(effects
				(font
					(size 1.27 1.27)
					(thickness 0.15)
				)
			)
		)
		(property "Author" "Antmicro"
			(at 0 0 0)
			(layer "B.Fab")
			(hide yes)
			(effects
				(font
					(size 1 1)
					(thickness 0.15)
				)
				(justify mirror)
			)
		)
		(property "Current" "1A"
			(at 0 0 0)
			(layer "B.Fab")
			(hide yes)
			(effects
				(font
					(size 1 1)
					(thickness 0.15)
				)
				(justify mirror)
			)
		)
		(property "License" "Apache-2.0"
			(at 0 0 0)
			(layer "B.Fab")
			(hide yes)
			(effects
				(font
					(size 1 1)
					(thickness 0.15)
				)
				(justify mirror)
			)
		)
		(property "MPN" "ERJ2GE0R00X"
			(at 0 0 0)
			(layer "B.Fab")
			(hide yes)
			(effects
				(font
					(size 1 1)
					(thickness 0.15)
				)
				(justify mirror)
			)
		)
		(property "Manufacturer" "Panasonic"
			(at 0 0 0)
			(layer "B.Fab")
			(hide yes)
			(effects
				(font
					(size 1 1)
					(thickness 0.15)
				)
				(justify mirror)
			)
		)
		(property "Public" "False"
			(at 0 0 0)
			(layer "B.Fab")
			(hide yes)
			(effects
				(font
					(size 1 1)
					(thickness 0.15)
				)
				(justify mirror)
			)
		)
		(property "Tolerance" ""
			(at 0 0 0)
			(layer "B.Fab")
			(hide yes)
			(effects
				(font
					(size 1 1)
					(thickness 0.15)
				)
				(justify mirror)
			)
		)
		(property "Val" "0R"
			(at 0 0 0)
			(layer "B.Fab")
			(hide yes)
			(effects
				(font
					(size 1 1)
					(thickness 0.15)
				)
				(justify mirror)
			)
		)
		(sheetname "PCIe redriver")
		(sheetfile "pcie_redriver.kicad_sch")
		(attr smd)
		(fp_rect
			(start -0.925 0.47)
			(end 0.925 -0.47)
			(stroke
				(width 0.05)
				(type default)
			)
			(fill no)
			(layer "B.CrtYd")
		)
		(fp_rect
			(start -0.5 0.25)
			(end 0.5 -0.25)
			(stroke
				(width 0.15)
				(type solid)
			)
			(fill no)
			(layer "B.Fab")
		)
		(pad "1" smd roundrect
			(at -0.48 0)
			(size 0.59 0.64)
			(layers "B.Cu" "B.Mask" "B.Paste")
			(roundrect_rratio 0.25)
			(net 629 "Net-(U39-EN_{I2C})")
			(pintype "passive")
			(teardrops
				(best_length_ratio 0.2)
				(max_length 1)
				(best_width_ratio 0.9)
				(max_width 2)
				(curved_edges yes)
				(filter_ratio 0.9)
				(enabled yes)
				(allow_two_segments yes)
				(prefer_zone_connections yes)
			)
		)
		(pad "2" smd roundrect
			(at 0.48 0)
			(size 0.59 0.64)
			(layers "B.Cu" "B.Mask" "B.Paste")
			(roundrect_rratio 0.25)
			(net 1 "GND")
			(pintype "passive")
			(teardrops
				(best_length_ratio 0.2)
				(max_length 1)
				(best_width_ratio 0.9)
				(max_width 2)
				(curved_edges yes)
				(filter_ratio 0.9)
				(enabled yes)
				(allow_two_segments yes)
				(prefer_zone_connections yes)
			)
		)
	)
	(footprint "antmicro-footprints:R_0402_1005Metric"
		(layer "B.Cu")
		(at 140.05 169.16 -90)
		(descr "Resistor SMD 0402")
		(tags "resistor SMD 0402")
		(property "Reference" "R54"
			(at -3.9 13.5 90)
			(layer "B.SilkS")
			(effects
				(font
					(size 0.7 0.7)
					(thickness 0.15)
				)
				(justify left bottom mirror)
			)
		)
		(property "Value" "R_1k_0402"
			(at -1.011843 -1.772047 90)
			(layer "B.Fab")
			(effects
				(font
					(size 0.7 0.7)
					(thickness 0.15)
				)
				(justify left bottom mirror)
			)
		)
		(property "Datasheet" "https://www.bourns.com/docs/product-datasheets/cr.pdf"
			(at 0 0 270)
			(layer "F.Fab")
			(hide yes)
			(effects
				(font
					(size 1.27 1.27)
					(thickness 0.15)
				)
			)
		)
		(property "Author" "Antmicro"
			(at -29.11 309.21 0)
			(layer "B.Fab")
			(hide yes)
			(effects
				(font
					(size 1 1)
					(thickness 0.15)
				)
				(justify mirror)
			)
		)
		(property "License" "Apache-2.0"
			(at -29.11 309.21 0)
			(layer "B.Fab")
			(hide yes)
			(effects
				(font
					(size 1 1)
					(thickness 0.15)
				)
				(justify mirror)
			)
		)
		(property "MPN" "CR0402-FX-1001GLF"
			(at -29.11 309.21 0)
			(layer "B.Fab")
			(hide yes)
			(effects
				(font
					(size 1 1)
					(thickness 0.15)
				)
				(justify mirror)
			)
		)
		(property "Manufacturer" "Bourns"
			(at -29.11 309.21 0)
			(layer "B.Fab")
			(hide yes)
			(effects
				(font
					(size 1 1)
					(thickness 0.15)
				)
				(justify mirror)
			)
		)
		(property "Public" "False"
			(at -29.11 309.21 0)
			(layer "B.Fab")
			(hide yes)
			(effects
				(font
					(size 1 1)
					(thickness 0.15)
				)
				(justify mirror)
			)
		)
		(property "Tolerance" "1%"
			(at -29.11 309.21 0)
			(layer "B.Fab")
			(hide yes)
			(effects
				(font
					(size 1 1)
					(thickness 0.15)
				)
				(justify mirror)
			)
		)
		(property "Val" "1k"
			(at -29.11 309.21 0)
			(layer "B.Fab")
			(hide yes)
			(effects
				(font
					(size 1 1)
					(thickness 0.15)
				)
				(justify mirror)
			)
		)
		(sheetname "2xSFP+")
		(sheetfile "2xSFP+.kicad_sch")
		(attr smd)
		(fp_rect
			(start -0.925 0.47)
			(end 0.925 -0.47)
			(stroke
				(width 0.05)
				(type default)
			)
			(fill no)
			(layer "B.CrtYd")
		)
		(fp_rect
			(start -0.5 0.25)
			(end 0.5 -0.25)
			(stroke
				(width 0.15)
				(type solid)
			)
			(fill no)
			(layer "B.Fab")
		)
		(pad "1" smd roundrect
			(at -0.48 0 270)
			(size 0.59 0.64)
			(layers "B.Cu" "B.Mask" "B.Paste")
			(roundrect_rratio 0.25)
			(net 896 "Net-(J2B-RX_{LOS})")
			(pintype "passive")
			(teardrops
				(best_length_ratio 0.2)
				(max_length 1)
				(best_width_ratio 0.9)
				(max_width 2)
				(curved_edges yes)
				(filter_ratio 0.9)
				(enabled yes)
				(allow_two_segments yes)
				(prefer_zone_connections yes)
			)
		)
		(pad "2" smd roundrect
			(at 0.48 0 270)
			(size 0.59 0.64)
			(layers "B.Cu" "B.Mask" "B.Paste")
			(roundrect_rratio 0.25)
			(net 2 "+3V3")
			(pintype "passive")
			(teardrops
				(best_length_ratio 0.2)
				(max_length 1)
				(best_width_ratio 0.9)
				(max_width 2)
				(curved_edges yes)
				(filter_ratio 0.9)
				(enabled yes)
				(allow_two_segments yes)
				(prefer_zone_connections yes)
			)
		)
	)
	(footprint "antmicro-footprints:C_0402_1005Metric"
		(layer "B.Cu")
		(at 124.45 157.14 -90)
		(descr "Capacitor SMD 0402")
		(tags "capacitor SMD 0402")
		(property "Reference" "C211"
			(at -1.33 0.55 90)
			(layer "B.SilkS")
			(effects
				(font
					(size 0.7 0.7)
					(thickness 0.15)
				)
				(justify left bottom mirror)
			)
		)
		(property "Value" "C_100n_0402"
			(at -1.022927 -2.155213 90)
			(layer "B.Fab")
			(effects
				(font
					(size 0.7 0.7)
					(thickness 0.15)
				)
				(justify left bottom mirror)
			)
		)
		(property "Datasheet" "https://www.murata.com/products/productdetail?partno=GRM155R61H104KE14%23"
			(at 0 0 270)
			(layer "F.Fab")
			(hide yes)
			(effects
				(font
					(size 1.27 1.27)
					(thickness 0.15)
				)
			)
		)
		(property "Author" "Antmicro"
			(at -32.69 281.59 0)
			(layer "B.Fab")
			(hide yes)
			(effects
				(font
					(size 1 1)
					(thickness 0.15)
				)
				(justify mirror)
			)
		)
		(property "Dielectric" "X5R"
			(at -32.69 281.59 0)
			(layer "B.Fab")
			(hide yes)
			(effects
				(font
					(size 1 1)
					(thickness 0.15)
				)
				(justify mirror)
			)
		)
		(property "License" "Apache-2.0"
			(at -32.69 281.59 0)
			(layer "B.Fab")
			(hide yes)
			(effects
				(font
					(size 1 1)
					(thickness 0.15)
				)
				(justify mirror)
			)
		)
		(property "MPN" "GRM155R61H104KE14D"
			(at -32.69 281.59 0)
			(layer "B.Fab")
			(hide yes)
			(effects
				(font
					(size 1 1)
					(thickness 0.15)
				)
				(justify mirror)
			)
		)
		(property "Manufacturer" "Murata"
			(at -32.69 281.59 0)
			(layer "B.Fab")
			(hide yes)
			(effects
				(font
					(size 1 1)
					(thickness 0.15)
				)
				(justify mirror)
			)
		)
		(property "Public" "False"
			(at -32.69 281.59 0)
			(layer "B.Fab")
			(hide yes)
			(effects
				(font
					(size 1 1)
					(thickness 0.15)
				)
				(justify mirror)
			)
		)
		(property "Val" "100n"
			(at -32.69 281.59 0)
			(layer "B.Fab")
			(hide yes)
			(effects
				(font
					(size 1 1)
					(thickness 0.15)
				)
				(justify mirror)
			)
		)
		(property "Voltage" "50V"
			(at -32.69 281.59 0)
			(layer "B.Fab")
			(hide yes)
			(effects
				(font
					(size 1 1)
					(thickness 0.15)
				)
				(justify mirror)
			)
		)
		(sheetname "2xSFP+")
		(sheetfile "2xSFP+.kicad_sch")
		(attr smd)
		(fp_rect
			(start -0.925 0.47)
			(end 0.925 -0.47)
			(stroke
				(width 0.05)
				(type default)
			)
			(fill no)
			(layer "B.CrtYd")
		)
		(fp_line
			(start -0.494 0.25)
			(end -0.494 -0.248)
			(stroke
				(width 0.15)
				(type solid)
			)
			(layer "B.Fab")
		)
		(fp_line
			(start 0.504 0.25)
			(end -0.494 0.25)
			(stroke
				(width 0.15)
				(type solid)
			)
			(layer "B.Fab")
		)
		(fp_line
			(start -0.494 -0.248)
			(end 0.504 -0.248)
			(stroke
				(width 0.15)
				(type solid)
			)
			(layer "B.Fab")
		)
		(fp_line
			(start 0.504 -0.248)
			(end 0.504 0.25)
			(stroke
				(width 0.15)
				(type solid)
			)
			(layer "B.Fab")
		)
		(pad "1" smd roundrect
			(at -0.48 0 270)
			(size 0.59 0.64)
			(layers "B.Cu" "B.Mask" "B.Paste")
			(roundrect_rratio 0.25)
			(net 53 "/2xSFP+/SH")
			(pintype "passive")
			(teardrops
				(best_length_ratio 0.2)
				(max_length 1)
				(best_width_ratio 0.9)
				(max_width 2)
				(curved_edges yes)
				(filter_ratio 0.9)
				(enabled yes)
				(allow_two_segments yes)
				(prefer_zone_connections yes)
			)
		)
		(pad "2" smd roundrect
			(at 0.48 0 270)
			(size 0.59 0.64)
			(layers "B.Cu" "B.Mask" "B.Paste")
			(roundrect_rratio 0.25)
			(net 1 "GND")
			(pintype "passive")
			(teardrops
				(best_length_ratio 0.2)
				(max_length 1)
				(best_width_ratio 0.9)
				(max_width 2)
				(curved_edges yes)
				(filter_ratio 0.9)
				(enabled yes)
				(allow_two_segments yes)
				(prefer_zone_connections yes)
			)
		)
	)
	(footprint "antmicro-footprints:R_0402_1005Metric"
		(layer "B.Cu")
		(at 144.25 141.06)
		(descr "Resistor SMD 0402")
		(tags "resistor SMD 0402")
		(property "Reference" "R258"
			(at -1.45 5.4 0)
			(layer "B.SilkS")
			(effects
				(font
					(size 0.7 0.7)
					(thickness 0.15)
				)
				(justify right bottom mirror)
			)
		)
		(property "Value" "R_10k_0402"
			(at -1.011843 -1.772047 0)
			(layer "B.Fab")
			(effects
				(font
					(size 0.7 0.7)
					(thickness 0.15)
				)
				(justify right bottom mirror)
			)
		)
		(property "Datasheet" "https://www.bourns.com/docs/product-datasheets/cr.pdf"
			(at 0 0 0)
			(layer "F.Fab")
			(hide yes)
			(effects
				(font
					(size 1.27 1.27)
					(thickness 0.15)
				)
			)
		)
		(property "Author" "Antmicro"
			(at 0 0 0)
			(layer "B.Fab")
			(hide yes)
			(effects
				(font
					(size 1 1)
					(thickness 0.15)
				)
				(justify mirror)
			)
		)
		(property "License" "Apache-2.0"
			(at 0 0 0)
			(layer "B.Fab")
			(hide yes)
			(effects
				(font
					(size 1 1)
					(thickness 0.15)
				)
				(justify mirror)
			)
		)
		(property "MPN" "CR0402-FX-1002GLF"
			(at 0 0 0)
			(layer "B.Fab")
			(hide yes)
			(effects
				(font
					(size 1 1)
					(thickness 0.15)
				)
				(justify mirror)
			)
		)
		(property "Manufacturer" "Bourns"
			(at 0 0 0)
			(layer "B.Fab")
			(hide yes)
			(effects
				(font
					(size 1 1)
					(thickness 0.15)
				)
				(justify mirror)
			)
		)
		(property "Public" "False"
			(at 0 0 0)
			(layer "B.Fab")
			(hide yes)
			(effects
				(font
					(size 1 1)
					(thickness 0.15)
				)
				(justify mirror)
			)
		)
		(property "Tolerance" "1%"
			(at 0 0 0)
			(layer "B.Fab")
			(hide yes)
			(effects
				(font
					(size 1 1)
					(thickness 0.15)
				)
				(justify mirror)
			)
		)
		(property "Val" "10k"
			(at 0 0 0)
			(layer "B.Fab")
			(hide yes)
			(effects
				(font
					(size 1 1)
					(thickness 0.15)
				)
				(justify mirror)
			)
		)
		(sheetname "KR to SFI #1")
		(sheetfile "kr_sfi.kicad_sch")
		(attr smd)
		(fp_rect
			(start -0.925 0.47)
			(end 0.925 -0.47)
			(stroke
				(width 0.05)
				(type default)
			)
			(fill no)
			(layer "B.CrtYd")
		)
		(fp_rect
			(start -0.5 0.25)
			(end 0.5 -0.25)
			(stroke
				(width 0.15)
				(type solid)
			)
			(fill no)
			(layer "B.Fab")
		)
		(pad "1" smd roundrect
			(at -0.48 0)
			(size 0.59 0.64)
			(layers "B.Cu" "B.Mask" "B.Paste")
			(roundrect_rratio 0.25)
			(net 1 "GND")
			(pintype "passive")
			(teardrops
				(best_length_ratio 0.2)
				(max_length 1)
				(best_width_ratio 0.9)
				(max_width 2)
				(curved_edges yes)
				(filter_ratio 0.9)
				(enabled yes)
				(allow_two_segments yes)
				(prefer_zone_connections yes)
			)
		)
		(pad "2" smd roundrect
			(at 0.48 0)
			(size 0.59 0.64)
			(layers "B.Cu" "B.Mask" "B.Paste")
			(roundrect_rratio 0.25)
			(net 654 "Net-(U43C-GPI0)")
			(pintype "passive")
			(teardrops
				(best_length_ratio 0.2)
				(max_length 1)
				(best_width_ratio 0.9)
				(max_width 2)
				(curved_edges yes)
				(filter_ratio 0.9)
				(enabled yes)
				(allow_two_segments yes)
				(prefer_zone_connections yes)
			)
		)
	)
	(footprint "antmicro-footprints:C_0402_1005Metric"
		(layer "B.Cu")
		(at 128.79 133.87)
		(descr "Capacitor SMD 0402")
		(tags "capacitor SMD 0402")
		(property "Reference" "C193"
			(at -4.19 -4.91 0)
			(layer "B.SilkS")
			(effects
				(font
					(size 0.7 0.7)
					(thickness 0.15)
				)
				(justify right bottom mirror)
			)
		)
		(property "Value" "C_100n_0402"
			(at -1.022927 -2.155213 0)
			(layer "B.Fab")
			(effects
				(font
					(size 0.7 0.7)
					(thickness 0.15)
				)
				(justify right bottom mirror)
			)
		)
		(property "Datasheet" "https://www.murata.com/products/productdetail?partno=GRM155R61H104KE14%23"
			(at 0 0 0)
			(layer "F.Fab")
			(hide yes)
			(effects
				(font
					(size 1.27 1.27)
					(thickness 0.15)
				)
			)
		)
		(property "Author" "Antmicro"
			(at 0 0 0)
			(layer "B.Fab")
			(hide yes)
			(effects
				(font
					(size 1 1)
					(thickness 0.15)
				)
				(justify mirror)
			)
		)
		(property "Dielectric" "X5R"
			(at 0 0 0)
			(layer "B.Fab")
			(hide yes)
			(effects
				(font
					(size 1 1)
					(thickness 0.15)
				)
				(justify mirror)
			)
		)
		(property "License" "Apache-2.0"
			(at 0 0 0)
			(layer "B.Fab")
			(hide yes)
			(effects
				(font
					(size 1 1)
					(thickness 0.15)
				)
				(justify mirror)
			)
		)
		(property "MPN" "GRM155R61H104KE14D"
			(at 0 0 0)
			(layer "B.Fab")
			(hide yes)
			(effects
				(font
					(size 1 1)
					(thickness 0.15)
				)
				(justify mirror)
			)
		)
		(property "Manufacturer" "Murata"
			(at 0 0 0)
			(layer "B.Fab")
			(hide yes)
			(effects
				(font
					(size 1 1)
					(thickness 0.15)
				)
				(justify mirror)
			)
		)
		(property "Public" "False"
			(at 0 0 0)
			(layer "B.Fab")
			(hide yes)
			(effects
				(font
					(size 1 1)
					(thickness 0.15)
				)
				(justify mirror)
			)
		)
		(property "Val" "100n"
			(at 0 0 0)
			(layer "B.Fab")
			(hide yes)
			(effects
				(font
					(size 1 1)
					(thickness 0.15)
				)
				(justify mirror)
			)
		)
		(property "Voltage" "50V"
			(at 0 0 0)
			(layer "B.Fab")
			(hide yes)
			(effects
				(font
					(size 1 1)
					(thickness 0.15)
				)
				(justify mirror)
			)
		)
		(sheetname "KR to SFI #2")
		(sheetfile "kr_sfi.kicad_sch")
		(attr smd)
		(fp_rect
			(start -0.925 0.47)
			(end 0.925 -0.47)
			(stroke
				(width 0.05)
				(type default)
			)
			(fill no)
			(layer "B.CrtYd")
		)
		(fp_line
			(start -0.494 -0.248)
			(end 0.504 -0.248)
			(stroke
				(width 0.15)
				(type solid)
			)
			(layer "B.Fab")
		)
		(fp_line
			(start -0.494 0.25)
			(end -0.494 -0.248)
			(stroke
				(width 0.15)
				(type solid)
			)
			(layer "B.Fab")
		)
		(fp_line
			(start 0.504 -0.248)
			(end 0.504 0.25)
			(stroke
				(width 0.15)
				(type solid)
			)
			(layer "B.Fab")
		)
		(fp_line
			(start 0.504 0.25)
			(end -0.494 0.25)
			(stroke
				(width 0.15)
				(type solid)
			)
			(layer "B.Fab")
		)
		(pad "1" smd roundrect
			(at -0.48 0)
			(size 0.59 0.64)
			(layers "B.Cu" "B.Mask" "B.Paste")
			(roundrect_rratio 0.25)
			(net 1 "GND")
			(pintype "passive")
			(teardrops
				(best_length_ratio 0.2)
				(max_length 1)
				(best_width_ratio 0.9)
				(max_width 2)
				(curved_edges yes)
				(filter_ratio 0.9)
				(enabled yes)
				(allow_two_segments yes)
				(prefer_zone_connections yes)
			)
		)
		(pad "2" smd roundrect
			(at 0.48 0)
			(size 0.59 0.64)
			(layers "B.Cu" "B.Mask" "B.Paste")
			(roundrect_rratio 0.25)
			(net 78 "+1V8")
			(pintype "passive")
			(teardrops
				(best_length_ratio 0.2)
				(max_length 1)
				(best_width_ratio 0.9)
				(max_width 2)
				(curved_edges yes)
				(filter_ratio 0.9)
				(enabled yes)
				(allow_two_segments yes)
				(prefer_zone_connections yes)
			)
		)
	)
	(footprint "antmicro-footprints:C_0603_1608Metric"
		(layer "B.Cu")
		(at 148.7 87.23 180)
		(descr "Capacitor SMD 0603")
		(tags "capacitor 0603")
		(property "Reference" "C81"
			(at -3.3 -0.53 0)
			(layer "B.SilkS")
			(effects
				(font
					(size 0.7 0.7)
					(thickness 0.15)
				)
				(justify left bottom mirror)
			)
		)
		(property "Value" "C_22u_16V_0603"
			(at -1.42757 -1.770288 0)
			(layer "B.Fab")
			(effects
				(font
					(size 0.7 0.7)
					(thickness 0.15)
				)
				(justify left bottom mirror)
			)
		)
		(property "Datasheet" "https://product.samsungsem.com/mlcc/CL10A226MO7JZN.do"
			(at 0 0 180)
			(layer "F.Fab")
			(hide yes)
			(effects
				(font
					(size 1.27 1.27)
					(thickness 0.15)
				)
			)
		)
		(property "Author" "Antmicro"
			(at 297.4 174.46 0)
			(layer "B.Fab")
			(hide yes)
			(effects
				(font
					(size 1 1)
					(thickness 0.15)
				)
				(justify mirror)
			)
		)
		(property "Dielectric" ""
			(at 297.4 174.46 0)
			(layer "B.Fab")
			(hide yes)
			(effects
				(font
					(size 1 1)
					(thickness 0.15)
				)
				(justify mirror)
			)
		)
		(property "License" "Apache-2.0"
			(at 297.4 174.46 0)
			(layer "B.Fab")
			(hide yes)
			(effects
				(font
					(size 1 1)
					(thickness 0.15)
				)
				(justify mirror)
			)
		)
		(property "MPN" "CL10A226MO7JZNC"
			(at 297.4 174.46 0)
			(layer "B.Fab")
			(hide yes)
			(effects
				(font
					(size 1 1)
					(thickness 0.15)
				)
				(justify mirror)
			)
		)
		(property "Manufacturer" "Samsung Electro-Mechanics"
			(at 297.4 174.46 0)
			(layer "B.Fab")
			(hide yes)
			(effects
				(font
					(size 1 1)
					(thickness 0.15)
				)
				(justify mirror)
			)
		)
		(property "Public" "False"
			(at 297.4 174.46 0)
			(layer "B.Fab")
			(hide yes)
			(effects
				(font
					(size 1 1)
					(thickness 0.15)
				)
				(justify mirror)
			)
		)
		(property "Val" "22u"
			(at 297.4 174.46 0)
			(layer "B.Fab")
			(hide yes)
			(effects
				(font
					(size 1 1)
					(thickness 0.15)
				)
				(justify mirror)
			)
		)
		(property "Voltage" "16V"
			(at 297.4 174.46 0)
			(layer "B.Fab")
			(hide yes)
			(effects
				(font
					(size 1 1)
					(thickness 0.15)
				)
				(justify mirror)
			)
		)
		(sheetname "M.2 key E")
		(sheetfile "m2keye.kicad_sch")
		(attr smd)
		(fp_line
			(start 0.15 0.4)
			(end -0.15 0.4)
			(stroke
				(width 0.15)
				(type solid)
			)
			(layer "B.SilkS")
		)
		(fp_line
			(start 0.15 -0.4)
			(end -0.15 -0.4)
			(stroke
				(width 0.15)
				(type solid)
			)
			(layer "B.SilkS")
		)
		(fp_rect
			(start -1.25 0.65)
			(end 1.25 -0.65)
			(stroke
				(width 0.05)
				(type solid)
			)
			(fill no)
			(layer "B.CrtYd")
		)
		(fp_rect
			(start -0.8 0.4)
			(end 0.8 -0.4)
			(stroke
				(width 0.15)
				(type solid)
			)
			(fill no)
			(layer "B.Fab")
		)
		(pad "1" smd roundrect
			(at -0.7 0 180)
			(size 0.8 1)
			(layers "B.Cu" "B.Mask" "B.Paste")
			(roundrect_rratio 0.2)
			(net 1 "GND")
			(pintype "passive")
			(teardrops
				(best_length_ratio 0.2)
				(max_length 1)
				(best_width_ratio 0.9)
				(max_width 2)
				(curved_edges yes)
				(filter_ratio 0.9)
				(enabled yes)
				(allow_two_segments yes)
				(prefer_zone_connections yes)
			)
		)
		(pad "2" smd roundrect
			(at 0.7 0 180)
			(size 0.8 1)
			(layers "B.Cu" "B.Mask" "B.Paste")
			(roundrect_rratio 0.2)
			(net 2 "+3V3")
			(pintype "passive")
			(teardrops
				(best_length_ratio 0.2)
				(max_length 1)
				(best_width_ratio 0.9)
				(max_width 2)
				(curved_edges yes)
				(filter_ratio 0.9)
				(enabled yes)
				(allow_two_segments yes)
				(prefer_zone_connections yes)
			)
		)
	)
	(footprint "antmicro-footprints:C_0402_1005Metric"
		(layer "B.Cu")
		(at 146.95 133.87)
		(descr "Capacitor SMD 0402")
		(tags "capacitor SMD 0402")
		(property "Reference" "C166"
			(at -4.3 -4.91 0)
			(layer "B.SilkS")
			(effects
				(font
					(size 0.7 0.7)
					(thickness 0.15)
				)
				(justify right bottom mirror)
			)
		)
		(property "Value" "C_100n_0402"
			(at -1.022927 -2.155213 0)
			(layer "B.Fab")
			(effects
				(font
					(size 0.7 0.7)
					(thickness 0.15)
				)
				(justify right bottom mirror)
			)
		)
		(property "Datasheet" "https://www.murata.com/products/productdetail?partno=GRM155R61H104KE14%23"
			(at 0 0 0)
			(layer "F.Fab")
			(hide yes)
			(effects
				(font
					(size 1.27 1.27)
					(thickness 0.15)
				)
			)
		)
		(property "Author" "Antmicro"
			(at 0 0 0)
			(layer "B.Fab")
			(hide yes)
			(effects
				(font
					(size 1 1)
					(thickness 0.15)
				)
				(justify mirror)
			)
		)
		(property "Dielectric" "X5R"
			(at 0 0 0)
			(layer "B.Fab")
			(hide yes)
			(effects
				(font
					(size 1 1)
					(thickness 0.15)
				)
				(justify mirror)
			)
		)
		(property "License" "Apache-2.0"
			(at 0 0 0)
			(layer "B.Fab")
			(hide yes)
			(effects
				(font
					(size 1 1)
					(thickness 0.15)
				)
				(justify mirror)
			)
		)
		(property "MPN" "GRM155R61H104KE14D"
			(at 0 0 0)
			(layer "B.Fab")
			(hide yes)
			(effects
				(font
					(size 1 1)
					(thickness 0.15)
				)
				(justify mirror)
			)
		)
		(property "Manufacturer" "Murata"
			(at 0 0 0)
			(layer "B.Fab")
			(hide yes)
			(effects
				(font
					(size 1 1)
					(thickness 0.15)
				)
				(justify mirror)
			)
		)
		(property "Public" "False"
			(at 0 0 0)
			(layer "B.Fab")
			(hide yes)
			(effects
				(font
					(size 1 1)
					(thickness 0.15)
				)
				(justify mirror)
			)
		)
		(property "Val" "100n"
			(at 0 0 0)
			(layer "B.Fab")
			(hide yes)
			(effects
				(font
					(size 1 1)
					(thickness 0.15)
				)
				(justify mirror)
			)
		)
		(property "Voltage" "50V"
			(at 0 0 0)
			(layer "B.Fab")
			(hide yes)
			(effects
				(font
					(size 1 1)
					(thickness 0.15)
				)
				(justify mirror)
			)
		)
		(sheetname "KR to SFI #1")
		(sheetfile "kr_sfi.kicad_sch")
		(attr smd)
		(fp_rect
			(start -0.925 0.47)
			(end 0.925 -0.47)
			(stroke
				(width 0.05)
				(type default)
			)
			(fill no)
			(layer "B.CrtYd")
		)
		(fp_line
			(start -0.494 -0.248)
			(end 0.504 -0.248)
			(stroke
				(width 0.15)
				(type solid)
			)
			(layer "B.Fab")
		)
		(fp_line
			(start -0.494 0.25)
			(end -0.494 -0.248)
			(stroke
				(width 0.15)
				(type solid)
			)
			(layer "B.Fab")
		)
		(fp_line
			(start 0.504 -0.248)
			(end 0.504 0.25)
			(stroke
				(width 0.15)
				(type solid)
			)
			(layer "B.Fab")
		)
		(fp_line
			(start 0.504 0.25)
			(end -0.494 0.25)
			(stroke
				(width 0.15)
				(type solid)
			)
			(layer "B.Fab")
		)
		(pad "1" smd roundrect
			(at -0.48 0)
			(size 0.59 0.64)
			(layers "B.Cu" "B.Mask" "B.Paste")
			(roundrect_rratio 0.25)
			(net 1 "GND")
			(pintype "passive")
			(teardrops
				(best_length_ratio 0.2)
				(max_length 1)
				(best_width_ratio 0.9)
				(max_width 2)
				(curved_edges yes)
				(filter_ratio 0.9)
				(enabled yes)
				(allow_two_segments yes)
				(prefer_zone_connections yes)
			)
		)
		(pad "2" smd roundrect
			(at 0.48 0)
			(size 0.59 0.64)
			(layers "B.Cu" "B.Mask" "B.Paste")
			(roundrect_rratio 0.25)
			(net 78 "+1V8")
			(pintype "passive")
			(teardrops
				(best_length_ratio 0.2)
				(max_length 1)
				(best_width_ratio 0.9)
				(max_width 2)
				(curved_edges yes)
				(filter_ratio 0.9)
				(enabled yes)
				(allow_two_segments yes)
				(prefer_zone_connections yes)
			)
		)
	)
	(footprint "antmicro-footprints:C_0402_1005Metric"
		(layer "B.Cu")
		(at 137 162.76)
		(descr "Capacitor SMD 0402")
		(tags "capacitor SMD 0402")
		(property "Reference" "C25"
			(at -3.05 0.45 0)
			(layer "B.SilkS")
			(effects
				(font
					(size 0.7 0.7)
					(thickness 0.15)
				)
				(justify right bottom mirror)
			)
		)
		(property "Value" "C_100n_0402"
			(at -1.022927 -2.155213 0)
			(layer "B.Fab")
			(effects
				(font
					(size 0.7 0.7)
					(thickness 0.15)
				)
				(justify right bottom mirror)
			)
		)
		(property "Datasheet" "https://www.murata.com/products/productdetail?partno=GRM155R61H104KE14%23"
			(at 0 0 0)
			(layer "F.Fab")
			(hide yes)
			(effects
				(font
					(size 1.27 1.27)
					(thickness 0.15)
				)
			)
		)
		(property "Author" "Antmicro"
			(at 0 0 0)
			(layer "B.Fab")
			(hide yes)
			(effects
				(font
					(size 1 1)
					(thickness 0.15)
				)
				(justify mirror)
			)
		)
		(property "Dielectric" "X5R"
			(at 0 0 0)
			(layer "B.Fab")
			(hide yes)
			(effects
				(font
					(size 1 1)
					(thickness 0.15)
				)
				(justify mirror)
			)
		)
		(property "License" "Apache-2.0"
			(at 0 0 0)
			(layer "B.Fab")
			(hide yes)
			(effects
				(font
					(size 1 1)
					(thickness 0.15)
				)
				(justify mirror)
			)
		)
		(property "MPN" "GRM155R61H104KE14D"
			(at 0 0 0)
			(layer "B.Fab")
			(hide yes)
			(effects
				(font
					(size 1 1)
					(thickness 0.15)
				)
				(justify mirror)
			)
		)
		(property "Manufacturer" "Murata"
			(at 0 0 0)
			(layer "B.Fab")
			(hide yes)
			(effects
				(font
					(size 1 1)
					(thickness 0.15)
				)
				(justify mirror)
			)
		)
		(property "Public" "False"
			(at 0 0 0)
			(layer "B.Fab")
			(hide yes)
			(effects
				(font
					(size 1 1)
					(thickness 0.15)
				)
				(justify mirror)
			)
		)
		(property "Val" "100n"
			(at 0 0 0)
			(layer "B.Fab")
			(hide yes)
			(effects
				(font
					(size 1 1)
					(thickness 0.15)
				)
				(justify mirror)
			)
		)
		(property "Voltage" "50V"
			(at 0 0 0)
			(layer "B.Fab")
			(hide yes)
			(effects
				(font
					(size 1 1)
					(thickness 0.15)
				)
				(justify mirror)
			)
		)
		(sheetname "2xSFP+")
		(sheetfile "2xSFP+.kicad_sch")
		(attr smd)
		(fp_rect
			(start -0.925 0.47)
			(end 0.925 -0.47)
			(stroke
				(width 0.05)
				(type default)
			)
			(fill no)
			(layer "B.CrtYd")
		)
		(fp_line
			(start -0.494 -0.248)
			(end 0.504 -0.248)
			(stroke
				(width 0.15)
				(type solid)
			)
			(layer "B.Fab")
		)
		(fp_line
			(start -0.494 0.25)
			(end -0.494 -0.248)
			(stroke
				(width 0.15)
				(type solid)
			)
			(layer "B.Fab")
		)
		(fp_line
			(start 0.504 -0.248)
			(end 0.504 0.25)
			(stroke
				(width 0.15)
				(type solid)
			)
			(layer "B.Fab")
		)
		(fp_line
			(start 0.504 0.25)
			(end -0.494 0.25)
			(stroke
				(width 0.15)
				(type solid)
			)
			(layer "B.Fab")
		)
		(pad "1" smd roundrect
			(at -0.48 0)
			(size 0.59 0.64)
			(layers "B.Cu" "B.Mask" "B.Paste")
			(roundrect_rratio 0.25)
			(net 1 "GND")
			(pintype "passive")
			(teardrops
				(best_length_ratio 0.2)
				(max_length 1)
				(best_width_ratio 0.9)
				(max_width 2)
				(curved_edges yes)
				(filter_ratio 0.9)
				(enabled yes)
				(allow_two_segments yes)
				(prefer_zone_connections yes)
			)
		)
		(pad "2" smd roundrect
			(at 0.48 0)
			(size 0.59 0.64)
			(layers "B.Cu" "B.Mask" "B.Paste")
			(roundrect_rratio 0.25)
			(net 2 "+3V3")
			(pintype "passive")
			(teardrops
				(best_length_ratio 0.2)
				(max_length 1)
				(best_width_ratio 0.9)
				(max_width 2)
				(curved_edges yes)
				(filter_ratio 0.9)
				(enabled yes)
				(allow_two_segments yes)
				(prefer_zone_connections yes)
			)
		)
	)
	(footprint "antmicro-footprints:C_0402_1005Metric"
		(layer "B.Cu")
		(at 151.45 141.36 -90)
		(descr "Capacitor SMD 0402")
		(tags "capacitor SMD 0402")
		(property "Reference" "C168"
			(at 0.85 -0.45 90)
			(layer "B.SilkS")
			(effects
				(font
					(size 0.7 0.7)
					(thickness 0.15)
				)
				(justify left bottom mirror)
			)
		)
		(property "Value" "C_100n_0402"
			(at -1.022927 -2.155213 90)
			(layer "B.Fab")
			(effects
				(font
					(size 0.7 0.7)
					(thickness 0.15)
				)
				(justify left bottom mirror)
			)
		)
		(property "Datasheet" "https://www.murata.com/products/productdetail?partno=GRM155R61H104KE14%23"
			(at 0 0 270)
			(layer "F.Fab")
			(hide yes)
			(effects
				(font
					(size 1.27 1.27)
					(thickness 0.15)
				)
			)
		)
		(property "Author" "Antmicro"
			(at 10.09 292.81 0)
			(layer "B.Fab")
			(hide yes)
			(effects
				(font
					(size 1 1)
					(thickness 0.15)
				)
				(justify mirror)
			)
		)
		(property "Dielectric" "X5R"
			(at 10.09 292.81 0)
			(layer "B.Fab")
			(hide yes)
			(effects
				(font
					(size 1 1)
					(thickness 0.15)
				)
				(justify mirror)
			)
		)
		(property "License" "Apache-2.0"
			(at 10.09 292.81 0)
			(layer "B.Fab")
			(hide yes)
			(effects
				(font
					(size 1 1)
					(thickness 0.15)
				)
				(justify mirror)
			)
		)
		(property "MPN" "GRM155R61H104KE14D"
			(at 10.09 292.81 0)
			(layer "B.Fab")
			(hide yes)
			(effects
				(font
					(size 1 1)
					(thickness 0.15)
				)
				(justify mirror)
			)
		)
		(property "Manufacturer" "Murata"
			(at 10.09 292.81 0)
			(layer "B.Fab")
			(hide yes)
			(effects
				(font
					(size 1 1)
					(thickness 0.15)
				)
				(justify mirror)
			)
		)
		(property "Public" "False"
			(at 10.09 292.81 0)
			(layer "B.Fab")
			(hide yes)
			(effects
				(font
					(size 1 1)
					(thickness 0.15)
				)
				(justify mirror)
			)
		)
		(property "Val" "100n"
			(at 10.09 292.81 0)
			(layer "B.Fab")
			(hide yes)
			(effects
				(font
					(size 1 1)
					(thickness 0.15)
				)
				(justify mirror)
			)
		)
		(property "Voltage" "50V"
			(at 10.09 292.81 0)
			(layer "B.Fab")
			(hide yes)
			(effects
				(font
					(size 1 1)
					(thickness 0.15)
				)
				(justify mirror)
			)
		)
		(sheetname "KR to SFI #1")
		(sheetfile "kr_sfi.kicad_sch")
		(attr smd)
		(fp_rect
			(start -0.925 0.47)
			(end 0.925 -0.47)
			(stroke
				(width 0.05)
				(type default)
			)
			(fill no)
			(layer "B.CrtYd")
		)
		(fp_line
			(start -0.494 0.25)
			(end -0.494 -0.248)
			(stroke
				(width 0.15)
				(type solid)
			)
			(layer "B.Fab")
		)
		(fp_line
			(start 0.504 0.25)
			(end -0.494 0.25)
			(stroke
				(width 0.15)
				(type solid)
			)
			(layer "B.Fab")
		)
		(fp_line
			(start -0.494 -0.248)
			(end 0.504 -0.248)
			(stroke
				(width 0.15)
				(type solid)
			)
			(layer "B.Fab")
		)
		(fp_line
			(start 0.504 -0.248)
			(end 0.504 0.25)
			(stroke
				(width 0.15)
				(type solid)
			)
			(layer "B.Fab")
		)
		(pad "1" smd roundrect
			(at -0.48 0 270)
			(size 0.59 0.64)
			(layers "B.Cu" "B.Mask" "B.Paste")
			(roundrect_rratio 0.25)
			(net 1 "GND")
			(pintype "passive")
			(teardrops
				(best_length_ratio 0.2)
				(max_length 1)
				(best_width_ratio 0.9)
				(max_width 2)
				(curved_edges yes)
				(filter_ratio 0.9)
				(enabled yes)
				(allow_two_segments yes)
				(prefer_zone_connections yes)
			)
		)
		(pad "2" smd roundrect
			(at 0.48 0 270)
			(size 0.59 0.64)
			(layers "B.Cu" "B.Mask" "B.Paste")
			(roundrect_rratio 0.25)
			(net 74 "+1V0")
			(pintype "passive")
			(teardrops
				(best_length_ratio 0.2)
				(max_length 1)
				(best_width_ratio 0.9)
				(max_width 2)
				(curved_edges yes)
				(filter_ratio 0.9)
				(enabled yes)
				(allow_two_segments yes)
				(prefer_zone_connections yes)
			)
		)
	)
	(footprint "antmicro-footprints:C_0402_1005Metric"
		(layer "B.Cu")
		(at 146.95 137.86)
		(descr "Capacitor SMD 0402")
		(tags "capacitor SMD 0402")
		(property "Reference" "C160"
			(at -1.5 1.35 0)
			(layer "B.SilkS")
			(effects
				(font
					(size 0.7 0.7)
					(thickness 0.15)
				)
				(justify right bottom mirror)
			)
		)
		(property "Value" "C_100n_0402"
			(at -1.022927 -2.155213 0)
			(layer "B.Fab")
			(effects
				(font
					(size 0.7 0.7)
					(thickness 0.15)
				)
				(justify right bottom mirror)
			)
		)
		(property "Datasheet" "https://www.murata.com/products/productdetail?partno=GRM155R61H104KE14%23"
			(at 0 0 0)
			(layer "F.Fab")
			(hide yes)
			(effects
				(font
					(size 1.27 1.27)
					(thickness 0.15)
				)
			)
		)
		(property "Author" "Antmicro"
			(at 0 0 0)
			(layer "B.Fab")
			(hide yes)
			(effects
				(font
					(size 1 1)
					(thickness 0.15)
				)
				(justify mirror)
			)
		)
		(property "Dielectric" "X5R"
			(at 0 0 0)
			(layer "B.Fab")
			(hide yes)
			(effects
				(font
					(size 1 1)
					(thickness 0.15)
				)
				(justify mirror)
			)
		)
		(property "License" "Apache-2.0"
			(at 0 0 0)
			(layer "B.Fab")
			(hide yes)
			(effects
				(font
					(size 1 1)
					(thickness 0.15)
				)
				(justify mirror)
			)
		)
		(property "MPN" "GRM155R61H104KE14D"
			(at 0 0 0)
			(layer "B.Fab")
			(hide yes)
			(effects
				(font
					(size 1 1)
					(thickness 0.15)
				)
				(justify mirror)
			)
		)
		(property "Manufacturer" "Murata"
			(at 0 0 0)
			(layer "B.Fab")
			(hide yes)
			(effects
				(font
					(size 1 1)
					(thickness 0.15)
				)
				(justify mirror)
			)
		)
		(property "Public" "False"
			(at 0 0 0)
			(layer "B.Fab")
			(hide yes)
			(effects
				(font
					(size 1 1)
					(thickness 0.15)
				)
				(justify mirror)
			)
		)
		(property "Val" "100n"
			(at 0 0 0)
			(layer "B.Fab")
			(hide yes)
			(effects
				(font
					(size 1 1)
					(thickness 0.15)
				)
				(justify mirror)
			)
		)
		(property "Voltage" "50V"
			(at 0 0 0)
			(layer "B.Fab")
			(hide yes)
			(effects
				(font
					(size 1 1)
					(thickness 0.15)
				)
				(justify mirror)
			)
		)
		(sheetname "KR to SFI #1")
		(sheetfile "kr_sfi.kicad_sch")
		(attr smd)
		(fp_rect
			(start -0.925 0.47)
			(end 0.925 -0.47)
			(stroke
				(width 0.05)
				(type default)
			)
			(fill no)
			(layer "B.CrtYd")
		)
		(fp_line
			(start -0.494 -0.248)
			(end 0.504 -0.248)
			(stroke
				(width 0.15)
				(type solid)
			)
			(layer "B.Fab")
		)
		(fp_line
			(start -0.494 0.25)
			(end -0.494 -0.248)
			(stroke
				(width 0.15)
				(type solid)
			)
			(layer "B.Fab")
		)
		(fp_line
			(start 0.504 -0.248)
			(end 0.504 0.25)
			(stroke
				(width 0.15)
				(type solid)
			)
			(layer "B.Fab")
		)
		(fp_line
			(start 0.504 0.25)
			(end -0.494 0.25)
			(stroke
				(width 0.15)
				(type solid)
			)
			(layer "B.Fab")
		)
		(pad "1" smd roundrect
			(at -0.48 0)
			(size 0.59 0.64)
			(layers "B.Cu" "B.Mask" "B.Paste")
			(roundrect_rratio 0.25)
			(net 1 "GND")
			(pintype "passive")
			(teardrops
				(best_length_ratio 0.2)
				(max_length 1)
				(best_width_ratio 0.9)
				(max_width 2)
				(curved_edges yes)
				(filter_ratio 0.9)
				(enabled yes)
				(allow_two_segments yes)
				(prefer_zone_connections yes)
			)
		)
		(pad "2" smd roundrect
			(at 0.48 0)
			(size 0.59 0.64)
			(layers "B.Cu" "B.Mask" "B.Paste")
			(roundrect_rratio 0.25)
			(net 74 "+1V0")
			(pintype "passive")
			(teardrops
				(best_length_ratio 0.2)
				(max_length 1)
				(best_width_ratio 0.9)
				(max_width 2)
				(curved_edges yes)
				(filter_ratio 0.9)
				(enabled yes)
				(allow_two_segments yes)
				(prefer_zone_connections yes)
			)
		)
	)
	(footprint "antmicro-footprints:C_0402_1005Metric"
		(layer "B.Cu")
		(at 133.29 132.36 -90)
		(descr "Capacitor SMD 0402")
		(tags "capacitor SMD 0402")
		(property "Reference" "C192"
			(at -3.7 -0.41 90)
			(layer "B.SilkS")
			(effects
				(font
					(size 0.7 0.7)
					(thickness 0.15)
				)
				(justify left bottom mirror)
			)
		)
		(property "Value" "C_100n_0402"
			(at -1.022927 -2.155213 90)
			(layer "B.Fab")
			(effects
				(font
					(size 0.7 0.7)
					(thickness 0.15)
				)
				(justify left bottom mirror)
			)
		)
		(property "Datasheet" "https://www.murata.com/products/productdetail?partno=GRM155R61H104KE14%23"
			(at 0 0 270)
			(layer "F.Fab")
			(hide yes)
			(effects
				(font
					(size 1.27 1.27)
					(thickness 0.15)
				)
			)
		)
		(property "Author" "Antmicro"
			(at 0.93 265.65 0)
			(layer "B.Fab")
			(hide yes)
			(effects
				(font
					(size 1 1)
					(thickness 0.15)
				)
				(justify mirror)
			)
		)
		(property "Dielectric" "X5R"
			(at 0.93 265.65 0)
			(layer "B.Fab")
			(hide yes)
			(effects
				(font
					(size 1 1)
					(thickness 0.15)
				)
				(justify mirror)
			)
		)
		(property "License" "Apache-2.0"
			(at 0.93 265.65 0)
			(layer "B.Fab")
			(hide yes)
			(effects
				(font
					(size 1 1)
					(thickness 0.15)
				)
				(justify mirror)
			)
		)
		(property "MPN" "GRM155R61H104KE14D"
			(at 0.93 265.65 0)
			(layer "B.Fab")
			(hide yes)
			(effects
				(font
					(size 1 1)
					(thickness 0.15)
				)
				(justify mirror)
			)
		)
		(property "Manufacturer" "Murata"
			(at 0.93 265.65 0)
			(layer "B.Fab")
			(hide yes)
			(effects
				(font
					(size 1 1)
					(thickness 0.15)
				)
				(justify mirror)
			)
		)
		(property "Public" "False"
			(at 0.93 265.65 0)
			(layer "B.Fab")
			(hide yes)
			(effects
				(font
					(size 1 1)
					(thickness 0.15)
				)
				(justify mirror)
			)
		)
		(property "Val" "100n"
			(at 0.93 265.65 0)
			(layer "B.Fab")
			(hide yes)
			(effects
				(font
					(size 1 1)
					(thickness 0.15)
				)
				(justify mirror)
			)
		)
		(property "Voltage" "50V"
			(at 0.93 265.65 0)
			(layer "B.Fab")
			(hide yes)
			(effects
				(font
					(size 1 1)
					(thickness 0.15)
				)
				(justify mirror)
			)
		)
		(sheetname "KR to SFI #2")
		(sheetfile "kr_sfi.kicad_sch")
		(attr smd)
		(fp_rect
			(start -0.925 0.47)
			(end 0.925 -0.47)
			(stroke
				(width 0.05)
				(type default)
			)
			(fill no)
			(layer "B.CrtYd")
		)
		(fp_line
			(start -0.494 0.25)
			(end -0.494 -0.248)
			(stroke
				(width 0.15)
				(type solid)
			)
			(layer "B.Fab")
		)
		(fp_line
			(start 0.504 0.25)
			(end -0.494 0.25)
			(stroke
				(width 0.15)
				(type solid)
			)
			(layer "B.Fab")
		)
		(fp_line
			(start -0.494 -0.248)
			(end 0.504 -0.248)
			(stroke
				(width 0.15)
				(type solid)
			)
			(layer "B.Fab")
		)
		(fp_line
			(start 0.504 -0.248)
			(end 0.504 0.25)
			(stroke
				(width 0.15)
				(type solid)
			)
			(layer "B.Fab")
		)
		(pad "1" smd roundrect
			(at -0.48 0 270)
			(size 0.59 0.64)
			(layers "B.Cu" "B.Mask" "B.Paste")
			(roundrect_rratio 0.25)
			(net 1 "GND")
			(pintype "passive")
			(teardrops
				(best_length_ratio 0.2)
				(max_length 1)
				(best_width_ratio 0.9)
				(max_width 2)
				(curved_edges yes)
				(filter_ratio 0.9)
				(enabled yes)
				(allow_two_segments yes)
				(prefer_zone_connections yes)
			)
		)
		(pad "2" smd roundrect
			(at 0.48 0 270)
			(size 0.59 0.64)
			(layers "B.Cu" "B.Mask" "B.Paste")
			(roundrect_rratio 0.25)
			(net 74 "+1V0")
			(pintype "passive")
			(teardrops
				(best_length_ratio 0.2)
				(max_length 1)
				(best_width_ratio 0.9)
				(max_width 2)
				(curved_edges yes)
				(filter_ratio 0.9)
				(enabled yes)
				(allow_two_segments yes)
				(prefer_zone_connections yes)
			)
		)
	)
	(footprint "antmicro-footprints:TP_SMD_0.75mm"
		(layer "B.Cu")
		(at 258.95 85.71 180)
		(property "Reference" "TP12"
			(at 0.399999 -0.4 0)
			(layer "B.SilkS")
			(effects
				(font
					(size 0.7 0.7)
					(thickness 0.15)
				)
				(justify left bottom mirror)
			)
		)
		(property "Value" "TP_0.75mm_SMD"
			(at 0 -1.2 0)
			(layer "B.Fab")
			(effects
				(font
					(size 0.7 0.7)
					(thickness 0.15)
				)
				(justify left bottom mirror)
			)
		)
		(property "Author" "Antmicro"
			(at 517.9 171.42 0)
			(layer "B.Fab")
			(hide yes)
			(effects
				(font
					(size 1 1)
					(thickness 0.15)
				)
				(justify mirror)
			)
		)
		(property "License" "Apache-2.0"
			(at 517.9 171.42 0)
			(layer "B.Fab")
			(hide yes)
			(effects
				(font
					(size 1 1)
					(thickness 0.15)
				)
				(justify mirror)
			)
		)
		(property "MPN" ""
			(at 517.9 171.42 0)
			(layer "B.Fab")
			(hide yes)
			(effects
				(font
					(size 1 1)
					(thickness 0.15)
				)
				(justify mirror)
			)
		)
		(property "Manufacturer" ""
			(at 517.9 171.42 0)
			(layer "B.Fab")
			(hide yes)
			(effects
				(font
					(size 1 1)
					(thickness 0.15)
				)
				(justify mirror)
			)
		)
		(property "Public" "False"
			(at 517.9 171.42 0)
			(layer "B.Fab")
			(hide yes)
			(effects
				(font
					(size 1 1)
					(thickness 0.15)
				)
				(justify mirror)
			)
		)
		(sheetname "Misc")
		(sheetfile "misc.kicad_sch")
		(attr exclude_from_pos_files exclude_from_bom)
		(fp_circle
			(center 0 0)
			(end 0.475 0)
			(stroke
				(width 0.05)
				(type default)
			)
			(fill no)
			(layer "B.CrtYd")
		)
		(pad "1" smd circle
			(at 0 0 180)
			(size 0.75 0.75)
			(layers "B.Cu" "B.Mask")
			(net 704 "Net-(U24-GPIO2)")
			(pinfunction "1")
			(pintype "passive")
			(teardrops
				(best_length_ratio 0.4)
				(max_length 1)
				(best_width_ratio 0.9)
				(max_width 2)
				(curved_edges yes)
				(filter_ratio 0.9)
				(enabled yes)
				(allow_two_segments yes)
				(prefer_zone_connections yes)
			)
		)
	)
	(footprint "antmicro-footprints:C_0603_1608Metric"
		(layer "B.Cu")
		(at 104.65 156.86 180)
		(descr "Capacitor SMD 0603")
		(tags "capacitor 0603")
		(property "Reference" "C36"
			(at -3.15 -1.09 0)
			(layer "B.SilkS")
			(effects
				(font
					(size 0.7 0.7)
					(thickness 0.15)
				)
				(justify left bottom mirror)
			)
		)
		(property "Value" "C_22u_16V_0603"
			(at -1.42757 -1.770288 0)
			(layer "B.Fab")
			(effects
				(font
					(size 0.7 0.7)
					(thickness 0.15)
				)
				(justify left bottom mirror)
			)
		)
		(property "Datasheet" "https://product.samsungsem.com/mlcc/CL10A226MO7JZN.do"
			(at 0 0 180)
			(layer "F.Fab")
			(hide yes)
			(effects
				(font
					(size 1.27 1.27)
					(thickness 0.15)
				)
			)
		)
		(property "Author" "Antmicro"
			(at 209.3 313.72 0)
			(layer "B.Fab")
			(hide yes)
			(effects
				(font
					(size 1 1)
					(thickness 0.15)
				)
				(justify mirror)
			)
		)
		(property "Dielectric" ""
			(at 209.3 313.72 0)
			(layer "B.Fab")
			(hide yes)
			(effects
				(font
					(size 1 1)
					(thickness 0.15)
				)
				(justify mirror)
			)
		)
		(property "License" "Apache-2.0"
			(at 209.3 313.72 0)
			(layer "B.Fab")
			(hide yes)
			(effects
				(font
					(size 1 1)
					(thickness 0.15)
				)
				(justify mirror)
			)
		)
		(property "MPN" "CL10A226MO7JZNC"
			(at 209.3 313.72 0)
			(layer "B.Fab")
			(hide yes)
			(effects
				(font
					(size 1 1)
					(thickness 0.15)
				)
				(justify mirror)
			)
		)
		(property "Manufacturer" "Samsung Electro-Mechanics"
			(at 209.3 313.72 0)
			(layer "B.Fab")
			(hide yes)
			(effects
				(font
					(size 1 1)
					(thickness 0.15)
				)
				(justify mirror)
			)
		)
		(property "Public" "False"
			(at 209.3 313.72 0)
			(layer "B.Fab")
			(hide yes)
			(effects
				(font
					(size 1 1)
					(thickness 0.15)
				)
				(justify mirror)
			)
		)
		(property "Val" "22u"
			(at 209.3 313.72 0)
			(layer "B.Fab")
			(hide yes)
			(effects
				(font
					(size 1 1)
					(thickness 0.15)
				)
				(justify mirror)
			)
		)
		(property "Voltage" "16V"
			(at 209.3 313.72 0)
			(layer "B.Fab")
			(hide yes)
			(effects
				(font
					(size 1 1)
					(thickness 0.15)
				)
				(justify mirror)
			)
		)
		(sheetname "OCuLink")
		(sheetfile "oculink.kicad_sch")
		(attr smd)
		(fp_line
			(start 0.15 0.4)
			(end -0.15 0.4)
			(stroke
				(width 0.15)
				(type solid)
			)
			(layer "B.SilkS")
		)
		(fp_line
			(start 0.15 -0.4)
			(end -0.15 -0.4)
			(stroke
				(width 0.15)
				(type solid)
			)
			(layer "B.SilkS")
		)
		(fp_rect
			(start -1.25 0.65)
			(end 1.25 -0.65)
			(stroke
				(width 0.05)
				(type solid)
			)
			(fill no)
			(layer "B.CrtYd")
		)
		(fp_rect
			(start -0.8 0.4)
			(end 0.8 -0.4)
			(stroke
				(width 0.15)
				(type solid)
			)
			(fill no)
			(layer "B.Fab")
		)
		(pad "1" smd roundrect
			(at -0.7 0 180)
			(size 0.8 1)
			(layers "B.Cu" "B.Mask" "B.Paste")
			(roundrect_rratio 0.2)
			(net 1 "GND")
			(pintype "passive")
			(teardrops
				(best_length_ratio 0.2)
				(max_length 1)
				(best_width_ratio 0.9)
				(max_width 2)
				(curved_edges yes)
				(filter_ratio 0.9)
				(enabled yes)
				(allow_two_segments yes)
				(prefer_zone_connections yes)
			)
		)
		(pad "2" smd roundrect
			(at 0.7 0 180)
			(size 0.8 1)
			(layers "B.Cu" "B.Mask" "B.Paste")
			(roundrect_rratio 0.2)
			(net 59 "/OCuLink/V_{ACT_TX}0")
			(pintype "passive")
			(teardrops
				(best_length_ratio 0.2)
				(max_length 1)
				(best_width_ratio 0.9)
				(max_width 2)
				(curved_edges yes)
				(filter_ratio 0.9)
				(enabled yes)
				(allow_two_segments yes)
				(prefer_zone_connections yes)
			)
		)
	)
	(footprint "antmicro-footprints:TP_SMD_0.75mm"
		(layer "B.Cu")
		(at 143.55 167.21 180)
		(property "Reference" "TP3"
			(at -0.75 0.5 0)
			(layer "B.SilkS")
			(effects
				(font
					(size 0.7 0.7)
					(thickness 0.15)
				)
				(justify left bottom mirror)
			)
		)
		(property "Value" "TP_0.75mm_SMD"
			(at 0 -1.2 0)
			(layer "B.Fab")
			(effects
				(font
					(size 0.7 0.7)
					(thickness 0.15)
				)
				(justify left bottom mirror)
			)
		)
		(property "Author" "Antmicro"
			(at 287.1 334.42 0)
			(layer "B.Fab")
			(hide yes)
			(effects
				(font
					(size 1 1)
					(thickness 0.15)
				)
				(justify mirror)
			)
		)
		(property "License" "Apache-2.0"
			(at 287.1 334.42 0)
			(layer "B.Fab")
			(hide yes)
			(effects
				(font
					(size 1 1)
					(thickness 0.15)
				)
				(justify mirror)
			)
		)
		(property "MPN" ""
			(at 287.1 334.42 0)
			(layer "B.Fab")
			(hide yes)
			(effects
				(font
					(size 1 1)
					(thickness 0.15)
				)
				(justify mirror)
			)
		)
		(property "Manufacturer" ""
			(at 287.1 334.42 0)
			(layer "B.Fab")
			(hide yes)
			(effects
				(font
					(size 1 1)
					(thickness 0.15)
				)
				(justify mirror)
			)
		)
		(property "Public" "False"
			(at 287.1 334.42 0)
			(layer "B.Fab")
			(hide yes)
			(effects
				(font
					(size 1 1)
					(thickness 0.15)
				)
				(justify mirror)
			)
		)
		(sheetname "2xSFP+")
		(sheetfile "2xSFP+.kicad_sch")
		(attr exclude_from_pos_files exclude_from_bom)
		(fp_circle
			(center 0 0)
			(end 0.475 0)
			(stroke
				(width 0.05)
				(type default)
			)
			(fill no)
			(layer "B.CrtYd")
		)
		(pad "1" smd circle
			(at 0 0 180)
			(size 0.75 0.75)
			(layers "B.Cu" "B.Mask")
			(net 162 "Net-(J2A-TX_{FAULT})")
			(pinfunction "1")
			(pintype "passive")
			(teardrops
				(best_length_ratio 0.4)
				(max_length 1)
				(best_width_ratio 0.9)
				(max_width 2)
				(curved_edges yes)
				(filter_ratio 0.9)
				(enabled yes)
				(allow_two_segments yes)
				(prefer_zone_connections yes)
			)
		)
	)
	(footprint "antmicro-footprints:C_0402_1005Metric"
		(layer "B.Cu")
		(at 109.811 166.847571 180)
		(descr "Capacitor SMD 0402")
		(tags "capacitor SMD 0402")
		(property "Reference" "C142"
			(at -3.689 -0.462429 0)
			(layer "B.SilkS")
			(effects
				(font
					(size 0.7 0.7)
					(thickness 0.15)
				)
				(justify left bottom mirror)
			)
		)
		(property "Value" "C_220n_0402"
			(at -1.022927 -2.155213 0)
			(layer "B.Fab")
			(effects
				(font
					(size 0.7 0.7)
					(thickness 0.15)
				)
				(justify left bottom mirror)
			)
		)
		(property "Datasheet" "https://www.yageo.com/en/Chart/Download/pdf/CC0402KRX5R6BB224"
			(at 0 0 180)
			(layer "F.Fab")
			(hide yes)
			(effects
				(font
					(size 1.27 1.27)
					(thickness 0.15)
				)
			)
		)
		(property "Author" "Antmicro"
			(at 219.622 333.695142 0)
			(layer "B.Fab")
			(hide yes)
			(effects
				(font
					(size 1 1)
					(thickness 0.15)
				)
				(justify mirror)
			)
		)
		(property "Dielectric" ""
			(at 219.622 333.695142 0)
			(layer "B.Fab")
			(hide yes)
			(effects
				(font
					(size 1 1)
					(thickness 0.15)
				)
				(justify mirror)
			)
		)
		(property "License" "Apache-2.0"
			(at 219.622 333.695142 0)
			(layer "B.Fab")
			(hide yes)
			(effects
				(font
					(size 1 1)
					(thickness 0.15)
				)
				(justify mirror)
			)
		)
		(property "MPN" "CC0402KRX5R6BB224"
			(at 219.622 333.695142 0)
			(layer "B.Fab")
			(hide yes)
			(effects
				(font
					(size 1 1)
					(thickness 0.15)
				)
				(justify mirror)
			)
		)
		(property "Manufacturer" "YAGEO"
			(at 219.622 333.695142 0)
			(layer "B.Fab")
			(hide yes)
			(effects
				(font
					(size 1 1)
					(thickness 0.15)
				)
				(justify mirror)
			)
		)
		(property "Public" "False"
			(at 219.622 333.695142 0)
			(layer "B.Fab")
			(hide yes)
			(effects
				(font
					(size 1 1)
					(thickness 0.15)
				)
				(justify mirror)
			)
		)
		(property "Val" "220n"
			(at 219.622 333.695142 0)
			(layer "B.Fab")
			(hide yes)
			(effects
				(font
					(size 1 1)
					(thickness 0.15)
				)
				(justify mirror)
			)
		)
		(property "Voltage" ""
			(at 219.622 333.695142 0)
			(layer "B.Fab")
			(hide yes)
			(effects
				(font
					(size 1 1)
					(thickness 0.15)
				)
				(justify mirror)
			)
		)
		(sheetname "PCIe redriver")
		(sheetfile "pcie_redriver.kicad_sch")
		(attr smd)
		(fp_rect
			(start -0.925 0.47)
			(end 0.925 -0.47)
			(stroke
				(width 0.05)
				(type default)
			)
			(fill no)
			(layer "B.CrtYd")
		)
		(fp_line
			(start 0.504 0.25)
			(end -0.494 0.25)
			(stroke
				(width 0.15)
				(type solid)
			)
			(layer "B.Fab")
		)
		(fp_line
			(start 0.504 -0.248)
			(end 0.504 0.25)
			(stroke
				(width 0.15)
				(type solid)
			)
			(layer "B.Fab")
		)
		(fp_line
			(start -0.494 0.25)
			(end -0.494 -0.248)
			(stroke
				(width 0.15)
				(type solid)
			)
			(layer "B.Fab")
		)
		(fp_line
			(start -0.494 -0.248)
			(end 0.504 -0.248)
			(stroke
				(width 0.15)
				(type solid)
			)
			(layer "B.Fab")
		)
		(pad "1" smd roundrect
			(at -0.48 0 180)
			(size 0.59 0.64)
			(layers "B.Cu" "B.Mask" "B.Paste")
			(roundrect_rratio 0.25)
			(net 963 "/PCIe redriver/PCIe_{O}_C.TX0+")
			(pintype "passive")
			(teardrops
				(best_length_ratio 0.2)
				(max_length 1)
				(best_width_ratio 0.9)
				(max_width 2)
				(curved_edges yes)
				(filter_ratio 0.9)
				(enabled yes)
				(allow_two_segments yes)
				(prefer_zone_connections yes)
			)
		)
		(pad "2" smd roundrect
			(at 0.48 0 180)
			(size 0.59 0.64)
			(layers "B.Cu" "B.Mask" "B.Paste")
			(roundrect_rratio 0.25)
			(net 100 "/OCuLink/PCIe_{x4}.TX0+")
			(pintype "passive")
			(teardrops
				(best_length_ratio 0.2)
				(max_length 1)
				(best_width_ratio 0.9)
				(max_width 2)
				(curved_edges yes)
				(filter_ratio 0.9)
				(enabled yes)
				(allow_two_segments yes)
				(prefer_zone_connections yes)
			)
		)
	)
	(footprint "antmicro-footprints:R_0402_1005Metric"
		(layer "B.Cu")
		(at 142.05 169.16 -90)
		(descr "Resistor SMD 0402")
		(tags "resistor SMD 0402")
		(property "Reference" "R52"
			(at -3.9 13.5 90)
			(layer "B.SilkS")
			(effects
				(font
					(size 0.7 0.7)
					(thickness 0.15)
				)
				(justify left bottom mirror)
			)
		)
		(property "Value" "R_1k_0402"
			(at -1.011843 -1.772047 90)
			(layer "B.Fab")
			(effects
				(font
					(size 0.7 0.7)
					(thickness 0.15)
				)
				(justify left bottom mirror)
			)
		)
		(property "Datasheet" "https://www.bourns.com/docs/product-datasheets/cr.pdf"
			(at 0 0 270)
			(layer "F.Fab")
			(hide yes)
			(effects
				(font
					(size 1.27 1.27)
					(thickness 0.15)
				)
			)
		)
		(property "Author" "Antmicro"
			(at -27.11 311.21 0)
			(layer "B.Fab")
			(hide yes)
			(effects
				(font
					(size 1 1)
					(thickness 0.15)
				)
				(justify mirror)
			)
		)
		(property "License" "Apache-2.0"
			(at -27.11 311.21 0)
			(layer "B.Fab")
			(hide yes)
			(effects
				(font
					(size 1 1)
					(thickness 0.15)
				)
				(justify mirror)
			)
		)
		(property "MPN" "CR0402-FX-1001GLF"
			(at -27.11 311.21 0)
			(layer "B.Fab")
			(hide yes)
			(effects
				(font
					(size 1 1)
					(thickness 0.15)
				)
				(justify mirror)
			)
		)
		(property "Manufacturer" "Bourns"
			(at -27.11 311.21 0)
			(layer "B.Fab")
			(hide yes)
			(effects
				(font
					(size 1 1)
					(thickness 0.15)
				)
				(justify mirror)
			)
		)
		(property "Public" "False"
			(at -27.11 311.21 0)
			(layer "B.Fab")
			(hide yes)
			(effects
				(font
					(size 1 1)
					(thickness 0.15)
				)
				(justify mirror)
			)
		)
		(property "Tolerance" "1%"
			(at -27.11 311.21 0)
			(layer "B.Fab")
			(hide yes)
			(effects
				(font
					(size 1 1)
					(thickness 0.15)
				)
				(justify mirror)
			)
		)
		(property "Val" "1k"
			(at -27.11 311.21 0)
			(layer "B.Fab")
			(hide yes)
			(effects
				(font
					(size 1 1)
					(thickness 0.15)
				)
				(justify mirror)
			)
		)
		(sheetname "2xSFP+")
		(sheetfile "2xSFP+.kicad_sch")
		(attr smd)
		(fp_rect
			(start -0.925 0.47)
			(end 0.925 -0.47)
			(stroke
				(width 0.05)
				(type default)
			)
			(fill no)
			(layer "B.CrtYd")
		)
		(fp_rect
			(start -0.5 0.25)
			(end 0.5 -0.25)
			(stroke
				(width 0.15)
				(type solid)
			)
			(fill no)
			(layer "B.Fab")
		)
		(pad "1" smd roundrect
			(at -0.48 0 270)
			(size 0.59 0.64)
			(layers "B.Cu" "B.Mask" "B.Paste")
			(roundrect_rratio 0.25)
			(net 876 "Net-(J2B-TX_{FAULT})")
			(pintype "passive")
			(teardrops
				(best_length_ratio 0.2)
				(max_length 1)
				(best_width_ratio 0.9)
				(max_width 2)
				(curved_edges yes)
				(filter_ratio 0.9)
				(enabled yes)
				(allow_two_segments yes)
				(prefer_zone_connections yes)
			)
		)
		(pad "2" smd roundrect
			(at 0.48 0 270)
			(size 0.59 0.64)
			(layers "B.Cu" "B.Mask" "B.Paste")
			(roundrect_rratio 0.25)
			(net 2 "+3V3")
			(pintype "passive")
			(teardrops
				(best_length_ratio 0.2)
				(max_length 1)
				(best_width_ratio 0.9)
				(max_width 2)
				(curved_edges yes)
				(filter_ratio 0.9)
				(enabled yes)
				(allow_two_segments yes)
				(prefer_zone_connections yes)
			)
		)
	)
	(footprint "antmicro-footprints:TP_SMD_0.75mm"
		(layer "B.Cu")
		(at 191.55 163.4 -90)
		(property "Reference" "TP41"
			(at -1 0.35 90)
			(layer "B.SilkS")
			(effects
				(font
					(size 0.7 0.7)
					(thickness 0.15)
				)
				(justify right top mirror)
			)
		)
		(property "Value" "TP_0.75mm_SMD"
			(at 3.225 -53.865 90)
			(layer "B.Fab")
			(hide yes)
			(effects
				(font
					(size 0.7 0.7)
					(thickness 0.15)
				)
				(justify left bottom mirror)
			)
		)
		(property "Author" "Antmicro"
			(at 432.8 311.62 90)
			(layer "B.Fab")
			(hide yes)
			(effects
				(font
					(size 1 1)
					(thickness 0.15)
				)
				(justify mirror)
			)
		)
		(property "License" "Apache-2.0"
			(at 432.8 311.62 90)
			(layer "B.Fab")
			(hide yes)
			(effects
				(font
					(size 1 1)
					(thickness 0.15)
				)
				(justify mirror)
			)
		)
		(property "MPN" ""
			(at 432.8 311.62 90)
			(layer "B.Fab")
			(hide yes)
			(effects
				(font
					(size 1 1)
					(thickness 0.15)
				)
				(justify mirror)
			)
		)
		(property "Manufacturer" ""
			(at 432.8 311.62 90)
			(layer "B.Fab")
			(hide yes)
			(effects
				(font
					(size 1 1)
					(thickness 0.15)
				)
				(justify mirror)
			)
		)
		(property "Public" "False"
			(at 432.8 311.62 90)
			(layer "B.Fab")
			(hide yes)
			(effects
				(font
					(size 1 1)
					(thickness 0.15)
				)
				(justify mirror)
			)
		)
		(sheetname "Com Express 7 MGMT")
		(sheetfile "com_express_7_mgmt.kicad_sch")
		(attr exclude_from_pos_files exclude_from_bom)
		(fp_circle
			(center 0 0)
			(end 0.475 0)
			(stroke
				(width 0.05)
				(type default)
			)
			(fill no)
			(layer "B.CrtYd")
		)
		(pad "1" smd circle
			(at 0 0 270)
			(size 0.75 0.75)
			(layers "B.Cu" "B.Mask")
			(net 370 "Net-(J12D-SPKR)")
			(pinfunction "1")
			(pintype "passive")
			(teardrops
				(best_length_ratio 0.4)
				(max_length 1)
				(best_width_ratio 0.9)
				(max_width 2)
				(curved_edges yes)
				(filter_ratio 0.9)
				(enabled yes)
				(allow_two_segments yes)
				(prefer_zone_connections yes)
			)
		)
	)
	(footprint "antmicro-footprints:C_0402_1005Metric"
		(layer "B.Cu")
		(at 132.45 157.14 -90)
		(descr "Capacitor SMD 0402")
		(tags "capacitor SMD 0402")
		(property "Reference" "C212"
			(at -1.33 0.55 90)
			(layer "B.SilkS")
			(effects
				(font
					(size 0.7 0.7)
					(thickness 0.15)
				)
				(justify left bottom mirror)
			)
		)
		(property "Value" "C_100n_0402"
			(at -1.022927 -2.155213 90)
			(layer "B.Fab")
			(effects
				(font
					(size 0.7 0.7)
					(thickness 0.15)
				)
				(justify left bottom mirror)
			)
		)
		(property "Datasheet" "https://www.murata.com/products/productdetail?partno=GRM155R61H104KE14%23"
			(at 0 0 270)
			(layer "F.Fab")
			(hide yes)
			(effects
				(font
					(size 1.27 1.27)
					(thickness 0.15)
				)
			)
		)
		(property "Author" "Antmicro"
			(at -24.69 289.59 0)
			(layer "B.Fab")
			(hide yes)
			(effects
				(font
					(size 1 1)
					(thickness 0.15)
				)
				(justify mirror)
			)
		)
		(property "Dielectric" "X5R"
			(at -24.69 289.59 0)
			(layer "B.Fab")
			(hide yes)
			(effects
				(font
					(size 1 1)
					(thickness 0.15)
				)
				(justify mirror)
			)
		)
		(property "License" "Apache-2.0"
			(at -24.69 289.59 0)
			(layer "B.Fab")
			(hide yes)
			(effects
				(font
					(size 1 1)
					(thickness 0.15)
				)
				(justify mirror)
			)
		)
		(property "MPN" "GRM155R61H104KE14D"
			(at -24.69 289.59 0)
			(layer "B.Fab")
			(hide yes)
			(effects
				(font
					(size 1 1)
					(thickness 0.15)
				)
				(justify mirror)
			)
		)
		(property "Manufacturer" "Murata"
			(at -24.69 289.59 0)
			(layer "B.Fab")
			(hide yes)
			(effects
				(font
					(size 1 1)
					(thickness 0.15)
				)
				(justify mirror)
			)
		)
		(property "Public" "False"
			(at -24.69 289.59 0)
			(layer "B.Fab")
			(hide yes)
			(effects
				(font
					(size 1 1)
					(thickness 0.15)
				)
				(justify mirror)
			)
		)
		(property "Val" "100n"
			(at -24.69 289.59 0)
			(layer "B.Fab")
			(hide yes)
			(effects
				(font
					(size 1 1)
					(thickness 0.15)
				)
				(justify mirror)
			)
		)
		(property "Voltage" "50V"
			(at -24.69 289.59 0)
			(layer "B.Fab")
			(hide yes)
			(effects
				(font
					(size 1 1)
					(thickness 0.15)
				)
				(justify mirror)
			)
		)
		(sheetname "2xSFP+")
		(sheetfile "2xSFP+.kicad_sch")
		(attr smd)
		(fp_rect
			(start -0.925 0.47)
			(end 0.925 -0.47)
			(stroke
				(width 0.05)
				(type default)
			)
			(fill no)
			(layer "B.CrtYd")
		)
		(fp_line
			(start -0.494 0.25)
			(end -0.494 -0.248)
			(stroke
				(width 0.15)
				(type solid)
			)
			(layer "B.Fab")
		)
		(fp_line
			(start 0.504 0.25)
			(end -0.494 0.25)
			(stroke
				(width 0.15)
				(type solid)
			)
			(layer "B.Fab")
		)
		(fp_line
			(start -0.494 -0.248)
			(end 0.504 -0.248)
			(stroke
				(width 0.15)
				(type solid)
			)
			(layer "B.Fab")
		)
		(fp_line
			(start 0.504 -0.248)
			(end 0.504 0.25)
			(stroke
				(width 0.15)
				(type solid)
			)
			(layer "B.Fab")
		)
		(pad "1" smd roundrect
			(at -0.48 0 270)
			(size 0.59 0.64)
			(layers "B.Cu" "B.Mask" "B.Paste")
			(roundrect_rratio 0.25)
			(net 53 "/2xSFP+/SH")
			(pintype "passive")
			(teardrops
				(best_length_ratio 0.2)
				(max_length 1)
				(best_width_ratio 0.9)
				(max_width 2)
				(curved_edges yes)
				(filter_ratio 0.9)
				(enabled yes)
				(allow_two_segments yes)
				(prefer_zone_connections yes)
			)
		)
		(pad "2" smd roundrect
			(at 0.48 0 270)
			(size 0.59 0.64)
			(layers "B.Cu" "B.Mask" "B.Paste")
			(roundrect_rratio 0.25)
			(net 1 "GND")
			(pintype "passive")
			(teardrops
				(best_length_ratio 0.2)
				(max_length 1)
				(best_width_ratio 0.9)
				(max_width 2)
				(curved_edges yes)
				(filter_ratio 0.9)
				(enabled yes)
				(allow_two_segments yes)
				(prefer_zone_connections yes)
			)
		)
	)
	(footprint "antmicro-footprints:R_0402_1005Metric"
		(layer "B.Cu")
		(at 126.09 136.06 180)
		(descr "Resistor SMD 0402")
		(tags "resistor SMD 0402")
		(property "Reference" "R293"
			(at 0.79 -0.45 0)
			(layer "B.SilkS")
			(effects
				(font
					(size 0.7 0.7)
					(thickness 0.15)
				)
				(justify left bottom mirror)
			)
		)
		(property "Value" "R_10k_0402"
			(at -1.011843 -1.772047 0)
			(layer "B.Fab")
			(effects
				(font
					(size 0.7 0.7)
					(thickness 0.15)
				)
				(justify left bottom mirror)
			)
		)
		(property "Datasheet" "https://www.bourns.com/docs/product-datasheets/cr.pdf"
			(at 0 0 180)
			(layer "F.Fab")
			(hide yes)
			(effects
				(font
					(size 1.27 1.27)
					(thickness 0.15)
				)
			)
		)
		(property "Author" "Antmicro"
			(at 252.18 272.12 0)
			(layer "B.Fab")
			(hide yes)
			(effects
				(font
					(size 1 1)
					(thickness 0.15)
				)
				(justify mirror)
			)
		)
		(property "License" "Apache-2.0"
			(at 252.18 272.12 0)
			(layer "B.Fab")
			(hide yes)
			(effects
				(font
					(size 1 1)
					(thickness 0.15)
				)
				(justify mirror)
			)
		)
		(property "MPN" "CR0402-FX-1002GLF"
			(at 252.18 272.12 0)
			(layer "B.Fab")
			(hide yes)
			(effects
				(font
					(size 1 1)
					(thickness 0.15)
				)
				(justify mirror)
			)
		)
		(property "Manufacturer" "Bourns"
			(at 252.18 272.12 0)
			(layer "B.Fab")
			(hide yes)
			(effects
				(font
					(size 1 1)
					(thickness 0.15)
				)
				(justify mirror)
			)
		)
		(property "Public" "False"
			(at 252.18 272.12 0)
			(layer "B.Fab")
			(hide yes)
			(effects
				(font
					(size 1 1)
					(thickness 0.15)
				)
				(justify mirror)
			)
		)
		(property "Tolerance" "1%"
			(at 252.18 272.12 0)
			(layer "B.Fab")
			(hide yes)
			(effects
				(font
					(size 1 1)
					(thickness 0.15)
				)
				(justify mirror)
			)
		)
		(property "Val" "10k"
			(at 252.18 272.12 0)
			(layer "B.Fab")
			(hide yes)
			(effects
				(font
					(size 1 1)
					(thickness 0.15)
				)
				(justify mirror)
			)
		)
		(sheetname "KR to SFI #2")
		(sheetfile "kr_sfi.kicad_sch")
		(attr smd)
		(fp_rect
			(start -0.925 0.47)
			(end 0.925 -0.47)
			(stroke
				(width 0.05)
				(type default)
			)
			(fill no)
			(layer "B.CrtYd")
		)
		(fp_rect
			(start -0.5 0.25)
			(end 0.5 -0.25)
			(stroke
				(width 0.15)
				(type solid)
			)
			(fill no)
			(layer "B.Fab")
		)
		(pad "1" smd roundrect
			(at -0.48 0 180)
			(size 0.59 0.64)
			(layers "B.Cu" "B.Mask" "B.Paste")
			(roundrect_rratio 0.25)
			(net 143 "/2xSFP+/KR to SFI #2/~{RESET}")
			(pintype "passive")
			(teardrops
				(best_length_ratio 0.2)
				(max_length 1)
				(best_width_ratio 0.9)
				(max_width 2)
				(curved_edges yes)
				(filter_ratio 0.9)
				(enabled yes)
				(allow_two_segments yes)
				(prefer_zone_connections yes)
			)
		)
		(pad "2" smd roundrect
			(at 0.48 0 180)
			(size 0.59 0.64)
			(layers "B.Cu" "B.Mask" "B.Paste")
			(roundrect_rratio 0.25)
			(net 78 "+1V8")
			(pintype "passive")
			(teardrops
				(best_length_ratio 0.2)
				(max_length 1)
				(best_width_ratio 0.9)
				(max_width 2)
				(curved_edges yes)
				(filter_ratio 0.9)
				(enabled yes)
				(allow_two_segments yes)
				(prefer_zone_connections yes)
			)
		)
	)
	(footprint "antmicro-footprints:TP_SMD_0.75mm"
		(layer "B.Cu")
		(at 182.35 165.75)
		(property "Reference" "TP26"
			(at -0.35 -0.75 90)
			(layer "B.SilkS")
			(effects
				(font
					(size 0.7 0.7)
					(thickness 0.15)
				)
				(justify right top mirror)
			)
		)
		(property "Value" "TP_0.75mm_SMD"
			(at 3.225 -53.865 0)
			(layer "B.Fab")
			(hide yes)
			(effects
				(font
					(size 0.7 0.7)
					(thickness 0.15)
				)
				(justify right top mirror)
			)
		)
		(property "Author" "Antmicro"
			(at 451.2 306.12 0)
			(layer "B.Fab")
			(hide yes)
			(effects
				(font
					(size 1 1)
					(thickness 0.15)
				)
				(justify mirror)
			)
		)
		(property "License" "Apache-2.0"
			(at 451.2 306.12 0)
			(layer "B.Fab")
			(hide yes)
			(effects
				(font
					(size 1 1)
					(thickness 0.15)
				)
				(justify mirror)
			)
		)
		(property "MPN" ""
			(at 451.2 306.12 0)
			(layer "B.Fab")
			(hide yes)
			(effects
				(font
					(size 1 1)
					(thickness 0.15)
				)
				(justify mirror)
			)
		)
		(property "Manufacturer" ""
			(at 451.2 306.12 0)
			(layer "B.Fab")
			(hide yes)
			(effects
				(font
					(size 1 1)
					(thickness 0.15)
				)
				(justify mirror)
			)
		)
		(property "Public" "False"
			(at 451.2 306.12 0)
			(layer "B.Fab")
			(hide yes)
			(effects
				(font
					(size 1 1)
					(thickness 0.15)
				)
				(justify mirror)
			)
		)
		(sheetname "Com Express 7 MGMT")
		(sheetfile "com_express_7_mgmt.kicad_sch")
		(attr exclude_from_pos_files exclude_from_bom)
		(fp_circle
			(center 0 0)
			(end 0.475 0)
			(stroke
				(width 0.05)
				(type default)
			)
			(fill no)
			(layer "B.CrtYd")
		)
		(pad "1" smd circle
			(at 0 0)
			(size 0.75 0.75)
			(layers "B.Cu" "B.Mask")
			(net 355 "Net-(J12D-LPC_CLK{slash}ESPI_CK)")
			(pinfunction "1")
			(pintype "passive")
			(teardrops
				(best_length_ratio 0.4)
				(max_length 1)
				(best_width_ratio 0.9)
				(max_width 2)
				(curved_edges yes)
				(filter_ratio 0.9)
				(enabled yes)
				(allow_two_segments yes)
				(prefer_zone_connections yes)
			)
		)
	)
	(footprint "antmicro-footprints:TP_SMD_0.75mm"
		(layer "B.Cu")
		(at 123.4 146.76 180)
		(property "Reference" "TP50"
			(at -3.15 -0.45 0)
			(layer "B.SilkS")
			(effects
				(font
					(size 0.7 0.7)
					(thickness 0.15)
				)
				(justify left bottom mirror)
			)
		)
		(property "Value" "TP_0.75mm_SMD"
			(at 0 -1.2 0)
			(layer "B.Fab")
			(effects
				(font
					(size 0.7 0.7)
					(thickness 0.15)
				)
				(justify left bottom mirror)
			)
		)
		(property "Author" "Antmicro"
			(at 246.8 293.52 0)
			(layer "B.Fab")
			(hide yes)
			(effects
				(font
					(size 1 1)
					(thickness 0.15)
				)
				(justify mirror)
			)
		)
		(property "License" "Apache-2.0"
			(at 246.8 293.52 0)
			(layer "B.Fab")
			(hide yes)
			(effects
				(font
					(size 1 1)
					(thickness 0.15)
				)
				(justify mirror)
			)
		)
		(property "MPN" ""
			(at 246.8 293.52 0)
			(layer "B.Fab")
			(hide yes)
			(effects
				(font
					(size 1 1)
					(thickness 0.15)
				)
				(justify mirror)
			)
		)
		(property "Manufacturer" ""
			(at 246.8 293.52 0)
			(layer "B.Fab")
			(hide yes)
			(effects
				(font
					(size 1 1)
					(thickness 0.15)
				)
				(justify mirror)
			)
		)
		(property "Public" "False"
			(at 246.8 293.52 0)
			(layer "B.Fab")
			(hide yes)
			(effects
				(font
					(size 1 1)
					(thickness 0.15)
				)
				(justify mirror)
			)
		)
		(sheetname "PCIe redriver")
		(sheetfile "pcie_redriver.kicad_sch")
		(attr exclude_from_pos_files exclude_from_bom)
		(fp_circle
			(center 0 0)
			(end 0.475 0)
			(stroke
				(width 0.05)
				(type default)
			)
			(fill no)
			(layer "B.CrtYd")
		)
		(pad "1" smd circle
			(at 0 0 180)
			(size 0.75 0.75)
			(layers "B.Cu" "B.Mask")
			(net 713 "Net-(U39-SCL)")
			(pinfunction "1")
			(pintype "passive")
			(teardrops
				(best_length_ratio 0.4)
				(max_length 1)
				(best_width_ratio 0.9)
				(max_width 2)
				(curved_edges yes)
				(filter_ratio 0.9)
				(enabled yes)
				(allow_two_segments yes)
				(prefer_zone_connections yes)
			)
		)
	)
	(footprint "antmicro-footprints:TP_SMD_0.75mm"
		(layer "B.Cu")
		(at 176.25 163.8)
		(property "Reference" "TP24"
			(at -0.25 -2.3 270)
			(layer "B.SilkS")
			(effects
				(font
					(size 0.7 0.7)
					(thickness 0.15)
				)
				(justify right top mirror)
			)
		)
		(property "Value" "TP_0.75mm_SMD"
			(at 3.225 -53.865 0)
			(layer "B.Fab")
			(hide yes)
			(effects
				(font
					(size 0.7 0.7)
					(thickness 0.15)
				)
				(justify right top mirror)
			)
		)
		(property "Author" "Antmicro"
			(at 457.2 308.02 0)
			(layer "B.Fab")
			(hide yes)
			(effects
				(font
					(size 1 1)
					(thickness 0.15)
				)
				(justify mirror)
			)
		)
		(property "License" "Apache-2.0"
			(at 457.2 308.02 0)
			(layer "B.Fab")
			(hide yes)
			(effects
				(font
					(size 1 1)
					(thickness 0.15)
				)
				(justify mirror)
			)
		)
		(property "MPN" ""
			(at 457.2 308.02 0)
			(layer "B.Fab")
			(hide yes)
			(effects
				(font
					(size 1 1)
					(thickness 0.15)
				)
				(justify mirror)
			)
		)
		(property "Manufacturer" ""
			(at 457.2 308.02 0)
			(layer "B.Fab")
			(hide yes)
			(effects
				(font
					(size 1 1)
					(thickness 0.15)
				)
				(justify mirror)
			)
		)
		(property "Public" "False"
			(at 457.2 308.02 0)
			(layer "B.Fab")
			(hide yes)
			(effects
				(font
					(size 1 1)
					(thickness 0.15)
				)
				(justify mirror)
			)
		)
		(sheetname "Com Express 7 MGMT")
		(sheetfile "com_express_7_mgmt.kicad_sch")
		(attr exclude_from_pos_files exclude_from_bom)
		(fp_circle
			(center 0 0)
			(end 0.475 0)
			(stroke
				(width 0.05)
				(type default)
			)
			(fill no)
			(layer "B.CrtYd")
		)
		(pad "1" smd circle
			(at 0 0)
			(size 0.75 0.75)
			(layers "B.Cu" "B.Mask")
			(net 350 "Net-(J12D-LPC_AD1{slash}ESPI_IO_1)")
			(pinfunction "1")
			(pintype "passive")
			(teardrops
				(best_length_ratio 0.4)
				(max_length 1)
				(best_width_ratio 0.9)
				(max_width 2)
				(curved_edges yes)
				(filter_ratio 0.9)
				(enabled yes)
				(allow_two_segments yes)
				(prefer_zone_connections yes)
			)
		)
	)
	(footprint "antmicro-footprints:C_0402_1005Metric"
		(layer "B.Cu")
		(at 196.715146 141.541851 135)
		(descr "Capacitor SMD 0402")
		(tags "capacitor SMD 0402")
		(property "Reference" "C123"
			(at -3.530586 -0.359976 135)
			(layer "B.SilkS")
			(effects
				(font
					(size 0.7 0.7)
					(thickness 0.15)
				)
				(justify right bottom mirror)
			)
		)
		(property "Value" "C_220n_0402"
			(at -1.022927 -2.155213 135)
			(layer "B.Fab")
			(effects
				(font
					(size 0.7 0.7)
					(thickness 0.15)
				)
				(justify right bottom mirror)
			)
		)
		(property "Datasheet" "https://www.yageo.com/en/Chart/Download/pdf/CC0402KRX5R6BB224"
			(at 0 0 135)
			(layer "F.Fab")
			(hide yes)
			(effects
				(font
					(size 1.27 1.27)
					(thickness 0.15)
				)
			)
		)
		(property "Author" "Antmicro"
			(at 339.3 -42.5 45)
			(layer "B.Fab")
			(hide yes)
			(effects
				(font
					(size 1 1)
					(thickness 0.15)
				)
				(justify mirror)
			)
		)
		(property "Dielectric" ""
			(at 339.3 -42.5 45)
			(layer "B.Fab")
			(hide yes)
			(effects
				(font
					(size 1 1)
					(thickness 0.15)
				)
				(justify mirror)
			)
		)
		(property "License" "Apache-2.0"
			(at 339.3 -42.5 45)
			(layer "B.Fab")
			(hide yes)
			(effects
				(font
					(size 1 1)
					(thickness 0.15)
				)
				(justify mirror)
			)
		)
		(property "MPN" "CC0402KRX5R6BB224"
			(at 339.3 -42.5 45)
			(layer "B.Fab")
			(hide yes)
			(effects
				(font
					(size 1 1)
					(thickness 0.15)
				)
				(justify mirror)
			)
		)
		(property "Manufacturer" "YAGEO"
			(at 339.3 -42.5 45)
			(layer "B.Fab")
			(hide yes)
			(effects
				(font
					(size 1 1)
					(thickness 0.15)
				)
				(justify mirror)
			)
		)
		(property "Public" "False"
			(at 339.3 -42.5 45)
			(layer "B.Fab")
			(hide yes)
			(effects
				(font
					(size 1 1)
					(thickness 0.15)
				)
				(justify mirror)
			)
		)
		(property "Val" "220n"
			(at 339.3 -42.5 45)
			(layer "B.Fab")
			(hide yes)
			(effects
				(font
					(size 1 1)
					(thickness 0.15)
				)
				(justify mirror)
			)
		)
		(property "Voltage" ""
			(at 339.3 -42.5 45)
			(layer "B.Fab")
			(hide yes)
			(effects
				(font
					(size 1 1)
					(thickness 0.15)
				)
				(justify mirror)
			)
		)
		(sheetname "PCIe redriver")
		(sheetfile "pcie_redriver.kicad_sch")
		(attr smd)
		(fp_poly
			(pts
				(xy -0.925 0.47) (xy 0.925 0.47) (xy 0.925 -0.47) (xy -0.925 -0.47)
			)
			(stroke
				(width 0.05)
				(type default)
			)
			(fill no)
			(layer "B.CrtYd")
		)
		(fp_line
			(start 0.504 -0.248)
			(end 0.504 0.25)
			(stroke
				(width 0.15)
				(type solid)
			)
			(layer "B.Fab")
		)
		(fp_line
			(start 0.504 0.25)
			(end -0.494 0.25)
			(stroke
				(width 0.15)
				(type solid)
			)
			(layer "B.Fab")
		)
		(fp_line
			(start -0.494 -0.248)
			(end 0.504 -0.248)
			(stroke
				(width 0.15)
				(type solid)
			)
			(layer "B.Fab")
		)
		(fp_line
			(start -0.494 0.25)
			(end -0.494 -0.248)
			(stroke
				(width 0.15)
				(type solid)
			)
			(layer "B.Fab")
		)
		(pad "1" smd roundrect
			(at -0.48 0 135)
			(size 0.59 0.64)
			(layers "B.Cu" "B.Mask" "B.Paste")
			(roundrect_rratio 0.25)
			(net 209 "/Com Express 7 Interfaces/PCIe_{B1x4}.RX3-")
			(pintype "passive")
			(teardrops
				(best_length_ratio 0.2)
				(max_length 1)
				(best_width_ratio 0.9)
				(max_width 2)
				(curved_edges yes)
				(filter_ratio 0.9)
				(enabled yes)
				(allow_two_segments yes)
				(prefer_zone_connections yes)
			)
		)
		(pad "2" smd roundrect
			(at 0.48 0 135)
			(size 0.59 0.64)
			(layers "B.Cu" "B.Mask" "B.Paste")
			(roundrect_rratio 0.25)
			(net 956 "/PCIe redriver/PCIe_{I}_C.RX3-")
			(pintype "passive")
			(teardrops
				(best_length_ratio 0.2)
				(max_length 1)
				(best_width_ratio 0.9)
				(max_width 2)
				(curved_edges yes)
				(filter_ratio 0.9)
				(enabled yes)
				(allow_two_segments yes)
				(prefer_zone_connections yes)
			)
		)
	)
	(footprint "antmicro-footprints:C_0603_1608Metric"
		(layer "B.Cu")
		(at 289.28 79.12 -90)
		(descr "Capacitor SMD 0603")
		(tags "capacitor 0603")
		(property "Reference" "C76"
			(at -3.31 -0.42 90)
			(layer "B.SilkS")
			(effects
				(font
					(size 0.7 0.7)
					(thickness 0.15)
				)
				(justify left bottom mirror)
			)
		)
		(property "Value" "C_22u_16V_0603"
			(at -1.42757 -1.770288 90)
			(layer "B.Fab")
			(effects
				(font
					(size 0.7 0.7)
					(thickness 0.15)
				)
				(justify left bottom mirror)
			)
		)
		(property "Datasheet" "https://product.samsungsem.com/mlcc/CL10A226MO7JZN.do"
			(at 0 0 270)
			(layer "F.Fab")
			(hide yes)
			(effects
				(font
					(size 1.27 1.27)
					(thickness 0.15)
				)
			)
		)
		(property "Author" "Antmicro"
			(at 210.16 368.4 0)
			(layer "B.Fab")
			(hide yes)
			(effects
				(font
					(size 1 1)
					(thickness 0.15)
				)
				(justify mirror)
			)
		)
		(property "Dielectric" ""
			(at 210.16 368.4 0)
			(layer "B.Fab")
			(hide yes)
			(effects
				(font
					(size 1 1)
					(thickness 0.15)
				)
				(justify mirror)
			)
		)
		(property "License" "Apache-2.0"
			(at 210.16 368.4 0)
			(layer "B.Fab")
			(hide yes)
			(effects
				(font
					(size 1 1)
					(thickness 0.15)
				)
				(justify mirror)
			)
		)
		(property "MPN" "CL10A226MO7JZNC"
			(at 210.16 368.4 0)
			(layer "B.Fab")
			(hide yes)
			(effects
				(font
					(size 1 1)
					(thickness 0.15)
				)
				(justify mirror)
			)
		)
		(property "Manufacturer" "Samsung Electro-Mechanics"
			(at 210.16 368.4 0)
			(layer "B.Fab")
			(hide yes)
			(effects
				(font
					(size 1 1)
					(thickness 0.15)
				)
				(justify mirror)
			)
		)
		(property "Public" "False"
			(at 210.16 368.4 0)
			(layer "B.Fab")
			(hide yes)
			(effects
				(font
					(size 1 1)
					(thickness 0.15)
				)
				(justify mirror)
			)
		)
		(property "Val" "22u"
			(at 210.16 368.4 0)
			(layer "B.Fab")
			(hide yes)
			(effects
				(font
					(size 1 1)
					(thickness 0.15)
				)
				(justify mirror)
			)
		)
		(property "Voltage" "16V"
			(at 210.16 368.4 0)
			(layer "B.Fab")
			(hide yes)
			(effects
				(font
					(size 1 1)
					(thickness 0.15)
				)
				(justify mirror)
			)
		)
		(sheetname "M.2 key M #2")
		(sheetfile "m2keym.kicad_sch")
		(attr smd)
		(fp_line
			(start 0.15 0.4)
			(end -0.15 0.4)
			(stroke
				(width 0.15)
				(type solid)
			)
			(layer "B.SilkS")
		)
		(fp_line
			(start 0.15 -0.4)
			(end -0.15 -0.4)
			(stroke
				(width 0.15)
				(type solid)
			)
			(layer "B.SilkS")
		)
		(fp_rect
			(start -1.25 0.65)
			(end 1.25 -0.65)
			(stroke
				(width 0.05)
				(type solid)
			)
			(fill no)
			(layer "B.CrtYd")
		)
		(fp_rect
			(start -0.8 0.4)
			(end 0.8 -0.4)
			(stroke
				(width 0.15)
				(type solid)
			)
			(fill no)
			(layer "B.Fab")
		)
		(pad "1" smd roundrect
			(at -0.7 0 270)
			(size 0.8 1)
			(layers "B.Cu" "B.Mask" "B.Paste")
			(roundrect_rratio 0.2)
			(net 1 "GND")
			(pintype "passive")
			(teardrops
				(best_length_ratio 0.2)
				(max_length 1)
				(best_width_ratio 0.9)
				(max_width 2)
				(curved_edges yes)
				(filter_ratio 0.9)
				(enabled yes)
				(allow_two_segments yes)
				(prefer_zone_connections yes)
			)
		)
		(pad "2" smd roundrect
			(at 0.7 0 270)
			(size 0.8 1)
			(layers "B.Cu" "B.Mask" "B.Paste")
			(roundrect_rratio 0.2)
			(net 970 "/M.2 key M #2/M2_3V3")
			(pintype "passive")
			(teardrops
				(best_length_ratio 0.2)
				(max_length 1)
				(best_width_ratio 0.9)
				(max_width 2)
				(curved_edges yes)
				(filter_ratio 0.9)
				(enabled yes)
				(allow_two_segments yes)
				(prefer_zone_connections yes)
			)
		)
	)
	(footprint "antmicro-footprints:R_0402_1005Metric"
		(layer "B.Cu")
		(at 139.05 169.16 -90)
		(descr "Resistor SMD 0402")
		(tags "resistor SMD 0402")
		(property "Reference" "R50"
			(at -3.9 13.5 90)
			(layer "B.SilkS")
			(effects
				(font
					(size 0.7 0.7)
					(thickness 0.15)
				)
				(justify left bottom mirror)
			)
		)
		(property "Value" "R_1k_0402"
			(at -1.011843 -1.772047 90)
			(layer "B.Fab")
			(effects
				(font
					(size 0.7 0.7)
					(thickness 0.15)
				)
				(justify left bottom mirror)
			)
		)
		(property "Datasheet" "https://www.bourns.com/docs/product-datasheets/cr.pdf"
			(at 0 0 270)
			(layer "F.Fab")
			(hide yes)
			(effects
				(font
					(size 1.27 1.27)
					(thickness 0.15)
				)
			)
		)
		(property "Author" "Antmicro"
			(at -30.11 308.21 0)
			(layer "B.Fab")
			(hide yes)
			(effects
				(font
					(size 1 1)
					(thickness 0.15)
				)
				(justify mirror)
			)
		)
		(property "License" "Apache-2.0"
			(at -30.11 308.21 0)
			(layer "B.Fab")
			(hide yes)
			(effects
				(font
					(size 1 1)
					(thickness 0.15)
				)
				(justify mirror)
			)
		)
		(property "MPN" "CR0402-FX-1001GLF"
			(at -30.11 308.21 0)
			(layer "B.Fab")
			(hide yes)
			(effects
				(font
					(size 1 1)
					(thickness 0.15)
				)
				(justify mirror)
			)
		)
		(property "Manufacturer" "Bourns"
			(at -30.11 308.21 0)
			(layer "B.Fab")
			(hide yes)
			(effects
				(font
					(size 1 1)
					(thickness 0.15)
				)
				(justify mirror)
			)
		)
		(property "Public" "False"
			(at -30.11 308.21 0)
			(layer "B.Fab")
			(hide yes)
			(effects
				(font
					(size 1 1)
					(thickness 0.15)
				)
				(justify mirror)
			)
		)
		(property "Tolerance" "1%"
			(at -30.11 308.21 0)
			(layer "B.Fab")
			(hide yes)
			(effects
				(font
					(size 1 1)
					(thickness 0.15)
				)
				(justify mirror)
			)
		)
		(property "Val" "1k"
			(at -30.11 308.21 0)
			(layer "B.Fab")
			(hide yes)
			(effects
				(font
					(size 1 1)
					(thickness 0.15)
				)
				(justify mirror)
			)
		)
		(sheetname "2xSFP+")
		(sheetfile "2xSFP+.kicad_sch")
		(attr smd)
		(fp_rect
			(start -0.925 0.47)
			(end 0.925 -0.47)
			(stroke
				(width 0.05)
				(type default)
			)
			(fill no)
			(layer "B.CrtYd")
		)
		(fp_rect
			(start -0.5 0.25)
			(end 0.5 -0.25)
			(stroke
				(width 0.15)
				(type solid)
			)
			(fill no)
			(layer "B.Fab")
		)
		(pad "1" smd roundrect
			(at -0.48 0 270)
			(size 0.59 0.64)
			(layers "B.Cu" "B.Mask" "B.Paste")
			(roundrect_rratio 0.25)
			(net 895 "Net-(J2B-RS0)")
			(pintype "passive")
			(teardrops
				(best_length_ratio 0.2)
				(max_length 1)
				(best_width_ratio 0.9)
				(max_width 2)
				(curved_edges yes)
				(filter_ratio 0.9)
				(enabled yes)
				(allow_two_segments yes)
				(prefer_zone_connections yes)
			)
		)
		(pad "2" smd roundrect
			(at 0.48 0 270)
			(size 0.59 0.64)
			(layers "B.Cu" "B.Mask" "B.Paste")
			(roundrect_rratio 0.25)
			(net 2 "+3V3")
			(pintype "passive")
			(teardrops
				(best_length_ratio 0.2)
				(max_length 1)
				(best_width_ratio 0.9)
				(max_width 2)
				(curved_edges yes)
				(filter_ratio 0.9)
				(enabled yes)
				(allow_two_segments yes)
				(prefer_zone_connections yes)
			)
		)
	)
	(footprint "antmicro-footprints:C_0402_1005Metric"
		(layer "B.Cu")
		(at 151.95 134.86 180)
		(descr "Capacitor SMD 0402")
		(tags "capacitor SMD 0402")
		(property "Reference" "C157"
			(at -3.7 -0.45 0)
			(layer "B.SilkS")
			(effects
				(font
					(size 0.7 0.7)
					(thickness 0.15)
				)
				(justify left bottom mirror)
			)
		)
		(property "Value" "C_100n_0402"
			(at -1.022927 -2.155213 0)
			(layer "B.Fab")
			(effects
				(font
					(size 0.7 0.7)
					(thickness 0.15)
				)
				(justify left bottom mirror)
			)
		)
		(property "Datasheet" "https://www.murata.com/products/productdetail?partno=GRM155R61H104KE14%23"
			(at 0 0 180)
			(layer "F.Fab")
			(hide yes)
			(effects
				(font
					(size 1.27 1.27)
					(thickness 0.15)
				)
			)
		)
		(property "Author" "Antmicro"
			(at 303.9 269.72 0)
			(layer "B.Fab")
			(hide yes)
			(effects
				(font
					(size 1 1)
					(thickness 0.15)
				)
				(justify mirror)
			)
		)
		(property "Dielectric" "X5R"
			(at 303.9 269.72 0)
			(layer "B.Fab")
			(hide yes)
			(effects
				(font
					(size 1 1)
					(thickness 0.15)
				)
				(justify mirror)
			)
		)
		(property "License" "Apache-2.0"
			(at 303.9 269.72 0)
			(layer "B.Fab")
			(hide yes)
			(effects
				(font
					(size 1 1)
					(thickness 0.15)
				)
				(justify mirror)
			)
		)
		(property "MPN" "GRM155R61H104KE14D"
			(at 303.9 269.72 0)
			(layer "B.Fab")
			(hide yes)
			(effects
				(font
					(size 1 1)
					(thickness 0.15)
				)
				(justify mirror)
			)
		)
		(property "Manufacturer" "Murata"
			(at 303.9 269.72 0)
			(layer "B.Fab")
			(hide yes)
			(effects
				(font
					(size 1 1)
					(thickness 0.15)
				)
				(justify mirror)
			)
		)
		(property "Public" "False"
			(at 303.9 269.72 0)
			(layer "B.Fab")
			(hide yes)
			(effects
				(font
					(size 1 1)
					(thickness 0.15)
				)
				(justify mirror)
			)
		)
		(property "Val" "100n"
			(at 303.9 269.72 0)
			(layer "B.Fab")
			(hide yes)
			(effects
				(font
					(size 1 1)
					(thickness 0.15)
				)
				(justify mirror)
			)
		)
		(property "Voltage" "50V"
			(at 303.9 269.72 0)
			(layer "B.Fab")
			(hide yes)
			(effects
				(font
					(size 1 1)
					(thickness 0.15)
				)
				(justify mirror)
			)
		)
		(sheetname "KR to SFI #1")
		(sheetfile "kr_sfi.kicad_sch")
		(attr smd)
		(fp_rect
			(start -0.925 0.47)
			(end 0.925 -0.47)
			(stroke
				(width 0.05)
				(type default)
			)
			(fill no)
			(layer "B.CrtYd")
		)
		(fp_line
			(start 0.504 0.25)
			(end -0.494 0.25)
			(stroke
				(width 0.15)
				(type solid)
			)
			(layer "B.Fab")
		)
		(fp_line
			(start 0.504 -0.248)
			(end 0.504 0.25)
			(stroke
				(width 0.15)
				(type solid)
			)
			(layer "B.Fab")
		)
		(fp_line
			(start -0.494 0.25)
			(end -0.494 -0.248)
			(stroke
				(width 0.15)
				(type solid)
			)
			(layer "B.Fab")
		)
		(fp_line
			(start -0.494 -0.248)
			(end 0.504 -0.248)
			(stroke
				(width 0.15)
				(type solid)
			)
			(layer "B.Fab")
		)
		(pad "1" smd roundrect
			(at -0.48 0 180)
			(size 0.59 0.64)
			(layers "B.Cu" "B.Mask" "B.Paste")
			(roundrect_rratio 0.25)
			(net 1 "GND")
			(pintype "passive")
			(teardrops
				(best_length_ratio 0.2)
				(max_length 1)
				(best_width_ratio 0.9)
				(max_width 2)
				(curved_edges yes)
				(filter_ratio 0.9)
				(enabled yes)
				(allow_two_segments yes)
				(prefer_zone_connections yes)
			)
		)
		(pad "2" smd roundrect
			(at 0.48 0 180)
			(size 0.59 0.64)
			(layers "B.Cu" "B.Mask" "B.Paste")
			(roundrect_rratio 0.25)
			(net 74 "+1V0")
			(pintype "passive")
			(teardrops
				(best_length_ratio 0.2)
				(max_length 1)
				(best_width_ratio 0.9)
				(max_width 2)
				(curved_edges yes)
				(filter_ratio 0.9)
				(enabled yes)
				(allow_two_segments yes)
				(prefer_zone_connections yes)
			)
		)
	)
	(footprint "antmicro-footprints:R_0402_1005Metric"
		(layer "B.Cu")
		(at 219.5 165.7 -90)
		(descr "Resistor SMD 0402")
		(tags "resistor SMD 0402")
		(property "Reference" "R160"
			(at -1.3 0.77 90)
			(layer "B.SilkS")
			(effects
				(font
					(size 0.7 0.7)
					(thickness 0.15)
				)
				(justify left bottom mirror)
			)
		)
		(property "Value" "R_1k_0402"
			(at 2.213157 -54.437047 90)
			(layer "B.Fab")
			(hide yes)
			(effects
				(font
					(size 0.7 0.7)
					(thickness 0.15)
				)
				(justify left bottom mirror)
			)
		)
		(property "Datasheet" "https://www.bourns.com/docs/product-datasheets/cr.pdf"
			(at 0 0 90)
			(layer "F.Fab")
			(hide yes)
			(effects
				(font
					(size 1.27 1.27)
					(thickness 0.15)
				)
			)
		)
		(property "Author" "Antmicro"
			(at 372.9 314.82 90)
			(layer "B.Fab")
			(hide yes)
			(effects
				(font
					(size 1 1)
					(thickness 0.15)
				)
				(justify mirror)
			)
		)
		(property "License" "Apache-2.0"
			(at 372.9 314.82 90)
			(layer "B.Fab")
			(hide yes)
			(effects
				(font
					(size 1 1)
					(thickness 0.15)
				)
				(justify mirror)
			)
		)
		(property "MPN" "CR0402-FX-1001GLF"
			(at 372.9 314.82 90)
			(layer "B.Fab")
			(hide yes)
			(effects
				(font
					(size 1 1)
					(thickness 0.15)
				)
				(justify mirror)
			)
		)
		(property "Manufacturer" "Bourns"
			(at 372.9 314.82 90)
			(layer "B.Fab")
			(hide yes)
			(effects
				(font
					(size 1 1)
					(thickness 0.15)
				)
				(justify mirror)
			)
		)
		(property "Public" "False"
			(at 372.9 314.82 90)
			(layer "B.Fab")
			(hide yes)
			(effects
				(font
					(size 1 1)
					(thickness 0.15)
				)
				(justify mirror)
			)
		)
		(property "Tolerance" "1%"
			(at 372.9 314.82 90)
			(layer "B.Fab")
			(hide yes)
			(effects
				(font
					(size 1 1)
					(thickness 0.15)
				)
				(justify mirror)
			)
		)
		(property "Val" "1k"
			(at 372.9 314.82 90)
			(layer "B.Fab")
			(hide yes)
			(effects
				(font
					(size 1 1)
					(thickness 0.15)
				)
				(justify mirror)
			)
		)
		(sheetname "Com Express 7 MGMT")
		(sheetfile "com_express_7_mgmt.kicad_sch")
		(attr smd)
		(fp_rect
			(start -0.925 0.47)
			(end 0.925 -0.47)
			(stroke
				(width 0.05)
				(type default)
			)
			(fill no)
			(layer "B.CrtYd")
		)
		(fp_rect
			(start -0.5 0.25)
			(end 0.5 -0.25)
			(stroke
				(width 0.15)
				(type solid)
			)
			(fill no)
			(layer "B.Fab")
		)
		(pad "1" smd roundrect
			(at -0.48 0 270)
			(size 0.59 0.64)
			(layers "B.Cu" "B.Mask" "B.Paste")
			(roundrect_rratio 0.25)
			(net 389 "Net-(J12D-~{BIOS_DIS1})")
			(pintype "passive")
			(teardrops
				(best_length_ratio 0.2)
				(max_length 1)
				(best_width_ratio 0.9)
				(max_width 2)
				(curved_edges yes)
				(filter_ratio 0.9)
				(enabled yes)
				(allow_two_segments yes)
				(prefer_zone_connections yes)
			)
		)
		(pad "2" smd roundrect
			(at 0.48 0 270)
			(size 0.59 0.64)
			(layers "B.Cu" "B.Mask" "B.Paste")
			(roundrect_rratio 0.25)
			(net 1 "GND")
			(pintype "passive")
			(teardrops
				(best_length_ratio 0.2)
				(max_length 1)
				(best_width_ratio 0.9)
				(max_width 2)
				(curved_edges yes)
				(filter_ratio 0.9)
				(enabled yes)
				(allow_two_segments yes)
				(prefer_zone_connections yes)
			)
		)
	)
	(footprint "antmicro-footprints:TP_SMD_0.75mm"
		(layer "B.Cu")
		(at 194.35 151.2 -45)
		(property "Reference" "TP19"
			(at -0.388909 -0.742462 45)
			(layer "B.SilkS")
			(effects
				(font
					(size 0.7 0.7)
					(thickness 0.15)
				)
				(justify right top mirror)
			)
		)
		(property "Value" "TP_0.75mm_SMD"
			(at 3.225 -53.865 135)
			(layer "B.Fab")
			(hide yes)
			(effects
				(font
					(size 0.7 0.7)
					(thickness 0.15)
				)
				(justify left bottom mirror)
			)
		)
		(property "Author" "Antmicro"
			(at 428.6 339.52 135)
			(layer "B.Fab")
			(hide yes)
			(effects
				(font
					(size 1 1)
					(thickness 0.15)
				)
				(justify mirror)
			)
		)
		(property "License" "Apache-2.0"
			(at 428.6 339.52 135)
			(layer "B.Fab")
			(hide yes)
			(effects
				(font
					(size 1 1)
					(thickness 0.15)
				)
				(justify mirror)
			)
		)
		(property "MPN" ""
			(at 428.6 339.52 135)
			(layer "B.Fab")
			(hide yes)
			(effects
				(font
					(size 1 1)
					(thickness 0.15)
				)
				(justify mirror)
			)
		)
		(property "Manufacturer" ""
			(at 428.6 339.52 135)
			(layer "B.Fab")
			(hide yes)
			(effects
				(font
					(size 1 1)
					(thickness 0.15)
				)
				(justify mirror)
			)
		)
		(property "Public" "False"
			(at 428.6 339.52 135)
			(layer "B.Fab")
			(hide yes)
			(effects
				(font
					(size 1 1)
					(thickness 0.15)
				)
				(justify mirror)
			)
		)
		(sheetname "Com Express 7 Interfaces")
		(sheetfile "com_express_7_interfaces.kicad_sch")
		(attr exclude_from_pos_files exclude_from_bom)
		(fp_circle
			(center 0 0)
			(end 0.475 0)
			(stroke
				(width 0.05)
				(type default)
			)
			(fill no)
			(layer "B.CrtYd")
		)
		(pad "1" smd circle
			(at 0 0 315)
			(size 0.75 0.75)
			(layers "B.Cu" "B.Mask")
			(net 489 "Net-(J12K-10G_SDP1)")
			(pinfunction "1")
			(pintype "passive")
			(teardrops
				(best_length_ratio 0.4)
				(max_length 1)
				(best_width_ratio 0.9)
				(max_width 2)
				(curved_edges yes)
				(filter_ratio 0.9)
				(enabled yes)
				(allow_two_segments yes)
				(prefer_zone_connections yes)
			)
		)
	)
	(footprint "antmicro-footprints:C_0402_1005Metric"
		(layer "B.Cu")
		(at 116.9 85.910001)
		(descr "Capacitor SMD 0402")
		(tags "capacitor SMD 0402")
		(property "Reference" "C17"
			(at -1.05 -0.500001 0)
			(layer "B.SilkS")
			(effects
				(font
					(size 0.7 0.7)
					(thickness 0.15)
				)
				(justify right bottom mirror)
			)
		)
		(property "Value" "C_100n_0402"
			(at -1.022927 -2.155213 0)
			(layer "B.Fab")
			(effects
				(font
					(size 0.7 0.7)
					(thickness 0.15)
				)
				(justify right bottom mirror)
			)
		)
		(property "Datasheet" "https://www.murata.com/products/productdetail?partno=GRM155R61H104KE14%23"
			(at 0 0 0)
			(layer "F.Fab")
			(hide yes)
			(effects
				(font
					(size 1.27 1.27)
					(thickness 0.15)
				)
			)
		)
		(property "Author" "Antmicro"
			(at 0 0 0)
			(layer "B.Fab")
			(hide yes)
			(effects
				(font
					(size 1 1)
					(thickness 0.15)
				)
				(justify mirror)
			)
		)
		(property "Dielectric" "X5R"
			(at 0 0 0)
			(layer "B.Fab")
			(hide yes)
			(effects
				(font
					(size 1 1)
					(thickness 0.15)
				)
				(justify mirror)
			)
		)
		(property "License" "Apache-2.0"
			(at 0 0 0)
			(layer "B.Fab")
			(hide yes)
			(effects
				(font
					(size 1 1)
					(thickness 0.15)
				)
				(justify mirror)
			)
		)
		(property "MPN" "GRM155R61H104KE14D"
			(at 0 0 0)
			(layer "B.Fab")
			(hide yes)
			(effects
				(font
					(size 1 1)
					(thickness 0.15)
				)
				(justify mirror)
			)
		)
		(property "Manufacturer" "Murata"
			(at 0 0 0)
			(layer "B.Fab")
			(hide yes)
			(effects
				(font
					(size 1 1)
					(thickness 0.15)
				)
				(justify mirror)
			)
		)
		(property "Public" "False"
			(at 0 0 0)
			(layer "B.Fab")
			(hide yes)
			(effects
				(font
					(size 1 1)
					(thickness 0.15)
				)
				(justify mirror)
			)
		)
		(property "Val" "100n"
			(at 0 0 0)
			(layer "B.Fab")
			(hide yes)
			(effects
				(font
					(size 1 1)
					(thickness 0.15)
				)
				(justify mirror)
			)
		)
		(property "Voltage" "50V"
			(at 0 0 0)
			(layer "B.Fab")
			(hide yes)
			(effects
				(font
					(size 1 1)
					(thickness 0.15)
				)
				(justify mirror)
			)
		)
		(sheetname "2xUSB3.0+RJ45")
		(sheetfile "usb3+rj45.kicad_sch")
		(attr smd)
		(fp_rect
			(start -0.925 0.47)
			(end 0.925 -0.47)
			(stroke
				(width 0.05)
				(type default)
			)
			(fill no)
			(layer "B.CrtYd")
		)
		(fp_line
			(start -0.494 -0.248)
			(end 0.504 -0.248)
			(stroke
				(width 0.15)
				(type solid)
			)
			(layer "B.Fab")
		)
		(fp_line
			(start -0.494 0.25)
			(end -0.494 -0.248)
			(stroke
				(width 0.15)
				(type solid)
			)
			(layer "B.Fab")
		)
		(fp_line
			(start 0.504 -0.248)
			(end 0.504 0.25)
			(stroke
				(width 0.15)
				(type solid)
			)
			(layer "B.Fab")
		)
		(fp_line
			(start 0.504 0.25)
			(end -0.494 0.25)
			(stroke
				(width 0.15)
				(type solid)
			)
			(layer "B.Fab")
		)
		(pad "1" smd roundrect
			(at -0.48 0)
			(size 0.59 0.64)
			(layers "B.Cu" "B.Mask" "B.Paste")
			(roundrect_rratio 0.25)
			(net 1 "GND")
			(pintype "passive")
			(teardrops
				(best_length_ratio 0.2)
				(max_length 1)
				(best_width_ratio 0.9)
				(max_width 2)
				(curved_edges yes)
				(filter_ratio 0.9)
				(enabled yes)
				(allow_two_segments yes)
				(prefer_zone_connections yes)
			)
		)
		(pad "2" smd roundrect
			(at 0.48 0)
			(size 0.59 0.64)
			(layers "B.Cu" "B.Mask" "B.Paste")
			(roundrect_rratio 0.25)
			(net 52 "+5V")
			(pintype "passive")
			(teardrops
				(best_length_ratio 0.2)
				(max_length 1)
				(best_width_ratio 0.9)
				(max_width 2)
				(curved_edges yes)
				(filter_ratio 0.9)
				(enabled yes)
				(allow_two_segments yes)
				(prefer_zone_connections yes)
			)
		)
	)
	(footprint "antmicro-footprints:C_0402_1005Metric"
		(layer "B.Cu")
		(at 115.314999 77.724999 180)
		(descr "Capacitor SMD 0402")
		(tags "capacitor SMD 0402")
		(property "Reference" "C33"
			(at 0.814999 -0.435001 0)
			(layer "B.SilkS")
			(effects
				(font
					(size 0.7 0.7)
					(thickness 0.15)
				)
				(justify left bottom mirror)
			)
		)
		(property "Value" "C_1u_0402"
			(at -1.022927 -2.155213 0)
			(layer "B.Fab")
			(effects
				(font
					(size 0.7 0.7)
					(thickness 0.15)
				)
				(justify left bottom mirror)
			)
		)
		(property "Datasheet" "https://product.tdk.com/en/search/capacitor/ceramic/mlcc/info?part_no=C1005X6S1A105K050BC"
			(at 0 0 180)
			(layer "F.Fab")
			(hide yes)
			(effects
				(font
					(size 1.27 1.27)
					(thickness 0.15)
				)
			)
		)
		(property "Author" "Antmicro"
			(at 230.629998 155.449998 0)
			(layer "B.Fab")
			(hide yes)
			(effects
				(font
					(size 1 1)
					(thickness 0.15)
				)
				(justify mirror)
			)
		)
		(property "Dielectric" ""
			(at 230.629998 155.449998 0)
			(layer "B.Fab")
			(hide yes)
			(effects
				(font
					(size 1 1)
					(thickness 0.15)
				)
				(justify mirror)
			)
		)
		(property "License" "Apache-2.0"
			(at 230.629998 155.449998 0)
			(layer "B.Fab")
			(hide yes)
			(effects
				(font
					(size 1 1)
					(thickness 0.15)
				)
				(justify mirror)
			)
		)
		(property "MPN" "C1005X6S1A105K050BC"
			(at 230.629998 155.449998 0)
			(layer "B.Fab")
			(hide yes)
			(effects
				(font
					(size 1 1)
					(thickness 0.15)
				)
				(justify mirror)
			)
		)
		(property "Manufacturer" "TDK"
			(at 230.629998 155.449998 0)
			(layer "B.Fab")
			(hide yes)
			(effects
				(font
					(size 1 1)
					(thickness 0.15)
				)
				(justify mirror)
			)
		)
		(property "Public" "False"
			(at 230.629998 155.449998 0)
			(layer "B.Fab")
			(hide yes)
			(effects
				(font
					(size 1 1)
					(thickness 0.15)
				)
				(justify mirror)
			)
		)
		(property "Val" "1u"
			(at 230.629998 155.449998 0)
			(layer "B.Fab")
			(hide yes)
			(effects
				(font
					(size 1 1)
					(thickness 0.15)
				)
				(justify mirror)
			)
		)
		(property "Voltage" ""
			(at 230.629998 155.449998 0)
			(layer "B.Fab")
			(hide yes)
			(effects
				(font
					(size 1 1)
					(thickness 0.15)
				)
				(justify mirror)
			)
		)
		(sheetname "USB-C console")
		(sheetfile "usb-c_console.kicad_sch")
		(attr smd)
		(fp_rect
			(start -0.925 0.47)
			(end 0.925 -0.47)
			(stroke
				(width 0.05)
				(type default)
			)
			(fill no)
			(layer "B.CrtYd")
		)
		(fp_line
			(start 0.504 0.25)
			(end -0.494 0.25)
			(stroke
				(width 0.15)
				(type solid)
			)
			(layer "B.Fab")
		)
		(fp_line
			(start 0.504 -0.248)
			(end 0.504 0.25)
			(stroke
				(width 0.15)
				(type solid)
			)
			(layer "B.Fab")
		)
		(fp_line
			(start -0.494 0.25)
			(end -0.494 -0.248)
			(stroke
				(width 0.15)
				(type solid)
			)
			(layer "B.Fab")
		)
		(fp_line
			(start -0.494 -0.248)
			(end 0.504 -0.248)
			(stroke
				(width 0.15)
				(type solid)
			)
			(layer "B.Fab")
		)
		(pad "1" smd roundrect
			(at -0.48 0 180)
			(size 0.59 0.64)
			(layers "B.Cu" "B.Mask" "B.Paste")
			(roundrect_rratio 0.25)
			(net 1 "GND")
			(pintype "passive")
			(teardrops
				(best_length_ratio 0.2)
				(max_length 1)
				(best_width_ratio 0.9)
				(max_width 2)
				(curved_edges yes)
				(filter_ratio 0.9)
				(enabled yes)
				(allow_two_segments yes)
				(prefer_zone_connections yes)
			)
		)
		(pad "2" smd roundrect
			(at 0.48 0 180)
			(size 0.59 0.64)
			(layers "B.Cu" "B.Mask" "B.Paste")
			(roundrect_rratio 0.25)
			(net 58 "/USB-C console/VBUS_FTDI")
			(pintype "passive")
			(teardrops
				(best_length_ratio 0.2)
				(max_length 1)
				(best_width_ratio 0.9)
				(max_width 2)
				(curved_edges yes)
				(filter_ratio 0.9)
				(enabled yes)
				(allow_two_segments yes)
				(prefer_zone_connections yes)
			)
		)
	)
	(footprint "antmicro-footprints:R_0402_1005Metric"
		(layer "B.Cu")
		(at 193 165.9 -90)
		(descr "Resistor SMD 0402")
		(tags "resistor SMD 0402")
		(property "Reference" "R162"
			(at 1.1 -0.4 90)
			(layer "B.SilkS")
			(effects
				(font
					(size 0.7 0.7)
					(thickness 0.15)
				)
				(justify left bottom mirror)
			)
		)
		(property "Value" "R_10k_0402"
			(at 2.213157 -54.437047 90)
			(layer "B.Fab")
			(hide yes)
			(effects
				(font
					(size 0.7 0.7)
					(thickness 0.15)
				)
				(justify left bottom mirror)
			)
		)
		(property "Datasheet" "https://www.bourns.com/docs/product-datasheets/cr.pdf"
			(at 0 0 90)
			(layer "F.Fab")
			(hide yes)
			(effects
				(font
					(size 1.27 1.27)
					(thickness 0.15)
				)
			)
		)
		(property "Author" "Antmicro"
			(at 426 315.67 90)
			(layer "B.Fab")
			(hide yes)
			(effects
				(font
					(size 1 1)
					(thickness 0.15)
				)
				(justify mirror)
			)
		)
		(property "License" "Apache-2.0"
			(at 426 315.67 90)
			(layer "B.Fab")
			(hide yes)
			(effects
				(font
					(size 1 1)
					(thickness 0.15)
				)
				(justify mirror)
			)
		)
		(property "MPN" "CR0402-FX-1002GLF"
			(at 426 315.67 90)
			(layer "B.Fab")
			(hide yes)
			(effects
				(font
					(size 1 1)
					(thickness 0.15)
				)
				(justify mirror)
			)
		)
		(property "Manufacturer" "Bourns"
			(at 426 315.67 90)
			(layer "B.Fab")
			(hide yes)
			(effects
				(font
					(size 1 1)
					(thickness 0.15)
				)
				(justify mirror)
			)
		)
		(property "Public" "False"
			(at 426 315.67 90)
			(layer "B.Fab")
			(hide yes)
			(effects
				(font
					(size 1 1)
					(thickness 0.15)
				)
				(justify mirror)
			)
		)
		(property "Tolerance" "1%"
			(at 426 315.67 90)
			(layer "B.Fab")
			(hide yes)
			(effects
				(font
					(size 1 1)
					(thickness 0.15)
				)
				(justify mirror)
			)
		)
		(property "Val" "10k"
			(at 426 315.67 90)
			(layer "B.Fab")
			(hide yes)
			(effects
				(font
					(size 1 1)
					(thickness 0.15)
				)
				(justify mirror)
			)
		)
		(sheetname "Com Express 7 MGMT")
		(sheetfile "com_express_7_mgmt.kicad_sch")
		(attr smd)
		(fp_rect
			(start -0.925 0.47)
			(end 0.925 -0.47)
			(stroke
				(width 0.05)
				(type default)
			)
			(fill no)
			(layer "B.CrtYd")
		)
		(fp_rect
			(start -0.5 0.25)
			(end 0.5 -0.25)
			(stroke
				(width 0.15)
				(type solid)
			)
			(fill no)
			(layer "B.Fab")
		)
		(pad "1" smd roundrect
			(at -0.48 0 270)
			(size 0.59 0.64)
			(layers "B.Cu" "B.Mask" "B.Paste")
			(roundrect_rratio 0.25)
			(net 373 "Net-(J12D-~{THRM})")
			(pintype "passive")
			(teardrops
				(best_length_ratio 0.2)
				(max_length 1)
				(best_width_ratio 0.9)
				(max_width 2)
				(curved_edges yes)
				(filter_ratio 0.9)
				(enabled yes)
				(allow_two_segments yes)
				(prefer_zone_connections yes)
			)
		)
		(pad "2" smd roundrect
			(at 0.48 0 270)
			(size 0.59 0.64)
			(layers "B.Cu" "B.Mask" "B.Paste")
			(roundrect_rratio 0.25)
			(net 2 "+3V3")
			(pintype "passive")
			(teardrops
				(best_length_ratio 0.2)
				(max_length 1)
				(best_width_ratio 0.9)
				(max_width 2)
				(curved_edges yes)
				(filter_ratio 0.9)
				(enabled yes)
				(allow_two_segments yes)
				(prefer_zone_connections yes)
			)
		)
	)
	(footprint "antmicro-footprints:C_0402_1005Metric"
		(layer "B.Cu")
		(at 195.711055 139.844794 135)
		(descr "Capacitor SMD 0402")
		(tags "capacitor SMD 0402")
		(property "Reference" "C130"
			(at -2.768935 0.013654 135)
			(layer "B.SilkS")
			(effects
				(font
					(size 0.7 0.7)
					(thickness 0.15)
				)
				(justify right bottom mirror)
			)
		)
		(property "Value" "C_220n_0402"
			(at -1.022927 -2.155213 135)
			(layer "B.Fab")
			(effects
				(font
					(size 0.7 0.7)
					(thickness 0.15)
				)
				(justify right bottom mirror)
			)
		)
		(property "Datasheet" "https://www.yageo.com/en/Chart/Download/pdf/CC0402KRX5R6BB224"
			(at 0 0 135)
			(layer "F.Fab")
			(hide yes)
			(effects
				(font
					(size 1.27 1.27)
					(thickness 0.15)
				)
			)
		)
		(property "Author" "Antmicro"
			(at 340.72 -40.099999 45)
			(layer "B.Fab")
			(hide yes)
			(effects
				(font
					(size 1 1)
					(thickness 0.15)
				)
				(justify mirror)
			)
		)
		(property "Dielectric" ""
			(at 340.72 -40.099999 45)
			(layer "B.Fab")
			(hide yes)
			(effects
				(font
					(size 1 1)
					(thickness 0.15)
				)
				(justify mirror)
			)
		)
		(property "License" "Apache-2.0"
			(at 340.72 -40.099999 45)
			(layer "B.Fab")
			(hide yes)
			(effects
				(font
					(size 1 1)
					(thickness 0.15)
				)
				(justify mirror)
			)
		)
		(property "MPN" "CC0402KRX5R6BB224"
			(at 340.72 -40.099999 45)
			(layer "B.Fab")
			(hide yes)
			(effects
				(font
					(size 1 1)
					(thickness 0.15)
				)
				(justify mirror)
			)
		)
		(property "Manufacturer" "YAGEO"
			(at 340.72 -40.099999 45)
			(layer "B.Fab")
			(hide yes)
			(effects
				(font
					(size 1 1)
					(thickness 0.15)
				)
				(justify mirror)
			)
		)
		(property "Public" "False"
			(at 340.72 -40.099999 45)
			(layer "B.Fab")
			(hide yes)
			(effects
				(font
					(size 1 1)
					(thickness 0.15)
				)
				(justify mirror)
			)
		)
		(property "Val" "220n"
			(at 340.72 -40.099999 45)
			(layer "B.Fab")
			(hide yes)
			(effects
				(font
					(size 1 1)
					(thickness 0.15)
				)
				(justify mirror)
			)
		)
		(property "Voltage" ""
			(at 340.72 -40.099999 45)
			(layer "B.Fab")
			(hide yes)
			(effects
				(font
					(size 1 1)
					(thickness 0.15)
				)
				(justify mirror)
			)
		)
		(sheetname "PCIe redriver")
		(sheetfile "pcie_redriver.kicad_sch")
		(attr smd)
		(fp_poly
			(pts
				(xy -0.925 0.47) (xy 0.925 0.47) (xy 0.925 -0.47) (xy -0.925 -0.47)
			)
			(stroke
				(width 0.05)
				(type default)
			)
			(fill no)
			(layer "B.CrtYd")
		)
		(fp_line
			(start 0.504 -0.248)
			(end 0.504 0.25)
			(stroke
				(width 0.15)
				(type solid)
			)
			(layer "B.Fab")
		)
		(fp_line
			(start 0.504 0.25)
			(end -0.494 0.25)
			(stroke
				(width 0.15)
				(type solid)
			)
			(layer "B.Fab")
		)
		(fp_line
			(start -0.494 -0.248)
			(end 0.504 -0.248)
			(stroke
				(width 0.15)
				(type solid)
			)
			(layer "B.Fab")
		)
		(fp_line
			(start -0.494 0.25)
			(end -0.494 -0.248)
			(stroke
				(width 0.15)
				(type solid)
			)
			(layer "B.Fab")
		)
		(pad "1" smd roundrect
			(at -0.48 0 135)
			(size 0.59 0.64)
			(layers "B.Cu" "B.Mask" "B.Paste")
			(roundrect_rratio 0.25)
			(net 214 "/Com Express 7 Interfaces/PCIe_{B1x4}.RX2+")
			(pintype "passive")
			(teardrops
				(best_length_ratio 0.2)
				(max_length 1)
				(best_width_ratio 0.9)
				(max_width 2)
				(curved_edges yes)
				(filter_ratio 0.9)
				(enabled yes)
				(allow_two_segments yes)
				(prefer_zone_connections yes)
			)
		)
		(pad "2" smd roundrect
			(at 0.48 0 135)
			(size 0.59 0.64)
			(layers "B.Cu" "B.Mask" "B.Paste")
			(roundrect_rratio 0.25)
			(net 959 "/PCIe redriver/PCIe_{I}_C.RX2+")
			(pintype "passive")
			(teardrops
				(best_length_ratio 0.2)
				(max_length 1)
				(best_width_ratio 0.9)
				(max_width 2)
				(curved_edges yes)
				(filter_ratio 0.9)
				(enabled yes)
				(allow_two_segments yes)
				(prefer_zone_connections yes)
			)
		)
	)
	(footprint "antmicro-footprints:C_0402_1005Metric"
		(layer "B.Cu")
		(at 123.74 138.01)
		(descr "Capacitor SMD 0402")
		(tags "capacitor SMD 0402")
		(property "Reference" "C175"
			(at -3.64 0.35 0)
			(layer "B.SilkS")
			(effects
				(font
					(size 0.7 0.7)
					(thickness 0.15)
				)
				(justify right bottom mirror)
			)
		)
		(property "Value" "C_100n_0402"
			(at -1.022927 -2.155213 0)
			(layer "B.Fab")
			(effects
				(font
					(size 0.7 0.7)
					(thickness 0.15)
				)
				(justify right bottom mirror)
			)
		)
		(property "Datasheet" "https://www.murata.com/products/productdetail?partno=GRM155R61H104KE14%23"
			(at 0 0 0)
			(layer "F.Fab")
			(hide yes)
			(effects
				(font
					(size 1.27 1.27)
					(thickness 0.15)
				)
			)
		)
		(property "Author" "Antmicro"
			(at 0 0 0)
			(layer "B.Fab")
			(hide yes)
			(effects
				(font
					(size 1 1)
					(thickness 0.15)
				)
				(justify mirror)
			)
		)
		(property "Dielectric" "X5R"
			(at 0 0 0)
			(layer "B.Fab")
			(hide yes)
			(effects
				(font
					(size 1 1)
					(thickness 0.15)
				)
				(justify mirror)
			)
		)
		(property "License" "Apache-2.0"
			(at 0 0 0)
			(layer "B.Fab")
			(hide yes)
			(effects
				(font
					(size 1 1)
					(thickness 0.15)
				)
				(justify mirror)
			)
		)
		(property "MPN" "GRM155R61H104KE14D"
			(at 0 0 0)
			(layer "B.Fab")
			(hide yes)
			(effects
				(font
					(size 1 1)
					(thickness 0.15)
				)
				(justify mirror)
			)
		)
		(property "Manufacturer" "Murata"
			(at 0 0 0)
			(layer "B.Fab")
			(hide yes)
			(effects
				(font
					(size 1 1)
					(thickness 0.15)
				)
				(justify mirror)
			)
		)
		(property "Public" "False"
			(at 0 0 0)
			(layer "B.Fab")
			(hide yes)
			(effects
				(font
					(size 1 1)
					(thickness 0.15)
				)
				(justify mirror)
			)
		)
		(property "Val" "100n"
			(at 0 0 0)
			(layer "B.Fab")
			(hide yes)
			(effects
				(font
					(size 1 1)
					(thickness 0.15)
				)
				(justify mirror)
			)
		)
		(property "Voltage" "50V"
			(at 0 0 0)
			(layer "B.Fab")
			(hide yes)
			(effects
				(font
					(size 1 1)
					(thickness 0.15)
				)
				(justify mirror)
			)
		)
		(sheetname "KR to SFI #2")
		(sheetfile "kr_sfi.kicad_sch")
		(attr smd)
		(fp_rect
			(start -0.925 0.47)
			(end 0.925 -0.47)
			(stroke
				(width 0.05)
				(type default)
			)
			(fill no)
			(layer "B.CrtYd")
		)
		(fp_line
			(start -0.494 -0.248)
			(end 0.504 -0.248)
			(stroke
				(width 0.15)
				(type solid)
			)
			(layer "B.Fab")
		)
		(fp_line
			(start -0.494 0.25)
			(end -0.494 -0.248)
			(stroke
				(width 0.15)
				(type solid)
			)
			(layer "B.Fab")
		)
		(fp_line
			(start 0.504 -0.248)
			(end 0.504 0.25)
			(stroke
				(width 0.15)
				(type solid)
			)
			(layer "B.Fab")
		)
		(fp_line
			(start 0.504 0.25)
			(end -0.494 0.25)
			(stroke
				(width 0.15)
				(type solid)
			)
			(layer "B.Fab")
		)
		(pad "1" smd roundrect
			(at -0.48 0)
			(size 0.59 0.64)
			(layers "B.Cu" "B.Mask" "B.Paste")
			(roundrect_rratio 0.25)
			(net 1 "GND")
			(pintype "passive")
			(teardrops
				(best_length_ratio 0.2)
				(max_length 1)
				(best_width_ratio 0.9)
				(max_width 2)
				(curved_edges yes)
				(filter_ratio 0.9)
				(enabled yes)
				(allow_two_segments yes)
				(prefer_zone_connections yes)
			)
		)
		(pad "2" smd roundrect
			(at 0.48 0)
			(size 0.59 0.64)
			(layers "B.Cu" "B.Mask" "B.Paste")
			(roundrect_rratio 0.25)
			(net 2 "+3V3")
			(pintype "passive")
			(teardrops
				(best_length_ratio 0.2)
				(max_length 1)
				(best_width_ratio 0.9)
				(max_width 2)
				(curved_edges yes)
				(filter_ratio 0.9)
				(enabled yes)
				(allow_two_segments yes)
				(prefer_zone_connections yes)
			)
		)
	)
	(footprint "antmicro-footprints:C_0402_1005Metric"
		(layer "B.Cu")
		(at 107.78 156.54 180)
		(descr "Capacitor SMD 0402")
		(tags "capacitor SMD 0402")
		(property "Reference" "C215"
			(at -3.68 -0.4 0)
			(layer "B.SilkS")
			(effects
				(font
					(size 0.7 0.7)
					(thickness 0.15)
				)
				(justify left bottom mirror)
			)
		)
		(property "Value" "C_100n_0402"
			(at -1.022927 -2.155213 0)
			(layer "B.Fab")
			(effects
				(font
					(size 0.7 0.7)
					(thickness 0.15)
				)
				(justify left bottom mirror)
			)
		)
		(property "Datasheet" "https://www.murata.com/products/productdetail?partno=GRM155R61H104KE14%23"
			(at 0 0 180)
			(layer "F.Fab")
			(hide yes)
			(effects
				(font
					(size 1.27 1.27)
					(thickness 0.15)
				)
			)
		)
		(property "Author" "Antmicro"
			(at 215.56 313.08 0)
			(layer "B.Fab")
			(hide yes)
			(effects
				(font
					(size 1 1)
					(thickness 0.15)
				)
				(justify mirror)
			)
		)
		(property "Dielectric" "X5R"
			(at 215.56 313.08 0)
			(layer "B.Fab")
			(hide yes)
			(effects
				(font
					(size 1 1)
					(thickness 0.15)
				)
				(justify mirror)
			)
		)
		(property "License" "Apache-2.0"
			(at 215.56 313.08 0)
			(layer "B.Fab")
			(hide yes)
			(effects
				(font
					(size 1 1)
					(thickness 0.15)
				)
				(justify mirror)
			)
		)
		(property "MPN" "GRM155R61H104KE14D"
			(at 215.56 313.08 0)
			(layer "B.Fab")
			(hide yes)
			(effects
				(font
					(size 1 1)
					(thickness 0.15)
				)
				(justify mirror)
			)
		)
		(property "Manufacturer" "Murata"
			(at 215.56 313.08 0)
			(layer "B.Fab")
			(hide yes)
			(effects
				(font
					(size 1 1)
					(thickness 0.15)
				)
				(justify mirror)
			)
		)
		(property "Public" "False"
			(at 215.56 313.08 0)
			(layer "B.Fab")
			(hide yes)
			(effects
				(font
					(size 1 1)
					(thickness 0.15)
				)
				(justify mirror)
			)
		)
		(property "Val" "100n"
			(at 215.56 313.08 0)
			(layer "B.Fab")
			(hide yes)
			(effects
				(font
					(size 1 1)
					(thickness 0.15)
				)
				(justify mirror)
			)
		)
		(property "Voltage" "50V"
			(at 215.56 313.08 0)
			(layer "B.Fab")
			(hide yes)
			(effects
				(font
					(size 1 1)
					(thickness 0.15)
				)
				(justify mirror)
			)
		)
		(sheetname "2xSFP+")
		(sheetfile "2xSFP+.kicad_sch")
		(attr smd)
		(fp_rect
			(start -0.925 0.47)
			(end 0.925 -0.47)
			(stroke
				(width 0.05)
				(type default)
			)
			(fill no)
			(layer "B.CrtYd")
		)
		(fp_line
			(start 0.504 0.25)
			(end -0.494 0.25)
			(stroke
				(width 0.15)
				(type solid)
			)
			(layer "B.Fab")
		)
		(fp_line
			(start 0.504 -0.248)
			(end 0.504 0.25)
			(stroke
				(width 0.15)
				(type solid)
			)
			(layer "B.Fab")
		)
		(fp_line
			(start -0.494 0.25)
			(end -0.494 -0.248)
			(stroke
				(width 0.15)
				(type solid)
			)
			(layer "B.Fab")
		)
		(fp_line
			(start -0.494 -0.248)
			(end 0.504 -0.248)
			(stroke
				(width 0.15)
				(type solid)
			)
			(layer "B.Fab")
		)
		(pad "1" smd roundrect
			(at -0.48 0 180)
			(size 0.59 0.64)
			(layers "B.Cu" "B.Mask" "B.Paste")
			(roundrect_rratio 0.25)
			(net 53 "/2xSFP+/SH")
			(pintype "passive")
			(teardrops
				(best_length_ratio 0.2)
				(max_length 1)
				(best_width_ratio 0.9)
				(max_width 2)
				(curved_edges yes)
				(filter_ratio 0.9)
				(enabled yes)
				(allow_two_segments yes)
				(prefer_zone_connections yes)
			)
		)
		(pad "2" smd roundrect
			(at 0.48 0 180)
			(size 0.59 0.64)
			(layers "B.Cu" "B.Mask" "B.Paste")
			(roundrect_rratio 0.25)
			(net 1 "GND")
			(pintype "passive")
			(teardrops
				(best_length_ratio 0.2)
				(max_length 1)
				(best_width_ratio 0.9)
				(max_width 2)
				(curved_edges yes)
				(filter_ratio 0.9)
				(enabled yes)
				(allow_two_segments yes)
				(prefer_zone_connections yes)
			)
		)
	)
	(footprint "antmicro-footprints:TP_SMD_0.75mm"
		(layer "B.Cu")
		(at 193.607538 150.457538 -45)
		(property "Reference" "TP17"
			(at -0.488908 -0.742463 45)
			(layer "B.SilkS")
			(effects
				(font
					(size 0.7 0.7)
					(thickness 0.15)
				)
				(justify right top mirror)
			)
		)
		(property "Value" "TP_0.75mm_SMD"
			(at 3.225 -53.865 135)
			(layer "B.Fab")
			(hide yes)
			(effects
				(font
					(size 0.7 0.7)
					(thickness 0.15)
				)
				(justify left bottom mirror)
			)
		)
		(property "Author" "Antmicro"
			(at 430.7 339.52 135)
			(layer "B.Fab")
			(hide yes)
			(effects
				(font
					(size 1 1)
					(thickness 0.15)
				)
				(justify mirror)
			)
		)
		(property "License" "Apache-2.0"
			(at 430.7 339.52 135)
			(layer "B.Fab")
			(hide yes)
			(effects
				(font
					(size 1 1)
					(thickness 0.15)
				)
				(justify mirror)
			)
		)
		(property "MPN" ""
			(at 430.7 339.52 135)
			(layer "B.Fab")
			(hide yes)
			(effects
				(font
					(size 1 1)
					(thickness 0.15)
				)
				(justify mirror)
			)
		)
		(property "Manufacturer" ""
			(at 430.7 339.52 135)
			(layer "B.Fab")
			(hide yes)
			(effects
				(font
					(size 1 1)
					(thickness 0.15)
				)
				(justify mirror)
			)
		)
		(property "Public" "False"
			(at 430.7 339.52 135)
			(layer "B.Fab")
			(hide yes)
			(effects
				(font
					(size 1 1)
					(thickness 0.15)
				)
				(justify mirror)
			)
		)
		(sheetname "Com Express 7 Interfaces")
		(sheetfile "com_express_7_interfaces.kicad_sch")
		(attr exclude_from_pos_files exclude_from_bom)
		(fp_circle
			(center 0 0)
			(end 0.475 0)
			(stroke
				(width 0.05)
				(type default)
			)
			(fill no)
			(layer "B.CrtYd")
		)
		(pad "1" smd circle
			(at 0 0 315)
			(size 0.75 0.75)
			(layers "B.Cu" "B.Mask")
			(net 484 "Net-(J12K-10G_PHY_CAP_01)")
			(pinfunction "1")
			(pintype "passive")
			(teardrops
				(best_length_ratio 0.4)
				(max_length 1)
				(best_width_ratio 0.9)
				(max_width 2)
				(curved_edges yes)
				(filter_ratio 0.9)
				(enabled yes)
				(allow_two_segments yes)
				(prefer_zone_connections yes)
			)
		)
	)
	(footprint "antmicro-footprints:TP_SMD_0.75mm"
		(layer "B.Cu")
		(at 158.9 162.46 -90)
		(property "Reference" "TP2"
			(at -2.437 -0.449 90)
			(layer "B.SilkS")
			(effects
				(font
					(size 0.7 0.7)
					(thickness 0.15)
				)
				(justify left bottom mirror)
			)
		)
		(property "Value" "TP_0.75mm_SMD"
			(at 0 -1.2 90)
			(layer "B.Fab")
			(effects
				(font
					(size 0.7 0.7)
					(thickness 0.15)
				)
				(justify left bottom mirror)
			)
		)
		(property "Author" "Antmicro"
			(at -3.56 321.36 0)
			(layer "B.Fab")
			(hide yes)
			(effects
				(font
					(size 1 1)
					(thickness 0.15)
				)
				(justify mirror)
			)
		)
		(property "License" "Apache-2.0"
			(at -3.56 321.36 0)
			(layer "B.Fab")
			(hide yes)
			(effects
				(font
					(size 1 1)
					(thickness 0.15)
				)
				(justify mirror)
			)
		)
		(property "MPN" ""
			(at -3.56 321.36 0)
			(layer "B.Fab")
			(hide yes)
			(effects
				(font
					(size 1 1)
					(thickness 0.15)
				)
				(justify mirror)
			)
		)
		(property "Manufacturer" ""
			(at -3.56 321.36 0)
			(layer "B.Fab")
			(hide yes)
			(effects
				(font
					(size 1 1)
					(thickness 0.15)
				)
				(justify mirror)
			)
		)
		(property "Public" "False"
			(at -3.56 321.36 0)
			(layer "B.Fab")
			(hide yes)
			(effects
				(font
					(size 1 1)
					(thickness 0.15)
				)
				(justify mirror)
			)
		)
		(sheetname "2xSFP+")
		(sheetfile "2xSFP+.kicad_sch")
		(attr exclude_from_pos_files exclude_from_bom)
		(fp_circle
			(center 0 0)
			(end 0.475 0)
			(stroke
				(width 0.05)
				(type default)
			)
			(fill no)
			(layer "B.CrtYd")
		)
		(pad "1" smd circle
			(at 0 0 270)
			(size 0.75 0.75)
			(layers "B.Cu" "B.Mask")
			(net 698 "Net-(U5-IO0_7)")
			(pinfunction "1")
			(pintype "passive")
			(teardrops
				(best_length_ratio 0.4)
				(max_length 1)
				(best_width_ratio 0.9)
				(max_width 2)
				(curved_edges yes)
				(filter_ratio 0.9)
				(enabled yes)
				(allow_two_segments yes)
				(prefer_zone_connections yes)
			)
		)
	)
	(footprint "antmicro-footprints:R_0402_1005Metric"
		(layer "B.Cu")
		(at 104.44 169.96)
		(descr "Resistor SMD 0402")
		(tags "resistor SMD 0402")
		(property "Reference" "R80"
			(at -1.1 1.35 0)
			(layer "B.SilkS")
			(effects
				(font
					(size 0.7 0.7)
					(thickness 0.15)
				)
				(justify right bottom mirror)
			)
		)
		(property "Value" "R_0R_0402"
			(at -1.011843 -1.772047 0)
			(layer "B.Fab")
			(effects
				(font
					(size 0.7 0.7)
					(thickness 0.15)
				)
				(justify right bottom mirror)
			)
		)
		(property "Datasheet" "https://industrial.panasonic.com/cdbs/www-data/pdf/RDA0000/AOA0000C301.pdf"
			(at 0 0 0)
			(layer "F.Fab")
			(hide yes)
			(effects
				(font
					(size 1.27 1.27)
					(thickness 0.15)
				)
			)
		)
		(property "Author" "Antmicro"
			(at 0 0 0)
			(layer "B.Fab")
			(hide yes)
			(effects
				(font
					(size 1 1)
					(thickness 0.15)
				)
				(justify mirror)
			)
		)
		(property "Current" "1A"
			(at 0 0 0)
			(layer "B.Fab")
			(hide yes)
			(effects
				(font
					(size 1 1)
					(thickness 0.15)
				)
				(justify mirror)
			)
		)
		(property "License" "Apache-2.0"
			(at 0 0 0)
			(layer "B.Fab")
			(hide yes)
			(effects
				(font
					(size 1 1)
					(thickness 0.15)
				)
				(justify mirror)
			)
		)
		(property "MPN" "ERJ2GE0R00X"
			(at 0 0 0)
			(layer "B.Fab")
			(hide yes)
			(effects
				(font
					(size 1 1)
					(thickness 0.15)
				)
				(justify mirror)
			)
		)
		(property "Manufacturer" "Panasonic"
			(at 0 0 0)
			(layer "B.Fab")
			(hide yes)
			(effects
				(font
					(size 1 1)
					(thickness 0.15)
				)
				(justify mirror)
			)
		)
		(property "Public" "False"
			(at 0 0 0)
			(layer "B.Fab")
			(hide yes)
			(effects
				(font
					(size 1 1)
					(thickness 0.15)
				)
				(justify mirror)
			)
		)
		(property "Tolerance" ""
			(at 0 0 0)
			(layer "B.Fab")
			(hide yes)
			(effects
				(font
					(size 1 1)
					(thickness 0.15)
				)
				(justify mirror)
			)
		)
		(property "Val" "0R"
			(at 0 0 0)
			(layer "B.Fab")
			(hide yes)
			(effects
				(font
					(size 1 1)
					(thickness 0.15)
				)
				(justify mirror)
			)
		)
		(sheetname "OCuLink")
		(sheetfile "oculink.kicad_sch")
		(attr smd)
		(fp_rect
			(start -0.925 0.47)
			(end 0.925 -0.47)
			(stroke
				(width 0.05)
				(type default)
			)
			(fill no)
			(layer "B.CrtYd")
		)
		(fp_rect
			(start -0.5 0.25)
			(end 0.5 -0.25)
			(stroke
				(width 0.15)
				(type solid)
			)
			(fill no)
			(layer "B.Fab")
		)
		(pad "1" smd roundrect
			(at -0.48 0)
			(size 0.59 0.64)
			(layers "B.Cu" "B.Mask" "B.Paste")
			(roundrect_rratio 0.25)
			(net 60 "/OCuLink/V_{ACT_RX}0")
			(pintype "passive")
			(teardrops
				(best_length_ratio 0.2)
				(max_length 1)
				(best_width_ratio 0.9)
				(max_width 2)
				(curved_edges yes)
				(filter_ratio 0.9)
				(enabled yes)
				(allow_two_segments yes)
				(prefer_zone_connections yes)
			)
		)
		(pad "2" smd roundrect
			(at 0.48 0)
			(size 0.59 0.64)
			(layers "B.Cu" "B.Mask" "B.Paste")
			(roundrect_rratio 0.25)
			(net 2 "+3V3")
			(pintype "passive")
			(teardrops
				(best_length_ratio 0.2)
				(max_length 1)
				(best_width_ratio 0.9)
				(max_width 2)
				(curved_edges yes)
				(filter_ratio 0.9)
				(enabled yes)
				(allow_two_segments yes)
				(prefer_zone_connections yes)
			)
		)
	)
	(footprint "antmicro-footprints:C_0402_1005Metric"
		(layer "B.Cu")
		(at 151.45 136.36 -90)
		(descr "Capacitor SMD 0402")
		(tags "capacitor SMD 0402")
		(property "Reference" "C174"
			(at -1.1 -1.4 90)
			(layer "B.SilkS")
			(effects
				(font
					(size 0.7 0.7)
					(thickness 0.15)
				)
				(justify left bottom mirror)
			)
		)
		(property "Value" "C_100n_0402"
			(at -1.022927 -2.155213 90)
			(layer "B.Fab")
			(effects
				(font
					(size 0.7 0.7)
					(thickness 0.15)
				)
				(justify left bottom mirror)
			)
		)
		(property "Datasheet" "https://www.murata.com/products/productdetail?partno=GRM155R61H104KE14%23"
			(at 0 0 270)
			(layer "F.Fab")
			(hide yes)
			(effects
				(font
					(size 1.27 1.27)
					(thickness 0.15)
				)
			)
		)
		(property "Author" "Antmicro"
			(at 15.09 287.81 0)
			(layer "B.Fab")
			(hide yes)
			(effects
				(font
					(size 1 1)
					(thickness 0.15)
				)
				(justify mirror)
			)
		)
		(property "Dielectric" "X5R"
			(at 15.09 287.81 0)
			(layer "B.Fab")
			(hide yes)
			(effects
				(font
					(size 1 1)
					(thickness 0.15)
				)
				(justify mirror)
			)
		)
		(property "License" "Apache-2.0"
			(at 15.09 287.81 0)
			(layer "B.Fab")
			(hide yes)
			(effects
				(font
					(size 1 1)
					(thickness 0.15)
				)
				(justify mirror)
			)
		)
		(property "MPN" "GRM155R61H104KE14D"
			(at 15.09 287.81 0)
			(layer "B.Fab")
			(hide yes)
			(effects
				(font
					(size 1 1)
					(thickness 0.15)
				)
				(justify mirror)
			)
		)
		(property "Manufacturer" "Murata"
			(at 15.09 287.81 0)
			(layer "B.Fab")
			(hide yes)
			(effects
				(font
					(size 1 1)
					(thickness 0.15)
				)
				(justify mirror)
			)
		)
		(property "Public" "False"
			(at 15.09 287.81 0)
			(layer "B.Fab")
			(hide yes)
			(effects
				(font
					(size 1 1)
					(thickness 0.15)
				)
				(justify mirror)
			)
		)
		(property "Val" "100n"
			(at 15.09 287.81 0)
			(layer "B.Fab")
			(hide yes)
			(effects
				(font
					(size 1 1)
					(thickness 0.15)
				)
				(justify mirror)
			)
		)
		(property "Voltage" "50V"
			(at 15.09 287.81 0)
			(layer "B.Fab")
			(hide yes)
			(effects
				(font
					(size 1 1)
					(thickness 0.15)
				)
				(justify mirror)
			)
		)
		(sheetname "KR to SFI #1")
		(sheetfile "kr_sfi.kicad_sch")
		(attr smd)
		(fp_rect
			(start -0.925 0.47)
			(end 0.925 -0.47)
			(stroke
				(width 0.05)
				(type default)
			)
			(fill no)
			(layer "B.CrtYd")
		)
		(fp_line
			(start -0.494 0.25)
			(end -0.494 -0.248)
			(stroke
				(width 0.15)
				(type solid)
			)
			(layer "B.Fab")
		)
		(fp_line
			(start 0.504 0.25)
			(end -0.494 0.25)
			(stroke
				(width 0.15)
				(type solid)
			)
			(layer "B.Fab")
		)
		(fp_line
			(start -0.494 -0.248)
			(end 0.504 -0.248)
			(stroke
				(width 0.15)
				(type solid)
			)
			(layer "B.Fab")
		)
		(fp_line
			(start 0.504 -0.248)
			(end 0.504 0.25)
			(stroke
				(width 0.15)
				(type solid)
			)
			(layer "B.Fab")
		)
		(pad "1" smd roundrect
			(at -0.48 0 270)
			(size 0.59 0.64)
			(layers "B.Cu" "B.Mask" "B.Paste")
			(roundrect_rratio 0.25)
			(net 1 "GND")
			(pintype "passive")
			(teardrops
				(best_length_ratio 0.2)
				(max_length 1)
				(best_width_ratio 0.9)
				(max_width 2)
				(curved_edges yes)
				(filter_ratio 0.9)
				(enabled yes)
				(allow_two_segments yes)
				(prefer_zone_connections yes)
			)
		)
		(pad "2" smd roundrect
			(at 0.48 0 270)
			(size 0.59 0.64)
			(layers "B.Cu" "B.Mask" "B.Paste")
			(roundrect_rratio 0.25)
			(net 74 "+1V0")
			(pintype "passive")
			(teardrops
				(best_length_ratio 0.2)
				(max_length 1)
				(best_width_ratio 0.9)
				(max_width 2)
				(curved_edges yes)
				(filter_ratio 0.9)
				(enabled yes)
				(allow_two_segments yes)
				(prefer_zone_connections yes)
			)
		)
	)
	(footprint "antmicro-footprints:R_0402_1005Metric"
		(layer "B.Cu")
		(at 139.74 140.36)
		(descr "Resistor SMD 0402")
		(tags "resistor SMD 0402")
		(property "Reference" "R286"
			(at -3.64 0.75 0)
			(layer "B.SilkS")
			(effects
				(font
					(size 0.7 0.7)
					(thickness 0.15)
				)
				(justify right bottom mirror)
			)
		)
		(property "Value" "R_10k_0402"
			(at -1.011843 -1.772047 0)
			(layer "B.Fab")
			(effects
				(font
					(size 0.7 0.7)
					(thickness 0.15)
				)
				(justify right bottom mirror)
			)
		)
		(property "Datasheet" "https://www.bourns.com/docs/product-datasheets/cr.pdf"
			(at 0 0 0)
			(layer "F.Fab")
			(hide yes)
			(effects
				(font
					(size 1.27 1.27)
					(thickness 0.15)
				)
			)
		)
		(property "Author" "Antmicro"
			(at 0 0 0)
			(layer "B.Fab")
			(hide yes)
			(effects
				(font
					(size 1 1)
					(thickness 0.15)
				)
				(justify mirror)
			)
		)
		(property "License" "Apache-2.0"
			(at 0 0 0)
			(layer "B.Fab")
			(hide yes)
			(effects
				(font
					(size 1 1)
					(thickness 0.15)
				)
				(justify mirror)
			)
		)
		(property "MPN" "CR0402-FX-1002GLF"
			(at 0 0 0)
			(layer "B.Fab")
			(hide yes)
			(effects
				(font
					(size 1 1)
					(thickness 0.15)
				)
				(justify mirror)
			)
		)
		(property "Manufacturer" "Bourns"
			(at 0 0 0)
			(layer "B.Fab")
			(hide yes)
			(effects
				(font
					(size 1 1)
					(thickness 0.15)
				)
				(justify mirror)
			)
		)
		(property "Public" "False"
			(at 0 0 0)
			(layer "B.Fab")
			(hide yes)
			(effects
				(font
					(size 1 1)
					(thickness 0.15)
				)
				(justify mirror)
			)
		)
		(property "Tolerance" "1%"
			(at 0 0 0)
			(layer "B.Fab")
			(hide yes)
			(effects
				(font
					(size 1 1)
					(thickness 0.15)
				)
				(justify mirror)
			)
		)
		(property "Val" "10k"
			(at 0 0 0)
			(layer "B.Fab")
			(hide yes)
			(effects
				(font
					(size 1 1)
					(thickness 0.15)
				)
				(justify mirror)
			)
		)
		(sheetname "KR to SFI #2")
		(sheetfile "kr_sfi.kicad_sch")
		(attr smd dnp)
		(fp_rect
			(start -0.925 0.47)
			(end 0.925 -0.47)
			(stroke
				(width 0.05)
				(type default)
			)
			(fill no)
			(layer "B.CrtYd")
		)
		(fp_rect
			(start -0.5 0.25)
			(end 0.5 -0.25)
			(stroke
				(width 0.15)
				(type solid)
			)
			(fill no)
			(layer "B.Fab")
		)
		(pad "1" smd roundrect
			(at -0.48 0)
			(size 0.59 0.64)
			(layers "B.Cu" "B.Mask" "B.Paste")
			(roundrect_rratio 0.25)
			(net 673 "/2xSFP+/KR to SFI #2/PRBSEN")
			(pintype "passive")
			(teardrops
				(best_length_ratio 0.2)
				(max_length 1)
				(best_width_ratio 0.9)
				(max_width 2)
				(curved_edges yes)
				(filter_ratio 0.9)
				(enabled yes)
				(allow_two_segments yes)
				(prefer_zone_connections yes)
			)
		)
		(pad "2" smd roundrect
			(at 0.48 0)
			(size 0.59 0.64)
			(layers "B.Cu" "B.Mask" "B.Paste")
			(roundrect_rratio 0.25)
			(net 78 "+1V8")
			(pintype "passive")
			(teardrops
				(best_length_ratio 0.2)
				(max_length 1)
				(best_width_ratio 0.9)
				(max_width 2)
				(curved_edges yes)
				(filter_ratio 0.9)
				(enabled yes)
				(allow_two_segments yes)
				(prefer_zone_connections yes)
			)
		)
	)
	(footprint "antmicro-footprints:R_0402_1005Metric"
		(layer "B.Cu")
		(at 126.09 142.06)
		(descr "Resistor SMD 0402")
		(tags "resistor SMD 0402")
		(property "Reference" "R303"
			(at -3.64 1.05 0)
			(layer "B.SilkS")
			(effects
				(font
					(size 0.7 0.7)
					(thickness 0.15)
				)
				(justify right bottom mirror)
			)
		)
		(property "Value" "R_10k_0402"
			(at -1.011843 -1.772047 0)
			(layer "B.Fab")
			(effects
				(font
					(size 0.7 0.7)
					(thickness 0.15)
				)
				(justify right bottom mirror)
			)
		)
		(property "Datasheet" "https://www.bourns.com/docs/product-datasheets/cr.pdf"
			(at 0 0 0)
			(layer "F.Fab")
			(hide yes)
			(effects
				(font
					(size 1.27 1.27)
					(thickness 0.15)
				)
			)
		)
		(property "Author" "Antmicro"
			(at 0 0 0)
			(layer "B.Fab")
			(hide yes)
			(effects
				(font
					(size 1 1)
					(thickness 0.15)
				)
				(justify mirror)
			)
		)
		(property "License" "Apache-2.0"
			(at 0 0 0)
			(layer "B.Fab")
			(hide yes)
			(effects
				(font
					(size 1 1)
					(thickness 0.15)
				)
				(justify mirror)
			)
		)
		(property "MPN" "CR0402-FX-1002GLF"
			(at 0 0 0)
			(layer "B.Fab")
			(hide yes)
			(effects
				(font
					(size 1 1)
					(thickness 0.15)
				)
				(justify mirror)
			)
		)
		(property "Manufacturer" "Bourns"
			(at 0 0 0)
			(layer "B.Fab")
			(hide yes)
			(effects
				(font
					(size 1 1)
					(thickness 0.15)
				)
				(justify mirror)
			)
		)
		(property "Public" "False"
			(at 0 0 0)
			(layer "B.Fab")
			(hide yes)
			(effects
				(font
					(size 1 1)
					(thickness 0.15)
				)
				(justify mirror)
			)
		)
		(property "Tolerance" "1%"
			(at 0 0 0)
			(layer "B.Fab")
			(hide yes)
			(effects
				(font
					(size 1 1)
					(thickness 0.15)
				)
				(justify mirror)
			)
		)
		(property "Val" "10k"
			(at 0 0 0)
			(layer "B.Fab")
			(hide yes)
			(effects
				(font
					(size 1 1)
					(thickness 0.15)
				)
				(justify mirror)
			)
		)
		(sheetname "KR to SFI #2")
		(sheetfile "kr_sfi.kicad_sch")
		(attr smd)
		(fp_rect
			(start -0.925 0.47)
			(end 0.925 -0.47)
			(stroke
				(width 0.05)
				(type default)
			)
			(fill no)
			(layer "B.CrtYd")
		)
		(fp_rect
			(start -0.5 0.25)
			(end 0.5 -0.25)
			(stroke
				(width 0.15)
				(type solid)
			)
			(fill no)
			(layer "B.Fab")
		)
		(pad "1" smd roundrect
			(at -0.48 0)
			(size 0.59 0.64)
			(layers "B.Cu" "B.Mask" "B.Paste")
			(roundrect_rratio 0.25)
			(net 1 "GND")
			(pintype "passive")
			(teardrops
				(best_length_ratio 0.2)
				(max_length 1)
				(best_width_ratio 0.9)
				(max_width 2)
				(curved_edges yes)
				(filter_ratio 0.9)
				(enabled yes)
				(allow_two_segments yes)
				(prefer_zone_connections yes)
			)
		)
		(pad "2" smd roundrect
			(at 0.48 0)
			(size 0.59 0.64)
			(layers "B.Cu" "B.Mask" "B.Paste")
			(roundrect_rratio 0.25)
			(net 683 "Net-(U45C-MODE_{SEL})")
			(pintype "passive")
			(teardrops
				(best_length_ratio 0.2)
				(max_length 1)
				(best_width_ratio 0.9)
				(max_width 2)
				(curved_edges yes)
				(filter_ratio 0.9)
				(enabled yes)
				(allow_two_segments yes)
				(prefer_zone_connections yes)
			)
		)
	)
	(footprint "antmicro-footprints:USON-10_2.5x1mm_P0.5mm"
		(layer "B.Cu")
		(at 100.94 105.365)
		(descr "USON-10 2.5x1mm_ Pitch 0.5mm")
		(tags "USON-10 2.5x1mm Pitch 0.5mm")
		(property "Reference" "U1"
			(at 1.71 0.895 90)
			(layer "B.SilkS")
			(effects
				(font
					(size 0.7 0.7)
					(thickness 0.15)
				)
				(justify right bottom mirror)
			)
		)
		(property "Value" "ESD204DQAR"
			(at 0.018 -2.499 0)
			(layer "B.Fab")
			(effects
				(font
					(size 0.7 0.7)
					(thickness 0.15)
				)
				(justify right bottom mirror)
			)
		)
		(property "Datasheet" "https://www.ti.com/lit/ds/symlink/esd204.pdf?ts=1706004844383&ref_url=https%253A%252F%252Fwww.ti.com%252Finterface%252Fdiodes%252Fesd-protection-diodes%252Fproducts.html"
			(at 0 0 0)
			(layer "F.Fab")
			(hide yes)
			(effects
				(font
					(size 1.27 1.27)
					(thickness 0.15)
				)
			)
		)
		(property "Author" "Antmicro"
			(at 0 0 0)
			(layer "B.Fab")
			(hide yes)
			(effects
				(font
					(size 1 1)
					(thickness 0.15)
				)
				(justify mirror)
			)
		)
		(property "License" "Apache-2.0"
			(at 0 0 0)
			(layer "B.Fab")
			(hide yes)
			(effects
				(font
					(size 1 1)
					(thickness 0.15)
				)
				(justify mirror)
			)
		)
		(property "MPN" "ESD204DQAR"
			(at 0 0 0)
			(layer "B.Fab")
			(hide yes)
			(effects
				(font
					(size 1 1)
					(thickness 0.15)
				)
				(justify mirror)
			)
		)
		(property "Manufacturer" "Texas Instruments"
			(at 0 0 0)
			(layer "B.Fab")
			(hide yes)
			(effects
				(font
					(size 1 1)
					(thickness 0.15)
				)
				(justify mirror)
			)
		)
		(sheetname "2xUSB3.0+RJ45")
		(sheetfile "usb3+rj45.kicad_sch")
		(attr smd)
		(fp_line
			(start -0.5 -1.398)
			(end 0.498 -1.398)
			(stroke
				(width 0.15)
				(type solid)
			)
			(layer "B.SilkS")
		)
		(fp_line
			(start -0.5 1.401)
			(end 0.498 1.401)
			(stroke
				(width 0.15)
				(type solid)
			)
			(layer "B.SilkS")
		)
		(fp_circle
			(center -0.68 1.27)
			(end -0.63 1.27)
			(stroke
				(width 0.15)
				(type solid)
			)
			(fill yes)
			(layer "B.SilkS")
		)
		(fp_rect
			(start -0.8 1.5)
			(end 0.8 -1.499)
			(stroke
				(width 0.05)
				(type solid)
			)
			(fill no)
			(layer "B.CrtYd")
		)
		(fp_line
			(start -0.5 -1.249)
			(end -0.5 1)
			(stroke
				(width 0.15)
				(type solid)
			)
			(layer "B.Fab")
		)
		(fp_line
			(start -0.5 1)
			(end -0.25 1.25)
			(stroke
				(width 0.15)
				(type solid)
			)
			(layer "B.Fab")
		)
		(fp_line
			(start -0.25 1.25)
			(end 0.498 1.25)
			(stroke
				(width 0.15)
				(type solid)
			)
			(layer "B.Fab")
		)
		(fp_line
			(start 0.498 -1.249)
			(end -0.5 -1.249)
			(stroke
				(width 0.15)
				(type solid)
			)
			(layer "B.Fab")
		)
		(fp_line
			(start 0.498 -1.249)
			(end 0.498 1.25)
			(stroke
				(width 0.15)
				(type solid)
			)
			(layer "B.Fab")
		)
		(pad "1" smd roundrect
			(at -0.387 1 90)
			(size 0.25 0.55)
			(layers "B.Cu" "B.Mask" "B.Paste")
			(roundrect_rratio 0.25)
			(net 158 "/2xUSB3.0+RJ45/USBSS_1.RX-")
			(pintype "passive")
			(teardrops
				(best_length_ratio 0.2)
				(max_length 1)
				(best_width_ratio 0.9)
				(max_width 2)
				(curved_edges yes)
				(filter_ratio 0.9)
				(enabled yes)
				(allow_two_segments yes)
				(prefer_zone_connections yes)
			)
		)
		(pad "2" smd roundrect
			(at -0.387 0.5 90)
			(size 0.25 0.55)
			(layers "B.Cu" "B.Mask" "B.Paste")
			(roundrect_rratio 0.25)
			(net 159 "/2xUSB3.0+RJ45/USBSS_1.RX+")
			(pintype "passive")
			(teardrops
				(best_length_ratio 0.2)
				(max_length 1)
				(best_width_ratio 0.9)
				(max_width 2)
				(curved_edges yes)
				(filter_ratio 0.9)
				(enabled yes)
				(allow_two_segments yes)
				(prefer_zone_connections yes)
			)
		)
		(pad "3" smd roundrect
			(at -0.387 0 90)
			(size 0.4 0.55)
			(layers "B.Cu" "B.Mask" "B.Paste")
			(roundrect_rratio 0.25)
			(net 1 "GND")
			(pintype "power_in")
			(teardrops
				(best_length_ratio 0.2)
				(max_length 1)
				(best_width_ratio 0.9)
				(max_width 2)
				(curved_edges yes)
				(filter_ratio 0.9)
				(enabled yes)
				(allow_two_segments yes)
				(prefer_zone_connections yes)
			)
		)
		(pad "4" smd roundrect
			(at -0.387 -0.498 90)
			(size 0.25 0.55)
			(layers "B.Cu" "B.Mask" "B.Paste")
			(roundrect_rratio 0.25)
			(net 47 "/2xUSB3.0+RJ45/USBSS_1.TX-")
			(pintype "passive")
			(teardrops
				(best_length_ratio 0.2)
				(max_length 1)
				(best_width_ratio 0.9)
				(max_width 2)
				(curved_edges yes)
				(filter_ratio 0.9)
				(enabled yes)
				(allow_two_segments yes)
				(prefer_zone_connections yes)
			)
		)
		(pad "5" smd roundrect
			(at -0.387 -0.998 90)
			(size 0.25 0.55)
			(layers "B.Cu" "B.Mask" "B.Paste")
			(roundrect_rratio 0.25)
			(net 44 "/2xUSB3.0+RJ45/USBSS_1.TX+")
			(pintype "passive")
			(teardrops
				(best_length_ratio 0.2)
				(max_length 1)
				(best_width_ratio 0.9)
				(max_width 2)
				(curved_edges yes)
				(filter_ratio 0.9)
				(enabled yes)
				(allow_two_segments yes)
				(prefer_zone_connections yes)
			)
		)
		(pad "6" smd roundrect
			(at 0.385 -0.998 90)
			(size 0.25 0.55)
			(layers "B.Cu" "B.Mask" "B.Paste")
			(roundrect_rratio 0.25)
			(net 44 "/2xUSB3.0+RJ45/USBSS_1.TX+")
			(pintype "passive")
			(teardrops
				(best_length_ratio 0.2)
				(max_length 1)
				(best_width_ratio 0.9)
				(max_width 2)
				(curved_edges yes)
				(filter_ratio 0.9)
				(enabled yes)
				(allow_two_segments yes)
				(prefer_zone_connections yes)
			)
		)
		(pad "7" smd roundrect
			(at 0.385 -0.498 90)
			(size 0.25 0.55)
			(layers "B.Cu" "B.Mask" "B.Paste")
			(roundrect_rratio 0.25)
			(net 47 "/2xUSB3.0+RJ45/USBSS_1.TX-")
			(pintype "passive")
			(teardrops
				(best_length_ratio 0.2)
				(max_length 1)
				(best_width_ratio 0.9)
				(max_width 2)
				(curved_edges yes)
				(filter_ratio 0.9)
				(enabled yes)
				(allow_two_segments yes)
				(prefer_zone_connections yes)
			)
		)
		(pad "8" smd roundrect
			(at 0.385 0 90)
			(size 0.4 0.55)
			(layers "B.Cu" "B.Mask" "B.Paste")
			(roundrect_rratio 0.25)
			(net 1 "GND")
			(pintype "passive")
			(teardrops
				(best_length_ratio 0.2)
				(max_length 1)
				(best_width_ratio 0.9)
				(max_width 2)
				(curved_edges yes)
				(filter_ratio 0.9)
				(enabled yes)
				(allow_two_segments yes)
				(prefer_zone_connections yes)
			)
		)
		(pad "9" smd roundrect
			(at 0.385 0.5 90)
			(size 0.25 0.55)
			(layers "B.Cu" "B.Mask" "B.Paste")
			(roundrect_rratio 0.25)
			(net 159 "/2xUSB3.0+RJ45/USBSS_1.RX+")
			(pintype "passive")
			(teardrops
				(best_length_ratio 0.2)
				(max_length 1)
				(best_width_ratio 0.9)
				(max_width 2)
				(curved_edges yes)
				(filter_ratio 0.9)
				(enabled yes)
				(allow_two_segments yes)
				(prefer_zone_connections yes)
			)
		)
		(pad "10" smd roundrect
			(at 0.385 1 90)
			(size 0.25 0.55)
			(layers "B.Cu" "B.Mask" "B.Paste")
			(roundrect_rratio 0.25)
			(net 158 "/2xUSB3.0+RJ45/USBSS_1.RX-")
			(pintype "passive")
			(teardrops
				(best_length_ratio 0.2)
				(max_length 1)
				(best_width_ratio 0.9)
				(max_width 2)
				(curved_edges yes)
				(filter_ratio 0.9)
				(enabled yes)
				(allow_two_segments yes)
				(prefer_zone_connections yes)
			)
		)
	)
	(footprint "antmicro-footprints:SC70-3"
		(layer "B.Cu")
		(at 104.35 105.365 180)
		(property "Reference" "D25"
			(at -1.05 1.305 0)
			(layer "B.SilkS")
			(effects
				(font
					(size 0.7 0.7)
					(thickness 0.15)
				)
				(justify left bottom mirror)
			)
		)
		(property "Value" "TPD2E2U06_SC70"
			(at 0 -2.3 0)
			(layer "B.Fab")
			(effects
				(font
					(size 0.7 0.7)
					(thickness 0.15)
				)
				(justify left bottom mirror)
			)
		)
		(property "Datasheet" "https://www.ti.com/lit/ds/symlink/tpd2e2u06.pdf?ts=1706006131823&ref_url=https%253A%252F%252Fwww.ti.com%252Finterface%252Fdiodes%252Fesd-protection-diodes%252Fproducts.html"
			(at 0 0 180)
			(layer "F.Fab")
			(hide yes)
			(effects
				(font
					(size 1.27 1.27)
					(thickness 0.15)
				)
			)
		)
		(property "Author" "Antmicro"
			(at 208.7 210.73 0)
			(layer "B.Fab")
			(hide yes)
			(effects
				(font
					(size 1 1)
					(thickness 0.15)
				)
				(justify mirror)
			)
		)
		(property "License" "Apache-2.0"
			(at 208.7 210.73 0)
			(layer "B.Fab")
			(hide yes)
			(effects
				(font
					(size 1 1)
					(thickness 0.15)
				)
				(justify mirror)
			)
		)
		(property "MPN" "TPD2E2U06DCKR"
			(at 208.7 210.73 0)
			(layer "B.Fab")
			(hide yes)
			(effects
				(font
					(size 1 1)
					(thickness 0.15)
				)
				(justify mirror)
			)
		)
		(property "Manufacturer" "Texas Instruments"
			(at 208.7 210.73 0)
			(layer "B.Fab")
			(hide yes)
			(effects
				(font
					(size 1 1)
					(thickness 0.15)
				)
				(justify mirror)
			)
		)
		(sheetname "2xUSB3.0+RJ45")
		(sheetfile "usb3+rj45.kicad_sch")
		(attr smd)
		(fp_line
			(start 0.627 0.999)
			(end 0.627 0.6)
			(stroke
				(width 0.15)
				(type solid)
			)
			(layer "B.SilkS")
		)
		(fp_line
			(start 0.627 0.999)
			(end -0.3 1)
			(stroke
				(width 0.15)
				(type solid)
			)
			(layer "B.SilkS")
		)
		(fp_line
			(start 0.627 -1.001)
			(end 0.627 -0.6)
			(stroke
				(width 0.15)
				(type solid)
			)
			(layer "B.SilkS")
		)
		(fp_line
			(start 0.627 -1.001)
			(end -0.3 -1)
			(stroke
				(width 0.15)
				(type solid)
			)
			(layer "B.SilkS")
		)
		(fp_line
			(start 1.4 0.4)
			(end 0.9 0.4)
			(stroke
				(width 0.05)
				(type solid)
			)
			(layer "B.CrtYd")
		)
		(fp_line
			(start 1.4 -0.4)
			(end 1.4 0.4)
			(stroke
				(width 0.05)
				(type solid)
			)
			(layer "B.CrtYd")
		)
		(fp_line
			(start 0.9 1.3)
			(end -0.9 1.3)
			(stroke
				(width 0.05)
				(type solid)
			)
			(layer "B.CrtYd")
		)
		(fp_line
			(start 0.9 0.4)
			(end 0.9 1.3)
			(stroke
				(width 0.05)
				(type solid)
			)
			(layer "B.CrtYd")
		)
		(fp_line
			(start 0.9 -0.4)
			(end 1.4 -0.4)
			(stroke
				(width 0.05)
				(type solid)
			)
			(layer "B.CrtYd")
		)
		(fp_line
			(start 0.9 -1.3)
			(end 0.9 -0.4)
			(stroke
				(width 0.05)
				(type solid)
			)
			(layer "B.CrtYd")
		)
		(fp_line
			(start -0.9 1)
			(end -0.9 1.3)
			(stroke
				(width 0.05)
				(type solid)
			)
			(layer "B.CrtYd")
		)
		(fp_line
			(start -0.9 -1)
			(end -0.9 -1.3)
			(stroke
				(width 0.05)
				(type solid)
			)
			(layer "B.CrtYd")
		)
		(fp_line
			(start -0.9 -1.3)
			(end 0.9 -1.3)
			(stroke
				(width 0.05)
				(type solid)
			)
			(layer "B.CrtYd")
		)
		(fp_line
			(start -1.4 1)
			(end -0.9 1)
			(stroke
				(width 0.05)
				(type solid)
			)
			(layer "B.CrtYd")
		)
		(fp_line
			(start -1.4 1)
			(end -1.4 -1)
			(stroke
				(width 0.05)
				(type solid)
			)
			(layer "B.CrtYd")
		)
		(fp_line
			(start -1.4 -1)
			(end -0.9 -1)
			(stroke
				(width 0.05)
				(type solid)
			)
			(layer "B.CrtYd")
		)
		(fp_rect
			(start -0.623 0.999)
			(end 0.627 -1.001)
			(stroke
				(width 0.15)
				(type solid)
			)
			(fill no)
			(layer "B.Fab")
		)
		(pad "1" smd rect
			(at -1.051 0.65 90)
			(size 0.6 0.6)
			(layers "B.Cu" "B.Mask" "B.Paste")
			(net 123 "/2xUSB3.0+RJ45/P1_D-")
			(pinfunction "1")
			(pintype "passive")
			(teardrops
				(best_length_ratio 0.2)
				(max_length 1)
				(best_width_ratio 0.9)
				(max_width 2)
				(curved_edges yes)
				(filter_ratio 0.9)
				(enabled yes)
				(allow_two_segments yes)
				(prefer_zone_connections yes)
			)
		)
		(pad "2" smd rect
			(at -1.051 -0.65 90)
			(size 0.6 0.6)
			(layers "B.Cu" "B.Mask" "B.Paste")
			(net 124 "/2xUSB3.0+RJ45/P1_D+")
			(pinfunction "2")
			(pintype "passive")
			(teardrops
				(best_length_ratio 0.2)
				(max_length 1)
				(best_width_ratio 0.9)
				(max_width 2)
				(curved_edges yes)
				(filter_ratio 0.9)
				(enabled yes)
				(allow_two_segments yes)
				(prefer_zone_connections yes)
			)
		)
		(pad "3" smd rect
			(at 1.05 0 90)
			(size 0.6 0.6)
			(layers "B.Cu" "B.Mask" "B.Paste")
			(net 1 "GND")
			(pinfunction "3")
			(pintype "passive")
			(teardrops
				(best_length_ratio 0.2)
				(max_length 1)
				(best_width_ratio 0.9)
				(max_width 2)
				(curved_edges yes)
				(filter_ratio 0.9)
				(enabled yes)
				(allow_two_segments yes)
				(prefer_zone_connections yes)
			)
		)
	)
	(footprint "antmicro-footprints:C_0402_1005Metric"
		(layer "B.Cu")
		(at 124.22 149.26 90)
		(descr "Capacitor SMD 0402")
		(tags "capacitor SMD 0402")
		(property "Reference" "C177"
			(at -1.75 2.33 90)
			(layer "B.SilkS")
			(effects
				(font
					(size 0.7 0.7)
					(thickness 0.15)
				)
				(justify right bottom mirror)
			)
		)
		(property "Value" "C_100n_0402"
			(at -1.022927 -2.155213 90)
			(layer "B.Fab")
			(effects
				(font
					(size 0.7 0.7)
					(thickness 0.15)
				)
				(justify right bottom mirror)
			)
		)
		(property "Datasheet" "https://www.murata.com/products/productdetail?partno=GRM155R61H104KE14%23"
			(at 0 0 90)
			(layer "F.Fab")
			(hide yes)
			(effects
				(font
					(size 1.27 1.27)
					(thickness 0.15)
				)
			)
		)
		(property "Author" "Antmicro"
			(at 273.48 25.04 0)
			(layer "B.Fab")
			(hide yes)
			(effects
				(font
					(size 1 1)
					(thickness 0.15)
				)
				(justify mirror)
			)
		)
		(property "Dielectric" "X5R"
			(at 273.48 25.04 0)
			(layer "B.Fab")
			(hide yes)
			(effects
				(font
					(size 1 1)
					(thickness 0.15)
				)
				(justify mirror)
			)
		)
		(property "License" "Apache-2.0"
			(at 273.48 25.04 0)
			(layer "B.Fab")
			(hide yes)
			(effects
				(font
					(size 1 1)
					(thickness 0.15)
				)
				(justify mirror)
			)
		)
		(property "MPN" "GRM155R61H104KE14D"
			(at 273.48 25.04 0)
			(layer "B.Fab")
			(hide yes)
			(effects
				(font
					(size 1 1)
					(thickness 0.15)
				)
				(justify mirror)
			)
		)
		(property "Manufacturer" "Murata"
			(at 273.48 25.04 0)
			(layer "B.Fab")
			(hide yes)
			(effects
				(font
					(size 1 1)
					(thickness 0.15)
				)
				(justify mirror)
			)
		)
		(property "Public" "False"
			(at 273.48 25.04 0)
			(layer "B.Fab")
			(hide yes)
			(effects
				(font
					(size 1 1)
					(thickness 0.15)
				)
				(justify mirror)
			)
		)
		(property "Val" "100n"
			(at 273.48 25.04 0)
			(layer "B.Fab")
			(hide yes)
			(effects
				(font
					(size 1 1)
					(thickness 0.15)
				)
				(justify mirror)
			)
		)
		(property "Voltage" "50V"
			(at 273.48 25.04 0)
			(layer "B.Fab")
			(hide yes)
			(effects
				(font
					(size 1 1)
					(thickness 0.15)
				)
				(justify mirror)
			)
		)
		(sheetname "KR to SFI #2")
		(sheetfile "kr_sfi.kicad_sch")
		(attr smd)
		(fp_rect
			(start -0.925 0.47)
			(end 0.925 -0.47)
			(stroke
				(width 0.05)
				(type default)
			)
			(fill no)
			(layer "B.CrtYd")
		)
		(fp_line
			(start 0.504 -0.248)
			(end 0.504 0.25)
			(stroke
				(width 0.15)
				(type solid)
			)
			(layer "B.Fab")
		)
		(fp_line
			(start -0.494 -0.248)
			(end 0.504 -0.248)
			(stroke
				(width 0.15)
				(type solid)
			)
			(layer "B.Fab")
		)
		(fp_line
			(start 0.504 0.25)
			(end -0.494 0.25)
			(stroke
				(width 0.15)
				(type solid)
			)
			(layer "B.Fab")
		)
		(fp_line
			(start -0.494 0.25)
			(end -0.494 -0.248)
			(stroke
				(width 0.15)
				(type solid)
			)
			(layer "B.Fab")
		)
		(pad "1" smd roundrect
			(at -0.48 0 90)
			(size 0.59 0.64)
			(layers "B.Cu" "B.Mask" "B.Paste")
			(roundrect_rratio 0.25)
			(net 1 "GND")
			(pintype "passive")
			(teardrops
				(best_length_ratio 0.2)
				(max_length 1)
				(best_width_ratio 0.9)
				(max_width 2)
				(curved_edges yes)
				(filter_ratio 0.9)
				(enabled yes)
				(allow_two_segments yes)
				(prefer_zone_connections yes)
			)
		)
		(pad "2" smd roundrect
			(at 0.48 0 90)
			(size 0.59 0.64)
			(layers "B.Cu" "B.Mask" "B.Paste")
			(roundrect_rratio 0.25)
			(net 78 "+1V8")
			(pintype "passive")
			(teardrops
				(best_length_ratio 0.2)
				(max_length 1)
				(best_width_ratio 0.9)
				(max_width 2)
				(curved_edges yes)
				(filter_ratio 0.9)
				(enabled yes)
				(allow_two_segments yes)
				(prefer_zone_connections yes)
			)
		)
	)
	(footprint "antmicro-footprints:R_0402_1005Metric"
		(layer "B.Cu")
		(at 198.603122 133.106066 -45)
		(descr "Resistor SMD 0402")
		(tags "resistor SMD 0402")
		(property "Reference" "R217"
			(at 1.259224 -1.324371 135)
			(layer "B.SilkS")
			(effects
				(font
					(size 0.7 0.7)
					(thickness 0.15)
				)
				(justify left top mirror)
			)
		)
		(property "Value" "R_0R_0402"
			(at -1.011843 -1.772046 135)
			(layer "B.Fab")
			(effects
				(font
					(size 0.7 0.7)
					(thickness 0.15)
				)
				(justify left top mirror)
			)
		)
		(property "Datasheet" "https://industrial.panasonic.com/cdbs/www-data/pdf/RDA0000/AOA0000C301.pdf"
			(at 0 0 135)
			(layer "B.Fab")
			(hide yes)
			(effects
				(font
					(size 1.27 1.27)
					(thickness 0.15)
				)
				(justify mirror)
			)
		)
		(property "Author" "Antmicro"
			(at 46.64 -320.56 45)
			(layer "B.Fab")
			(hide yes)
			(effects
				(font
					(size 1 1)
					(thickness 0.15)
				)
				(justify mirror)
			)
		)
		(property "Current" "1A"
			(at 46.64 -320.56 45)
			(layer "B.Fab")
			(hide yes)
			(effects
				(font
					(size 1 1)
					(thickness 0.15)
				)
				(justify mirror)
			)
		)
		(property "License" "Apache-2.0"
			(at 46.64 -320.56 45)
			(layer "B.Fab")
			(hide yes)
			(effects
				(font
					(size 1 1)
					(thickness 0.15)
				)
				(justify mirror)
			)
		)
		(property "MPN" "ERJ2GE0R00X"
			(at 46.64 -320.56 45)
			(layer "B.Fab")
			(hide yes)
			(effects
				(font
					(size 1 1)
					(thickness 0.15)
				)
				(justify mirror)
			)
		)
		(property "Manufacturer" "Panasonic"
			(at 46.64 -320.56 45)
			(layer "B.Fab")
			(hide yes)
			(effects
				(font
					(size 1 1)
					(thickness 0.15)
				)
				(justify mirror)
			)
		)
		(property "Public" "False"
			(at 46.64 -320.56 45)
			(layer "B.Fab")
			(hide yes)
			(effects
				(font
					(size 1 1)
					(thickness 0.15)
				)
				(justify mirror)
			)
		)
		(property "Tolerance" ""
			(at 46.64 -320.56 45)
			(layer "B.Fab")
			(hide yes)
			(effects
				(font
					(size 1 1)
					(thickness 0.15)
				)
				(justify mirror)
			)
		)
		(property "Val" "0R"
			(at 46.64 -320.56 45)
			(layer "B.Fab")
			(hide yes)
			(effects
				(font
					(size 1 1)
					(thickness 0.15)
				)
				(justify mirror)
			)
		)
		(sheetname "PCIe redriver")
		(sheetfile "pcie_redriver.kicad_sch")
		(attr smd)
		(fp_poly
			(pts
				(xy -0.925 0.47) (xy 0.925 0.47) (xy 0.925 -0.47) (xy -0.925 -0.47)
			)
			(stroke
				(width 0.05)
				(type default)
			)
			(fill no)
			(layer "B.CrtYd")
		)
		(fp_poly
			(pts
				(xy -0.5 0.25) (xy 0.5 0.25) (xy 0.5 -0.25) (xy -0.5 -0.25)
			)
			(stroke
				(width 0.15)
				(type solid)
			)
			(fill no)
			(layer "B.Fab")
		)
		(pad "1" smd roundrect
			(at -0.48 0 315)
			(size 0.59 0.64)
			(layers "B.Cu" "B.Mask" "B.Paste")
			(roundrect_rratio 0.25)
			(net 632 "Net-(U40-EN_{I2C})")
			(pintype "passive")
			(teardrops
				(best_length_ratio 0.2)
				(max_length 1)
				(best_width_ratio 0.9)
				(max_width 2)
				(curved_edges yes)
				(filter_ratio 0.9)
				(enabled yes)
				(allow_two_segments yes)
				(prefer_zone_connections yes)
			)
		)
		(pad "2" smd roundrect
			(at 0.48 0 315)
			(size 0.59 0.64)
			(layers "B.Cu" "B.Mask" "B.Paste")
			(roundrect_rratio 0.25)
			(net 1 "GND")
			(pintype "passive")
			(teardrops
				(best_length_ratio 0.2)
				(max_length 1)
				(best_width_ratio 0.9)
				(max_width 2)
				(curved_edges yes)
				(filter_ratio 0.9)
				(enabled yes)
				(allow_two_segments yes)
				(prefer_zone_connections yes)
			)
		)
	)
	(footprint "antmicro-footprints:TP_SMD_0.75mm"
		(layer "B.Cu")
		(at 195.45 163.325 -90)
		(property "Reference" "TP32"
			(at -3.525 0.2 90)
			(layer "B.SilkS")
			(effects
				(font
					(size 0.7 0.7)
					(thickness 0.15)
				)
				(justify left top mirror)
			)
		)
		(property "Value" "TP_0.75mm_SMD"
			(at 0 -1.2 90)
			(layer "B.Fab")
			(effects
				(font
					(size 0.7 0.7)
					(thickness 0.15)
				)
				(justify left top mirror)
			)
		)
		(property "Author" "Antmicro"
			(at 364.61 -51.59 0)
			(layer "B.Fab")
			(hide yes)
			(effects
				(font
					(size 1 1)
					(thickness 0.15)
				)
				(justify mirror)
			)
		)
		(property "License" "Apache-2.0"
			(at 364.61 -51.59 0)
			(layer "B.Fab")
			(hide yes)
			(effects
				(font
					(size 1 1)
					(thickness 0.15)
				)
				(justify mirror)
			)
		)
		(property "MPN" ""
			(at 364.61 -51.59 0)
			(layer "B.Fab")
			(hide yes)
			(effects
				(font
					(size 1 1)
					(thickness 0.15)
				)
				(justify mirror)
			)
		)
		(property "Manufacturer" ""
			(at 364.61 -51.59 0)
			(layer "B.Fab")
			(hide yes)
			(effects
				(font
					(size 1 1)
					(thickness 0.15)
				)
				(justify mirror)
			)
		)
		(property "Public" "False"
			(at 364.61 -51.59 0)
			(layer "B.Fab")
			(hide yes)
			(effects
				(font
					(size 1 1)
					(thickness 0.15)
				)
				(justify mirror)
			)
		)
		(sheetname "Com Express 7 MGMT")
		(sheetfile "com_express_7_mgmt.kicad_sch")
		(attr exclude_from_pos_files exclude_from_bom)
		(fp_circle
			(center 0 0)
			(end 0.475 0)
			(stroke
				(width 0.05)
				(type default)
			)
			(fill no)
			(layer "B.CrtYd")
		)
		(pad "1" smd circle
			(at 0 0 270)
			(size 0.75 0.75)
			(layers "B.Cu" "B.Mask")
			(net 379 "Net-(J12D-~{ESPI_EN})")
			(pinfunction "1")
			(pintype "passive")
			(teardrops
				(best_length_ratio 0.4)
				(max_length 1)
				(best_width_ratio 0.9)
				(max_width 2)
				(curved_edges yes)
				(filter_ratio 0.9)
				(enabled yes)
				(allow_two_segments yes)
				(prefer_zone_connections yes)
			)
		)
	)
	(footprint "antmicro-footprints:C_0402_1005Metric"
		(layer "B.Cu")
		(at 198.12936 140.127637 135)
		(descr "Capacitor SMD 0402")
		(tags "capacitor SMD 0402")
		(property "Reference" "C131"
			(at -3.530586 -0.359976 135)
			(layer "B.SilkS")
			(effects
				(font
					(size 0.7 0.7)
					(thickness 0.15)
				)
				(justify right bottom mirror)
			)
		)
		(property "Value" "C_220n_0402"
			(at -1.022927 -2.155213 135)
			(layer "B.Fab")
			(effects
				(font
					(size 0.7 0.7)
					(thickness 0.15)
				)
				(justify right bottom mirror)
			)
		)
		(property "Datasheet" "https://www.yageo.com/en/Chart/Download/pdf/CC0402KRX5R6BB224"
			(at 0 0 135)
			(layer "F.Fab")
			(hide yes)
			(effects
				(font
					(size 1.27 1.27)
					(thickness 0.15)
				)
			)
		)
		(property "Author" "Antmicro"
			(at 337.3 -40.5 45)
			(layer "B.Fab")
			(hide yes)
			(effects
				(font
					(size 1 1)
					(thickness 0.15)
				)
				(justify mirror)
			)
		)
		(property "Dielectric" ""
			(at 337.3 -40.5 45)
			(layer "B.Fab")
			(hide yes)
			(effects
				(font
					(size 1 1)
					(thickness 0.15)
				)
				(justify mirror)
			)
		)
		(property "License" "Apache-2.0"
			(at 337.3 -40.5 45)
			(layer "B.Fab")
			(hide yes)
			(effects
				(font
					(size 1 1)
					(thickness 0.15)
				)
				(justify mirror)
			)
		)
		(property "MPN" "CC0402KRX5R6BB224"
			(at 337.3 -40.5 45)
			(layer "B.Fab")
			(hide yes)
			(effects
				(font
					(size 1 1)
					(thickness 0.15)
				)
				(justify mirror)
			)
		)
		(property "Manufacturer" "YAGEO"
			(at 337.3 -40.5 45)
			(layer "B.Fab")
			(hide yes)
			(effects
				(font
					(size 1 1)
					(thickness 0.15)
				)
				(justify mirror)
			)
		)
		(property "Public" "False"
			(at 337.3 -40.5 45)
			(layer "B.Fab")
			(hide yes)
			(effects
				(font
					(size 1 1)
					(thickness 0.15)
				)
				(justify mirror)
			)
		)
		(property "Val" "220n"
			(at 337.3 -40.5 45)
			(layer "B.Fab")
			(hide yes)
			(effects
				(font
					(size 1 1)
					(thickness 0.15)
				)
				(justify mirror)
			)
		)
		(property "Voltage" ""
			(at 337.3 -40.5 45)
			(layer "B.Fab")
			(hide yes)
			(effects
				(font
					(size 1 1)
					(thickness 0.15)
				)
				(justify mirror)
			)
		)
		(sheetname "PCIe redriver")
		(sheetfile "pcie_redriver.kicad_sch")
		(attr smd)
		(fp_poly
			(pts
				(xy -0.925 0.47) (xy 0.925 0.47) (xy 0.925 -0.47) (xy -0.925 -0.47)
			)
			(stroke
				(width 0.05)
				(type default)
			)
			(fill no)
			(layer "B.CrtYd")
		)
		(fp_line
			(start 0.504 -0.248)
			(end 0.504 0.25)
			(stroke
				(width 0.15)
				(type solid)
			)
			(layer "B.Fab")
		)
		(fp_line
			(start 0.504 0.25)
			(end -0.494 0.25)
			(stroke
				(width 0.15)
				(type solid)
			)
			(layer "B.Fab")
		)
		(fp_line
			(start -0.494 -0.248)
			(end 0.504 -0.248)
			(stroke
				(width 0.15)
				(type solid)
			)
			(layer "B.Fab")
		)
		(fp_line
			(start -0.494 0.25)
			(end -0.494 -0.248)
			(stroke
				(width 0.15)
				(type solid)
			)
			(layer "B.Fab")
		)
		(pad "1" smd roundrect
			(at -0.48 0 135)
			(size 0.59 0.64)
			(layers "B.Cu" "B.Mask" "B.Paste")
			(roundrect_rratio 0.25)
			(net 218 "/Com Express 7 Interfaces/PCIe_{B1x4}.RX1+")
			(pintype "passive")
			(teardrops
				(best_length_ratio 0.2)
				(max_length 1)
				(best_width_ratio 0.9)
				(max_width 2)
				(curved_edges yes)
				(filter_ratio 0.9)
				(enabled yes)
				(allow_two_segments yes)
				(prefer_zone_connections yes)
			)
		)
		(pad "2" smd roundrect
			(at 0.48 0 135)
			(size 0.59 0.64)
			(layers "B.Cu" "B.Mask" "B.Paste")
			(roundrect_rratio 0.25)
			(net 958 "/PCIe redriver/PCIe_{I}_C.RX1+")
			(pintype "passive")
			(teardrops
				(best_length_ratio 0.2)
				(max_length 1)
				(best_width_ratio 0.9)
				(max_width 2)
				(curved_edges yes)
				(filter_ratio 0.9)
				(enabled yes)
				(allow_two_segments yes)
				(prefer_zone_connections yes)
			)
		)
	)
	(footprint "antmicro-footprints:TP_SMD_0.75mm"
		(layer "B.Cu")
		(at 214.38 124.85 -90)
		(property "Reference" "TP44"
			(at -3.09 -0.52 90)
			(layer "B.SilkS")
			(effects
				(font
					(size 0.7 0.7)
					(thickness 0.15)
				)
				(justify left bottom mirror)
			)
		)
		(property "Value" "TP_0.75mm_SMD"
			(at 0 -1.2 90)
			(layer "B.Fab")
			(effects
				(font
					(size 0.7 0.7)
					(thickness 0.15)
				)
				(justify left bottom mirror)
			)
		)
		(property "Author" "Antmicro"
			(at 89.53 339.23 0)
			(layer "B.Fab")
			(hide yes)
			(effects
				(font
					(size 1 1)
					(thickness 0.15)
				)
				(justify mirror)
			)
		)
		(property "License" "Apache-2.0"
			(at 89.53 339.23 0)
			(layer "B.Fab")
			(hide yes)
			(effects
				(font
					(size 1 1)
					(thickness 0.15)
				)
				(justify mirror)
			)
		)
		(property "MPN" ""
			(at 89.53 339.23 0)
			(layer "B.Fab")
			(hide yes)
			(effects
				(font
					(size 1 1)
					(thickness 0.15)
				)
				(justify mirror)
			)
		)
		(property "Manufacturer" ""
			(at 89.53 339.23 0)
			(layer "B.Fab")
			(hide yes)
			(effects
				(font
					(size 1 1)
					(thickness 0.15)
				)
				(justify mirror)
			)
		)
		(property "Public" "False"
			(at 89.53 339.23 0)
			(layer "B.Fab")
			(hide yes)
			(effects
				(font
					(size 1 1)
					(thickness 0.15)
				)
				(justify mirror)
			)
		)
		(sheetname "PCIe misc")
		(sheetfile "pcie_misc.kicad_sch")
		(attr exclude_from_pos_files exclude_from_bom)
		(fp_circle
			(center 0 0)
			(end 0.475 0)
			(stroke
				(width 0.05)
				(type default)
			)
			(fill no)
			(layer "B.CrtYd")
		)
		(pad "1" smd circle
			(at 0 0 270)
			(size 0.75 0.75)
			(layers "B.Cu" "B.Mask")
			(net 709 "Net-(U37-SCLK)")
			(pinfunction "1")
			(pintype "passive")
			(teardrops
				(best_length_ratio 0.4)
				(max_length 1)
				(best_width_ratio 0.9)
				(max_width 2)
				(curved_edges yes)
				(filter_ratio 0.9)
				(enabled yes)
				(allow_two_segments yes)
				(prefer_zone_connections yes)
			)
		)
	)
	(footprint "antmicro-footprints:R_0402_1005Metric"
		(layer "B.Cu")
		(at 126.09 139.06)
		(descr "Resistor SMD 0402")
		(tags "resistor SMD 0402")
		(property "Reference" "R299"
			(at -3.64 1.2 0)
			(layer "B.SilkS")
			(effects
				(font
					(size 0.7 0.7)
					(thickness 0.15)
				)
				(justify right bottom mirror)
			)
		)
		(property "Value" "R_10k_0402"
			(at -1.011843 -1.772047 0)
			(layer "B.Fab")
			(effects
				(font
					(size 0.7 0.7)
					(thickness 0.15)
				)
				(justify right bottom mirror)
			)
		)
		(property "Datasheet" "https://www.bourns.com/docs/product-datasheets/cr.pdf"
			(at 0 0 0)
			(layer "F.Fab")
			(hide yes)
			(effects
				(font
					(size 1.27 1.27)
					(thickness 0.15)
				)
			)
		)
		(property "Author" "Antmicro"
			(at 0 0 0)
			(layer "B.Fab")
			(hide yes)
			(effects
				(font
					(size 1 1)
					(thickness 0.15)
				)
				(justify mirror)
			)
		)
		(property "License" "Apache-2.0"
			(at 0 0 0)
			(layer "B.Fab")
			(hide yes)
			(effects
				(font
					(size 1 1)
					(thickness 0.15)
				)
				(justify mirror)
			)
		)
		(property "MPN" "CR0402-FX-1002GLF"
			(at 0 0 0)
			(layer "B.Fab")
			(hide yes)
			(effects
				(font
					(size 1 1)
					(thickness 0.15)
				)
				(justify mirror)
			)
		)
		(property "Manufacturer" "Bourns"
			(at 0 0 0)
			(layer "B.Fab")
			(hide yes)
			(effects
				(font
					(size 1 1)
					(thickness 0.15)
				)
				(justify mirror)
			)
		)
		(property "Public" "False"
			(at 0 0 0)
			(layer "B.Fab")
			(hide yes)
			(effects
				(font
					(size 1 1)
					(thickness 0.15)
				)
				(justify mirror)
			)
		)
		(property "Tolerance" "1%"
			(at 0 0 0)
			(layer "B.Fab")
			(hide yes)
			(effects
				(font
					(size 1 1)
					(thickness 0.15)
				)
				(justify mirror)
			)
		)
		(property "Val" "10k"
			(at 0 0 0)
			(layer "B.Fab")
			(hide yes)
			(effects
				(font
					(size 1 1)
					(thickness 0.15)
				)
				(justify mirror)
			)
		)
		(sheetname "KR to SFI #2")
		(sheetfile "kr_sfi.kicad_sch")
		(attr smd)
		(fp_rect
			(start -0.925 0.47)
			(end 0.925 -0.47)
			(stroke
				(width 0.05)
				(type default)
			)
			(fill no)
			(layer "B.CrtYd")
		)
		(fp_rect
			(start -0.5 0.25)
			(end 0.5 -0.25)
			(stroke
				(width 0.15)
				(type solid)
			)
			(fill no)
			(layer "B.Fab")
		)
		(pad "1" smd roundrect
			(at -0.48 0)
			(size 0.59 0.64)
			(layers "B.Cu" "B.Mask" "B.Paste")
			(roundrect_rratio 0.25)
			(net 1 "GND")
			(pintype "passive")
			(teardrops
				(best_length_ratio 0.2)
				(max_length 1)
				(best_width_ratio 0.9)
				(max_width 2)
				(curved_edges yes)
				(filter_ratio 0.9)
				(enabled yes)
				(allow_two_segments yes)
				(prefer_zone_connections yes)
			)
		)
		(pad "2" smd roundrect
			(at 0.48 0)
			(size 0.59 0.64)
			(layers "B.Cu" "B.Mask" "B.Paste")
			(roundrect_rratio 0.25)
			(net 679 "Net-(U45C-PRTAD2)")
			(pintype "passive")
			(teardrops
				(best_length_ratio 0.2)
				(max_length 1)
				(best_width_ratio 0.9)
				(max_width 2)
				(curved_edges yes)
				(filter_ratio 0.9)
				(enabled yes)
				(allow_two_segments yes)
				(prefer_zone_connections yes)
			)
		)
	)
	(footprint "antmicro-footprints:TP_SMD_0.75mm"
		(layer "B.Cu")
		(at 177.35 162.55)
		(property "Reference" "TP30"
			(at 0.65 -0.3 180)
			(layer "B.SilkS")
			(effects
				(font
					(size 0.7 0.7)
					(thickness 0.15)
				)
				(justify right top mirror)
			)
		)
		(property "Value" "TP_0.75mm_SMD"
			(at 3.225 -53.865 0)
			(layer "B.Fab")
			(hide yes)
			(effects
				(font
					(size 0.7 0.7)
					(thickness 0.15)
				)
				(justify right top mirror)
			)
		)
		(property "Author" "Antmicro"
			(at 452.4 308.02 0)
			(layer "B.Fab")
			(hide yes)
			(effects
				(font
					(size 1 1)
					(thickness 0.15)
				)
				(justify mirror)
			)
		)
		(property "License" "Apache-2.0"
			(at 452.4 308.02 0)
			(layer "B.Fab")
			(hide yes)
			(effects
				(font
					(size 1 1)
					(thickness 0.15)
				)
				(justify mirror)
			)
		)
		(property "MPN" ""
			(at 452.4 308.02 0)
			(layer "B.Fab")
			(hide yes)
			(effects
				(font
					(size 1 1)
					(thickness 0.15)
				)
				(justify mirror)
			)
		)
		(property "Manufacturer" ""
			(at 452.4 308.02 0)
			(layer "B.Fab")
			(hide yes)
			(effects
				(font
					(size 1 1)
					(thickness 0.15)
				)
				(justify mirror)
			)
		)
		(property "Public" "False"
			(at 452.4 308.02 0)
			(layer "B.Fab")
			(hide yes)
			(effects
				(font
					(size 1 1)
					(thickness 0.15)
				)
				(justify mirror)
			)
		)
		(sheetname "Com Express 7 MGMT")
		(sheetfile "com_express_7_mgmt.kicad_sch")
		(attr exclude_from_pos_files exclude_from_bom)
		(fp_circle
			(center 0 0)
			(end 0.475 0)
			(stroke
				(width 0.05)
				(type default)
			)
			(fill no)
			(layer "B.CrtYd")
		)
		(pad "1" smd circle
			(at 0 0)
			(size 0.75 0.75)
			(layers "B.Cu" "B.Mask")
			(net 354 "Net-(J12D-~{LPC_DRQ1}{slash}~{ESPI_ALERT1})")
			(pinfunction "1")
			(pintype "passive")
			(teardrops
				(best_length_ratio 0.4)
				(max_length 1)
				(best_width_ratio 0.9)
				(max_width 2)
				(curved_edges yes)
				(filter_ratio 0.9)
				(enabled yes)
				(allow_two_segments yes)
				(prefer_zone_connections yes)
			)
		)
	)
	(footprint "antmicro-footprints:SOT-23-3"
		(layer "B.Cu")
		(at 101.05 71.91 90)
		(property "Reference" "Q7"
			(at 0.95 0.55 180)
			(layer "B.SilkS")
			(effects
				(font
					(size 0.7 0.7)
					(thickness 0.15)
				)
				(justify right bottom mirror)
			)
		)
		(property "Value" "BSS138-7-F"
			(at -1.9 -2.7 90)
			(layer "B.Fab")
			(effects
				(font
					(size 0.7 0.7)
					(thickness 0.15)
				)
				(justify right bottom mirror)
			)
		)
		(property "Datasheet" "https://www.diodes.com/assets/Datasheets/ds30144.pdf"
			(at 0 0 90)
			(layer "F.Fab")
			(hide yes)
			(effects
				(font
					(size 1.27 1.27)
					(thickness 0.15)
				)
			)
		)
		(property "Author" "Antmicro"
			(at 172.96 -29.14 0)
			(layer "B.Fab")
			(hide yes)
			(effects
				(font
					(size 1 1)
					(thickness 0.15)
				)
				(justify mirror)
			)
		)
		(property "License" "Apache-2.0"
			(at 172.96 -29.14 0)
			(layer "B.Fab")
			(hide yes)
			(effects
				(font
					(size 1 1)
					(thickness 0.15)
				)
				(justify mirror)
			)
		)
		(property "MPN" "BSS138-7-F"
			(at 172.96 -29.14 0)
			(layer "B.Fab")
			(hide yes)
			(effects
				(font
					(size 1 1)
					(thickness 0.15)
				)
				(justify mirror)
			)
		)
		(property "Manufacturer" "Diodes Incorporated"
			(at 172.96 -29.14 0)
			(layer "B.Fab")
			(hide yes)
			(effects
				(font
					(size 1 1)
					(thickness 0.15)
				)
				(justify mirror)
			)
		)
		(sheetname "Misc")
		(sheetfile "misc.kicad_sch")
		(attr smd)
		(fp_line
			(start 0.7 -1.5)
			(end 0.7 -0.4)
			(stroke
				(width 0.15)
				(type solid)
			)
			(layer "B.SilkS")
		)
		(fp_line
			(start -0.7 -1.5)
			(end 0.7 -1.5)
			(stroke
				(width 0.15)
				(type solid)
			)
			(layer "B.SilkS")
		)
		(fp_line
			(start -0.7 -1.35)
			(end -0.7 -1.5)
			(stroke
				(width 0.15)
				(type solid)
			)
			(layer "B.SilkS")
		)
		(fp_line
			(start -0.85 1.35)
			(end -1.45 1.35)
			(stroke
				(width 0.15)
				(type solid)
			)
			(layer "B.SilkS")
		)
		(fp_line
			(start 0.7 1.5)
			(end 0.7 0.4)
			(stroke
				(width 0.15)
				(type solid)
			)
			(layer "B.SilkS")
		)
		(fp_line
			(start -0.7 1.5)
			(end -0.85 1.35)
			(stroke
				(width 0.15)
				(type solid)
			)
			(layer "B.SilkS")
		)
		(fp_line
			(start -0.7 1.5)
			(end 0.7 1.5)
			(stroke
				(width 0.15)
				(type solid)
			)
			(layer "B.SilkS")
		)
		(fp_line
			(start 0.85 -1.65)
			(end 0.85 -0.45)
			(stroke
				(width 0.05)
				(type solid)
			)
			(layer "B.CrtYd")
		)
		(fp_line
			(start -0.85 -1.65)
			(end 0.85 -1.65)
			(stroke
				(width 0.05)
				(type solid)
			)
			(layer "B.CrtYd")
		)
		(fp_line
			(start -0.85 -1.4)
			(end -0.85 -1.65)
			(stroke
				(width 0.05)
				(type solid)
			)
			(layer "B.CrtYd")
		)
		(fp_line
			(start -1.75 -1.4)
			(end -0.85 -1.4)
			(stroke
				(width 0.05)
				(type solid)
			)
			(layer "B.CrtYd")
		)
		(fp_line
			(start -0.85 -0.5)
			(end -1.75 -0.5)
			(stroke
				(width 0.05)
				(type solid)
			)
			(layer "B.CrtYd")
		)
		(fp_line
			(start -1.75 -0.5)
			(end -1.75 -1.4)
			(stroke
				(width 0.05)
				(type solid)
			)
			(layer "B.CrtYd")
		)
		(fp_line
			(start 1.75 -0.45)
			(end 1.75 0.45)
			(stroke
				(width 0.05)
				(type solid)
			)
			(layer "B.CrtYd")
		)
		(fp_line
			(start 0.85 -0.45)
			(end 1.75 -0.45)
			(stroke
				(width 0.05)
				(type solid)
			)
			(layer "B.CrtYd")
		)
		(fp_line
			(start 1.75 0.45)
			(end 0.825 0.45)
			(stroke
				(width 0.05)
				(type solid)
			)
			(layer "B.CrtYd")
		)
		(fp_line
			(start 0.825 0.45)
			(end 0.825 1.6)
			(stroke
				(width 0.05)
				(type solid)
			)
			(layer "B.CrtYd")
		)
		(fp_line
			(start -0.85 0.5)
			(end -0.85 -0.5)
			(stroke
				(width 0.05)
				(type solid)
			)
			(layer "B.CrtYd")
		)
		(fp_line
			(start -1.75 0.5)
			(end -0.85 0.5)
			(stroke
				(width 0.05)
				(type solid)
			)
			(layer "B.CrtYd")
		)
		(fp_line
			(start -0.9 1.4)
			(end -0.9 1.6)
			(stroke
				(width 0.05)
				(type solid)
			)
			(layer "B.CrtYd")
		)
		(fp_line
			(start -1.75 1.4)
			(end -1.75 0.5)
			(stroke
				(width 0.05)
				(type solid)
			)
			(layer "B.CrtYd")
		)
		(fp_line
			(start -1.75 1.4)
			(end -0.9 1.4)
			(stroke
				(width 0.05)
				(type solid)
			)
			(layer "B.CrtYd")
		)
		(fp_line
			(start 0.825 1.6)
			(end -0.9 1.6)
			(stroke
				(width 0.05)
				(type solid)
			)
			(layer "B.CrtYd")
		)
		(fp_line
			(start -0.712 -1.523)
			(end -0.712 1.325)
			(stroke
				(width 0.15)
				(type solid)
			)
			(layer "B.Fab")
		)
		(fp_line
			(start 0.688 -1.519)
			(end -0.712 -1.519)
			(stroke
				(width 0.15)
				(type solid)
			)
			(layer "B.Fab")
		)
		(fp_line
			(start -0.712 1.325)
			(end -0.437 1.526)
			(stroke
				(width 0.15)
				(type solid)
			)
			(layer "B.Fab")
		)
		(fp_line
			(start 0.688 1.52)
			(end 0.688 -1.519)
			(stroke
				(width 0.15)
				(type solid)
			)
			(layer "B.Fab")
		)
		(fp_line
			(start 0.688 1.526)
			(end -0.437 1.526)
			(stroke
				(width 0.15)
				(type solid)
			)
			(layer "B.Fab")
		)
		(pad "1" smd roundrect
			(at -1.1 0.951 90)
			(size 1 0.6)
			(layers "B.Cu" "B.Mask" "B.Paste")
			(roundrect_rratio 0.15)
			(net 365 "/Com Express 7 MGMT/PWR_OK")
			(pinfunction "G")
			(pintype "bidirectional")
			(teardrops
				(best_length_ratio 0.2)
				(max_length 1)
				(best_width_ratio 0.9)
				(max_width 2)
				(curved_edges yes)
				(filter_ratio 0.9)
				(enabled yes)
				(allow_two_segments yes)
				(prefer_zone_connections yes)
			)
		)
		(pad "2" smd roundrect
			(at -1.1 -0.949 90)
			(size 1 0.6)
			(layers "B.Cu" "B.Mask" "B.Paste")
			(roundrect_rratio 0.15)
			(net 1 "GND")
			(pinfunction "S")
			(pintype "bidirectional")
			(teardrops
				(best_length_ratio 0.2)
				(max_length 1)
				(best_width_ratio 0.9)
				(max_width 2)
				(curved_edges yes)
				(filter_ratio 0.9)
				(enabled yes)
				(allow_two_segments yes)
				(prefer_zone_connections yes)
			)
		)
		(pad "3" smd roundrect
			(at 1.1 0.0005 90)
			(size 1 0.6)
			(layers "B.Cu" "B.Mask" "B.Paste")
			(roundrect_rratio 0.15)
			(net 539 "/Misc/~{PWR_OK}")
			(pinfunction "D")
			(pintype "bidirectional")
			(teardrops
				(best_length_ratio 0.2)
				(max_length 1)
				(best_width_ratio 0.9)
				(max_width 2)
				(curved_edges yes)
				(filter_ratio 0.9)
				(enabled yes)
				(allow_two_segments yes)
				(prefer_zone_connections yes)
			)
		)
	)
	(footprint "antmicro-footprints:C_0603_1608Metric"
		(layer "B.Cu")
		(at 303.9 79.12 -90)
		(descr "Capacitor SMD 0603")
		(tags "capacitor 0603")
		(property "Reference" "C78"
			(at -3.36 -0.45 90)
			(layer "B.SilkS")
			(effects
				(font
					(size 0.7 0.7)
					(thickness 0.15)
				)
				(justify left bottom mirror)
			)
		)
		(property "Value" "C_22u_16V_0603"
			(at -1.42757 -1.770288 90)
			(layer "B.Fab")
			(effects
				(font
					(size 0.7 0.7)
					(thickness 0.15)
				)
				(justify left bottom mirror)
			)
		)
		(property "Datasheet" "https://product.samsungsem.com/mlcc/CL10A226MO7JZN.do"
			(at 0 0 270)
			(layer "F.Fab")
			(hide yes)
			(effects
				(font
					(size 1.27 1.27)
					(thickness 0.15)
				)
			)
		)
		(property "Author" "Antmicro"
			(at 224.78 383.02 0)
			(layer "B.Fab")
			(hide yes)
			(effects
				(font
					(size 1 1)
					(thickness 0.15)
				)
				(justify mirror)
			)
		)
		(property "Dielectric" ""
			(at 224.78 383.02 0)
			(layer "B.Fab")
			(hide yes)
			(effects
				(font
					(size 1 1)
					(thickness 0.15)
				)
				(justify mirror)
			)
		)
		(property "License" "Apache-2.0"
			(at 224.78 383.02 0)
			(layer "B.Fab")
			(hide yes)
			(effects
				(font
					(size 1 1)
					(thickness 0.15)
				)
				(justify mirror)
			)
		)
		(property "MPN" "CL10A226MO7JZNC"
			(at 224.78 383.02 0)
			(layer "B.Fab")
			(hide yes)
			(effects
				(font
					(size 1 1)
					(thickness 0.15)
				)
				(justify mirror)
			)
		)
		(property "Manufacturer" "Samsung Electro-Mechanics"
			(at 224.78 383.02 0)
			(layer "B.Fab")
			(hide yes)
			(effects
				(font
					(size 1 1)
					(thickness 0.15)
				)
				(justify mirror)
			)
		)
		(property "Public" "False"
			(at 224.78 383.02 0)
			(layer "B.Fab")
			(hide yes)
			(effects
				(font
					(size 1 1)
					(thickness 0.15)
				)
				(justify mirror)
			)
		)
		(property "Val" "22u"
			(at 224.78 383.02 0)
			(layer "B.Fab")
			(hide yes)
			(effects
				(font
					(size 1 1)
					(thickness 0.15)
				)
				(justify mirror)
			)
		)
		(property "Voltage" "16V"
			(at 224.78 383.02 0)
			(layer "B.Fab")
			(hide yes)
			(effects
				(font
					(size 1 1)
					(thickness 0.15)
				)
				(justify mirror)
			)
		)
		(sheetname "M.2 key M #2")
		(sheetfile "m2keym.kicad_sch")
		(attr smd)
		(fp_line
			(start 0.15 0.4)
			(end -0.15 0.4)
			(stroke
				(width 0.15)
				(type solid)
			)
			(layer "B.SilkS")
		)
		(fp_line
			(start 0.15 -0.4)
			(end -0.15 -0.4)
			(stroke
				(width 0.15)
				(type solid)
			)
			(layer "B.SilkS")
		)
		(fp_rect
			(start -1.25 0.65)
			(end 1.25 -0.65)
			(stroke
				(width 0.05)
				(type solid)
			)
			(fill no)
			(layer "B.CrtYd")
		)
		(fp_rect
			(start -0.8 0.4)
			(end 0.8 -0.4)
			(stroke
				(width 0.15)
				(type solid)
			)
			(fill no)
			(layer "B.Fab")
		)
		(pad "1" smd roundrect
			(at -0.7 0 270)
			(size 0.8 1)
			(layers "B.Cu" "B.Mask" "B.Paste")
			(roundrect_rratio 0.2)
			(net 1 "GND")
			(pintype "passive")
			(teardrops
				(best_length_ratio 0.2)
				(max_length 1)
				(best_width_ratio 0.9)
				(max_width 2)
				(curved_edges yes)
				(filter_ratio 0.9)
				(enabled yes)
				(allow_two_segments yes)
				(prefer_zone_connections yes)
			)
		)
		(pad "2" smd roundrect
			(at 0.7 0 270)
			(size 0.8 1)
			(layers "B.Cu" "B.Mask" "B.Paste")
			(roundrect_rratio 0.2)
			(net 970 "/M.2 key M #2/M2_3V3")
			(pintype "passive")
			(teardrops
				(best_length_ratio 0.2)
				(max_length 1)
				(best_width_ratio 0.9)
				(max_width 2)
				(curved_edges yes)
				(filter_ratio 0.9)
				(enabled yes)
				(allow_two_segments yes)
				(prefer_zone_connections yes)
			)
		)
	)
	(footprint "antmicro-footprints:R_0402_1005Metric"
		(layer "B.Cu")
		(at 157.9 141.36)
		(descr "Resistor SMD 0402")
		(tags "resistor SMD 0402")
		(property "Reference" "R260"
			(at 0.85 0.45 0)
			(layer "B.SilkS")
			(effects
				(font
					(size 0.7 0.7)
					(thickness 0.15)
				)
				(justify right bottom mirror)
			)
		)
		(property "Value" "R_10k_0402"
			(at -1.011843 -1.772047 0)
			(layer "B.Fab")
			(effects
				(font
					(size 0.7 0.7)
					(thickness 0.15)
				)
				(justify right bottom mirror)
			)
		)
		(property "Datasheet" "https://www.bourns.com/docs/product-datasheets/cr.pdf"
			(at 0 0 0)
			(layer "F.Fab")
			(hide yes)
			(effects
				(font
					(size 1.27 1.27)
					(thickness 0.15)
				)
			)
		)
		(property "Author" "Antmicro"
			(at 0 0 0)
			(layer "B.Fab")
			(hide yes)
			(effects
				(font
					(size 1 1)
					(thickness 0.15)
				)
				(justify mirror)
			)
		)
		(property "License" "Apache-2.0"
			(at 0 0 0)
			(layer "B.Fab")
			(hide yes)
			(effects
				(font
					(size 1 1)
					(thickness 0.15)
				)
				(justify mirror)
			)
		)
		(property "MPN" "CR0402-FX-1002GLF"
			(at 0 0 0)
			(layer "B.Fab")
			(hide yes)
			(effects
				(font
					(size 1 1)
					(thickness 0.15)
				)
				(justify mirror)
			)
		)
		(property "Manufacturer" "Bourns"
			(at 0 0 0)
			(layer "B.Fab")
			(hide yes)
			(effects
				(font
					(size 1 1)
					(thickness 0.15)
				)
				(justify mirror)
			)
		)
		(property "Public" "False"
			(at 0 0 0)
			(layer "B.Fab")
			(hide yes)
			(effects
				(font
					(size 1 1)
					(thickness 0.15)
				)
				(justify mirror)
			)
		)
		(property "Tolerance" "1%"
			(at 0 0 0)
			(layer "B.Fab")
			(hide yes)
			(effects
				(font
					(size 1 1)
					(thickness 0.15)
				)
				(justify mirror)
			)
		)
		(property "Val" "10k"
			(at 0 0 0)
			(layer "B.Fab")
			(hide yes)
			(effects
				(font
					(size 1 1)
					(thickness 0.15)
				)
				(justify mirror)
			)
		)
		(sheetname "KR to SFI #1")
		(sheetfile "kr_sfi.kicad_sch")
		(attr smd dnp)
		(fp_rect
			(start -0.925 0.47)
			(end 0.925 -0.47)
			(stroke
				(width 0.05)
				(type default)
			)
			(fill no)
			(layer "B.CrtYd")
		)
		(fp_rect
			(start -0.5 0.25)
			(end 0.5 -0.25)
			(stroke
				(width 0.15)
				(type solid)
			)
			(fill no)
			(layer "B.Fab")
		)
		(pad "1" smd roundrect
			(at -0.48 0)
			(size 0.59 0.64)
			(layers "B.Cu" "B.Mask" "B.Paste")
			(roundrect_rratio 0.25)
			(net 655 "Net-(U43C-PRTAD0)")
			(pintype "passive")
			(teardrops
				(best_length_ratio 0.2)
				(max_length 1)
				(best_width_ratio 0.9)
				(max_width 2)
				(curved_edges yes)
				(filter_ratio 0.9)
				(enabled yes)
				(allow_two_segments yes)
				(prefer_zone_connections yes)
			)
		)
		(pad "2" smd roundrect
			(at 0.48 0)
			(size 0.59 0.64)
			(layers "B.Cu" "B.Mask" "B.Paste")
			(roundrect_rratio 0.25)
			(net 78 "+1V8")
			(pintype "passive")
			(teardrops
				(best_length_ratio 0.2)
				(max_length 1)
				(best_width_ratio 0.9)
				(max_width 2)
				(curved_edges yes)
				(filter_ratio 0.9)
				(enabled yes)
				(allow_two_segments yes)
				(prefer_zone_connections yes)
			)
		)
	)
	(footprint "antmicro-footprints:TP_SMD_0.75mm"
		(layer "B.Cu")
		(at 185.05 165.95 180)
		(property "Reference" "TP31"
			(at -0.45 3.2 90)
			(layer "B.SilkS")
			(effects
				(font
					(size 0.7 0.7)
					(thickness 0.15)
				)
				(justify left bottom mirror)
			)
		)
		(property "Value" "TP_0.75mm_SMD"
			(at 3.225 -53.865 0)
			(layer "B.Fab")
			(hide yes)
			(effects
				(font
					(size 0.7 0.7)
					(thickness 0.15)
				)
				(justify left bottom mirror)
			)
		)
		(property "Author" "Antmicro"
			(at 447.85 306.77 0)
			(layer "B.Fab")
			(hide yes)
			(effects
				(font
					(size 1 1)
					(thickness 0.15)
				)
				(justify mirror)
			)
		)
		(property "License" "Apache-2.0"
			(at 447.85 306.77 0)
			(layer "B.Fab")
			(hide yes)
			(effects
				(font
					(size 1 1)
					(thickness 0.15)
				)
				(justify mirror)
			)
		)
		(property "MPN" ""
			(at 447.85 306.77 0)
			(layer "B.Fab")
			(hide yes)
			(effects
				(font
					(size 1 1)
					(thickness 0.15)
				)
				(justify mirror)
			)
		)
		(property "Manufacturer" ""
			(at 447.85 306.77 0)
			(layer "B.Fab")
			(hide yes)
			(effects
				(font
					(size 1 1)
					(thickness 0.15)
				)
				(justify mirror)
			)
		)
		(property "Public" "False"
			(at 447.85 306.77 0)
			(layer "B.Fab")
			(hide yes)
			(effects
				(font
					(size 1 1)
					(thickness 0.15)
				)
				(justify mirror)
			)
		)
		(sheetname "Com Express 7 MGMT")
		(sheetfile "com_express_7_mgmt.kicad_sch")
		(attr exclude_from_pos_files exclude_from_bom)
		(fp_circle
			(center 0 0)
			(end 0.475 0)
			(stroke
				(width 0.05)
				(type default)
			)
			(fill no)
			(layer "B.CrtYd")
		)
		(pad "1" smd circle
			(at 0 0 180)
			(size 0.75 0.75)
			(layers "B.Cu" "B.Mask")
			(net 362 "Net-(J12D-~{SUS_STAT}{slash}~{ESPI_RESET})")
			(pinfunction "1")
			(pintype "passive")
			(teardrops
				(best_length_ratio 0.4)
				(max_length 1)
				(best_width_ratio 0.9)
				(max_width 2)
				(curved_edges yes)
				(filter_ratio 0.9)
				(enabled yes)
				(allow_two_segments yes)
				(prefer_zone_connections yes)
			)
		)
	)
	(footprint "antmicro-footprints:R_0402_1005Metric"
		(layer "B.Cu")
		(at 118.48 169.96)
		(descr "Resistor SMD 0402")
		(tags "resistor SMD 0402")
		(property "Reference" "R61"
			(at -1.13 1.35 0)
			(layer "B.SilkS")
			(effects
				(font
					(size 0.7 0.7)
					(thickness 0.15)
				)
				(justify right bottom mirror)
			)
		)
		(property "Value" "R_330R_0402"
			(at -1.011843 -1.772047 0)
			(layer "B.Fab")
			(effects
				(font
					(size 0.7 0.7)
					(thickness 0.15)
				)
				(justify right bottom mirror)
			)
		)
		(property "Datasheet" "https://www.bourns.com/docs/product-datasheets/cr.pdf"
			(at 0 0 0)
			(layer "F.Fab")
			(hide yes)
			(effects
				(font
					(size 1.27 1.27)
					(thickness 0.15)
				)
			)
		)
		(property "Author" "Antmicro"
			(at 0 0 0)
			(layer "B.Fab")
			(hide yes)
			(effects
				(font
					(size 1 1)
					(thickness 0.15)
				)
				(justify mirror)
			)
		)
		(property "License" "Apache-2.0"
			(at 0 0 0)
			(layer "B.Fab")
			(hide yes)
			(effects
				(font
					(size 1 1)
					(thickness 0.15)
				)
				(justify mirror)
			)
		)
		(property "MPN" "CR0402-FX-3300GLF"
			(at 0 0 0)
			(layer "B.Fab")
			(hide yes)
			(effects
				(font
					(size 1 1)
					(thickness 0.15)
				)
				(justify mirror)
			)
		)
		(property "Manufacturer" "Bourns"
			(at 0 0 0)
			(layer "B.Fab")
			(hide yes)
			(effects
				(font
					(size 1 1)
					(thickness 0.15)
				)
				(justify mirror)
			)
		)
		(property "Public" "False"
			(at 0 0 0)
			(layer "B.Fab")
			(hide yes)
			(effects
				(font
					(size 1 1)
					(thickness 0.15)
				)
				(justify mirror)
			)
		)
		(property "Tolerance" "1%"
			(at 0 0 0)
			(layer "B.Fab")
			(hide yes)
			(effects
				(font
					(size 1 1)
					(thickness 0.15)
				)
				(justify mirror)
			)
		)
		(property "Val" "330R"
			(at 0 0 0)
			(layer "B.Fab")
			(hide yes)
			(effects
				(font
					(size 1 1)
					(thickness 0.15)
				)
				(justify mirror)
			)
		)
		(sheetname "2xSFP+")
		(sheetfile "2xSFP+.kicad_sch")
		(attr smd)
		(fp_rect
			(start -0.925 0.47)
			(end 0.925 -0.47)
			(stroke
				(width 0.05)
				(type default)
			)
			(fill no)
			(layer "B.CrtYd")
		)
		(fp_rect
			(start -0.5 0.25)
			(end 0.5 -0.25)
			(stroke
				(width 0.15)
				(type solid)
			)
			(fill no)
			(layer "B.Fab")
		)
		(pad "1" smd roundrect
			(at -0.48 0)
			(size 0.59 0.64)
			(layers "B.Cu" "B.Mask" "B.Paste")
			(roundrect_rratio 0.25)
			(net 53 "/2xSFP+/SH")
			(pintype "passive")
			(teardrops
				(best_length_ratio 0.2)
				(max_length 1)
				(best_width_ratio 0.9)
				(max_width 2)
				(curved_edges yes)
				(filter_ratio 0.9)
				(enabled yes)
				(allow_two_segments yes)
				(prefer_zone_connections yes)
			)
		)
		(pad "2" smd roundrect
			(at 0.48 0)
			(size 0.59 0.64)
			(layers "B.Cu" "B.Mask" "B.Paste")
			(roundrect_rratio 0.25)
			(net 1 "GND")
			(pintype "passive")
			(teardrops
				(best_length_ratio 0.2)
				(max_length 1)
				(best_width_ratio 0.9)
				(max_width 2)
				(curved_edges yes)
				(filter_ratio 0.9)
				(enabled yes)
				(allow_two_segments yes)
				(prefer_zone_connections yes)
			)
		)
	)
	(footprint "antmicro-footprints:TP_SMD_0.75mm"
		(layer "B.Cu")
		(at 213.33 124.85 -90)
		(property "Reference" "TP45"
			(at -3.09 -0.47 90)
			(layer "B.SilkS")
			(effects
				(font
					(size 0.7 0.7)
					(thickness 0.15)
				)
				(justify left bottom mirror)
			)
		)
		(property "Value" "TP_0.75mm_SMD"
			(at 0 -1.2 90)
			(layer "B.Fab")
			(effects
				(font
					(size 0.7 0.7)
					(thickness 0.15)
				)
				(justify left bottom mirror)
			)
		)
		(property "Author" "Antmicro"
			(at 88.48 338.18 0)
			(layer "B.Fab")
			(hide yes)
			(effects
				(font
					(size 1 1)
					(thickness 0.15)
				)
				(justify mirror)
			)
		)
		(property "License" "Apache-2.0"
			(at 88.48 338.18 0)
			(layer "B.Fab")
			(hide yes)
			(effects
				(font
					(size 1 1)
					(thickness 0.15)
				)
				(justify mirror)
			)
		)
		(property "MPN" ""
			(at 88.48 338.18 0)
			(layer "B.Fab")
			(hide yes)
			(effects
				(font
					(size 1 1)
					(thickness 0.15)
				)
				(justify mirror)
			)
		)
		(property "Manufacturer" ""
			(at 88.48 338.18 0)
			(layer "B.Fab")
			(hide yes)
			(effects
				(font
					(size 1 1)
					(thickness 0.15)
				)
				(justify mirror)
			)
		)
		(property "Public" "False"
			(at 88.48 338.18 0)
			(layer "B.Fab")
			(hide yes)
			(effects
				(font
					(size 1 1)
					(thickness 0.15)
				)
				(justify mirror)
			)
		)
		(sheetname "PCIe misc")
		(sheetfile "pcie_misc.kicad_sch")
		(attr exclude_from_pos_files exclude_from_bom)
		(fp_circle
			(center 0 0)
			(end 0.475 0)
			(stroke
				(width 0.05)
				(type default)
			)
			(fill no)
			(layer "B.CrtYd")
		)
		(pad "1" smd circle
			(at 0 0 270)
			(size 0.75 0.75)
			(layers "B.Cu" "B.Mask")
			(net 710 "Net-(U37-SDAT)")
			(pinfunction "1")
			(pintype "passive")
			(teardrops
				(best_length_ratio 0.4)
				(max_length 1)
				(best_width_ratio 0.9)
				(max_width 2)
				(curved_edges yes)
				(filter_ratio 0.9)
				(enabled yes)
				(allow_two_segments yes)
				(prefer_zone_connections yes)
			)
		)
	)
	(footprint "antmicro-footprints:C_0402_1005Metric"
		(layer "B.Cu")
		(at 130.29 142.36 90)
		(descr "Capacitor SMD 0402")
		(tags "capacitor SMD 0402")
		(property "Reference" "C189"
			(at -1.4 -0.49 90)
			(layer "B.SilkS")
			(effects
				(font
					(size 0.7 0.7)
					(thickness 0.15)
				)
				(justify right bottom mirror)
			)
		)
		(property "Value" "C_100n_0402"
			(at -1.022927 -2.155213 90)
			(layer "B.Fab")
			(effects
				(font
					(size 0.7 0.7)
					(thickness 0.15)
				)
				(justify right bottom mirror)
			)
		)
		(property "Datasheet" "https://www.murata.com/products/productdetail?partno=GRM155R61H104KE14%23"
			(at 0 0 90)
			(layer "F.Fab")
			(hide yes)
			(effects
				(font
					(size 1.27 1.27)
					(thickness 0.15)
				)
			)
		)
		(property "Author" "Antmicro"
			(at 272.65 12.07 0)
			(layer "B.Fab")
			(hide yes)
			(effects
				(font
					(size 1 1)
					(thickness 0.15)
				)
				(justify mirror)
			)
		)
		(property "Dielectric" "X5R"
			(at 272.65 12.07 0)
			(layer "B.Fab")
			(hide yes)
			(effects
				(font
					(size 1 1)
					(thickness 0.15)
				)
				(justify mirror)
			)
		)
		(property "License" "Apache-2.0"
			(at 272.65 12.07 0)
			(layer "B.Fab")
			(hide yes)
			(effects
				(font
					(size 1 1)
					(thickness 0.15)
				)
				(justify mirror)
			)
		)
		(property "MPN" "GRM155R61H104KE14D"
			(at 272.65 12.07 0)
			(layer "B.Fab")
			(hide yes)
			(effects
				(font
					(size 1 1)
					(thickness 0.15)
				)
				(justify mirror)
			)
		)
		(property "Manufacturer" "Murata"
			(at 272.65 12.07 0)
			(layer "B.Fab")
			(hide yes)
			(effects
				(font
					(size 1 1)
					(thickness 0.15)
				)
				(justify mirror)
			)
		)
		(property "Public" "False"
			(at 272.65 12.07 0)
			(layer "B.Fab")
			(hide yes)
			(effects
				(font
					(size 1 1)
					(thickness 0.15)
				)
				(justify mirror)
			)
		)
		(property "Val" "100n"
			(at 272.65 12.07 0)
			(layer "B.Fab")
			(hide yes)
			(effects
				(font
					(size 1 1)
					(thickness 0.15)
				)
				(justify mirror)
			)
		)
		(property "Voltage" "50V"
			(at 272.65 12.07 0)
			(layer "B.Fab")
			(hide yes)
			(effects
				(font
					(size 1 1)
					(thickness 0.15)
				)
				(justify mirror)
			)
		)
		(sheetname "KR to SFI #2")
		(sheetfile "kr_sfi.kicad_sch")
		(attr smd)
		(fp_rect
			(start -0.925 0.47)
			(end 0.925 -0.47)
			(stroke
				(width 0.05)
				(type default)
			)
			(fill no)
			(layer "B.CrtYd")
		)
		(fp_line
			(start 0.504 -0.248)
			(end 0.504 0.25)
			(stroke
				(width 0.15)
				(type solid)
			)
			(layer "B.Fab")
		)
		(fp_line
			(start -0.494 -0.248)
			(end 0.504 -0.248)
			(stroke
				(width 0.15)
				(type solid)
			)
			(layer "B.Fab")
		)
		(fp_line
			(start 0.504 0.25)
			(end -0.494 0.25)
			(stroke
				(width 0.15)
				(type solid)
			)
			(layer "B.Fab")
		)
		(fp_line
			(start -0.494 0.25)
			(end -0.494 -0.248)
			(stroke
				(width 0.15)
				(type solid)
			)
			(layer "B.Fab")
		)
		(pad "1" smd roundrect
			(at -0.48 0 90)
			(size 0.59 0.64)
			(layers "B.Cu" "B.Mask" "B.Paste")
			(roundrect_rratio 0.25)
			(net 1 "GND")
			(pintype "passive")
			(teardrops
				(best_length_ratio 0.2)
				(max_length 1)
				(best_width_ratio 0.9)
				(max_width 2)
				(curved_edges yes)
				(filter_ratio 0.9)
				(enabled yes)
				(allow_two_segments yes)
				(prefer_zone_connections yes)
			)
		)
		(pad "2" smd roundrect
			(at 0.48 0 90)
			(size 0.59 0.64)
			(layers "B.Cu" "B.Mask" "B.Paste")
			(roundrect_rratio 0.25)
			(net 78 "+1V8")
			(pintype "passive")
			(teardrops
				(best_length_ratio 0.2)
				(max_length 1)
				(best_width_ratio 0.9)
				(max_width 2)
				(curved_edges yes)
				(filter_ratio 0.9)
				(enabled yes)
				(allow_two_segments yes)
				(prefer_zone_connections yes)
			)
		)
	)
	(footprint "antmicro-footprints:R_0402_1005Metric"
		(layer "B.Cu")
		(at 100.1 84.46 180)
		(descr "Resistor SMD 0402")
		(tags "resistor SMD 0402")
		(property "Reference" "R68"
			(at -1.1 0.45 0)
			(layer "B.SilkS")
			(effects
				(font
					(size 0.7 0.7)
					(thickness 0.15)
				)
				(justify left bottom mirror)
			)
		)
		(property "Value" "R_5k1_0402"
			(at -1.011843 -1.772047 0)
			(layer "B.Fab")
			(effects
				(font
					(size 0.7 0.7)
					(thickness 0.15)
				)
				(justify left bottom mirror)
			)
		)
		(property "Datasheet" "https://www.bourns.com/docs/product-datasheets/cr.pdf"
			(at 0 0 180)
			(layer "F.Fab")
			(hide yes)
			(effects
				(font
					(size 1.27 1.27)
					(thickness 0.15)
				)
			)
		)
		(property "Author" "Antmicro"
			(at 200 168.92 0)
			(layer "B.Fab")
			(hide yes)
			(effects
				(font
					(size 1 1)
					(thickness 0.15)
				)
				(justify mirror)
			)
		)
		(property "License" "Apache-2.0"
			(at 200 168.92 0)
			(layer "B.Fab")
			(hide yes)
			(effects
				(font
					(size 1 1)
					(thickness 0.15)
				)
				(justify mirror)
			)
		)
		(property "MPN" "CR0402-FX-5101GLF"
			(at 200 168.92 0)
			(layer "B.Fab")
			(hide yes)
			(effects
				(font
					(size 1 1)
					(thickness 0.15)
				)
				(justify mirror)
			)
		)
		(property "Manufacturer" "Bourns"
			(at 200 168.92 0)
			(layer "B.Fab")
			(hide yes)
			(effects
				(font
					(size 1 1)
					(thickness 0.15)
				)
				(justify mirror)
			)
		)
		(property "Public" "False"
			(at 200 168.92 0)
			(layer "B.Fab")
			(hide yes)
			(effects
				(font
					(size 1 1)
					(thickness 0.15)
				)
				(justify mirror)
			)
		)
		(property "Tolerance" "1%"
			(at 200 168.92 0)
			(layer "B.Fab")
			(hide yes)
			(effects
				(font
					(size 1 1)
					(thickness 0.15)
				)
				(justify mirror)
			)
		)
		(property "Val" "5k1"
			(at 200 168.92 0)
			(layer "B.Fab")
			(hide yes)
			(effects
				(font
					(size 1 1)
					(thickness 0.15)
				)
				(justify mirror)
			)
		)
		(sheetname "USB-C console")
		(sheetfile "usb-c_console.kicad_sch")
		(attr smd)
		(fp_rect
			(start -0.925 0.47)
			(end 0.925 -0.47)
			(stroke
				(width 0.05)
				(type default)
			)
			(fill no)
			(layer "B.CrtYd")
		)
		(fp_rect
			(start -0.5 0.25)
			(end 0.5 -0.25)
			(stroke
				(width 0.15)
				(type solid)
			)
			(fill no)
			(layer "B.Fab")
		)
		(pad "1" smd roundrect
			(at -0.48 0 180)
			(size 0.59 0.64)
			(layers "B.Cu" "B.Mask" "B.Paste")
			(roundrect_rratio 0.25)
			(net 182 "Net-(J3-CC_{2})")
			(pintype "passive")
			(teardrops
				(best_length_ratio 0.2)
				(max_length 1)
				(best_width_ratio 0.9)
				(max_width 2)
				(curved_edges yes)
				(filter_ratio 0.9)
				(enabled yes)
				(allow_two_segments yes)
				(prefer_zone_connections yes)
			)
		)
		(pad "2" smd roundrect
			(at 0.48 0 180)
			(size 0.59 0.64)
			(layers "B.Cu" "B.Mask" "B.Paste")
			(roundrect_rratio 0.25)
			(net 1 "GND")
			(pintype "passive")
			(teardrops
				(best_length_ratio 0.2)
				(max_length 1)
				(best_width_ratio 0.9)
				(max_width 2)
				(curved_edges yes)
				(filter_ratio 0.9)
				(enabled yes)
				(allow_two_segments yes)
				(prefer_zone_connections yes)
			)
		)
	)
	(footprint "antmicro-footprints:C_0402_1005Metric"
		(layer "B.Cu")
		(at 197.853588 137.730545 135)
		(descr "Capacitor SMD 0402")
		(tags "capacitor SMD 0402")
		(property "Reference" "C132"
			(at -2.768935 -0.026347 135)
			(layer "B.SilkS")
			(effects
				(font
					(size 0.7 0.7)
					(thickness 0.15)
				)
				(justify right bottom mirror)
			)
		)
		(property "Value" "C_220n_0402"
			(at -1.022927 -2.155213 135)
			(layer "B.Fab")
			(effects
				(font
					(size 0.7 0.7)
					(thickness 0.15)
				)
				(justify right bottom mirror)
			)
		)
		(property "Datasheet" "https://www.yageo.com/en/Chart/Download/pdf/CC0402KRX5R6BB224"
			(at 0 0 135)
			(layer "F.Fab")
			(hide yes)
			(effects
				(font
					(size 1.27 1.27)
					(thickness 0.15)
				)
			)
		)
		(property "Author" "Antmicro"
			(at 337.710001 -37.09 45)
			(layer "B.Fab")
			(hide yes)
			(effects
				(font
					(size 1 1)
					(thickness 0.15)
				)
				(justify mirror)
			)
		)
		(property "Dielectric" ""
			(at 337.710001 -37.09 45)
			(layer "B.Fab")
			(hide yes)
			(effects
				(font
					(size 1 1)
					(thickness 0.15)
				)
				(justify mirror)
			)
		)
		(property "License" "Apache-2.0"
			(at 337.710001 -37.09 45)
			(layer "B.Fab")
			(hide yes)
			(effects
				(font
					(size 1 1)
					(thickness 0.15)
				)
				(justify mirror)
			)
		)
		(property "MPN" "CC0402KRX5R6BB224"
			(at 337.710001 -37.09 45)
			(layer "B.Fab")
			(hide yes)
			(effects
				(font
					(size 1 1)
					(thickness 0.15)
				)
				(justify mirror)
			)
		)
		(property "Manufacturer" "YAGEO"
			(at 337.710001 -37.09 45)
			(layer "B.Fab")
			(hide yes)
			(effects
				(font
					(size 1 1)
					(thickness 0.15)
				)
				(justify mirror)
			)
		)
		(property "Public" "False"
			(at 337.710001 -37.09 45)
			(layer "B.Fab")
			(hide yes)
			(effects
				(font
					(size 1 1)
					(thickness 0.15)
				)
				(justify mirror)
			)
		)
		(property "Val" "220n"
			(at 337.710001 -37.09 45)
			(layer "B.Fab")
			(hide yes)
			(effects
				(font
					(size 1 1)
					(thickness 0.15)
				)
				(justify mirror)
			)
		)
		(property "Voltage" ""
			(at 337.710001 -37.09 45)
			(layer "B.Fab")
			(hide yes)
			(effects
				(font
					(size 1 1)
					(thickness 0.15)
				)
				(justify mirror)
			)
		)
		(sheetname "PCIe redriver")
		(sheetfile "pcie_redriver.kicad_sch")
		(attr smd)
		(fp_poly
			(pts
				(xy -0.925 0.47) (xy 0.925 0.47) (xy 0.925 -0.47) (xy -0.925 -0.47)
			)
			(stroke
				(width 0.05)
				(type default)
			)
			(fill no)
			(layer "B.CrtYd")
		)
		(fp_line
			(start 0.504 -0.248)
			(end 0.504 0.25)
			(stroke
				(width 0.15)
				(type solid)
			)
			(layer "B.Fab")
		)
		(fp_line
			(start 0.504 0.25)
			(end -0.494 0.25)
			(stroke
				(width 0.15)
				(type solid)
			)
			(layer "B.Fab")
		)
		(fp_line
			(start -0.494 -0.248)
			(end 0.504 -0.248)
			(stroke
				(width 0.15)
				(type solid)
			)
			(layer "B.Fab")
		)
		(fp_line
			(start -0.494 0.25)
			(end -0.494 -0.248)
			(stroke
				(width 0.15)
				(type solid)
			)
			(layer "B.Fab")
		)
		(pad "1" smd roundrect
			(at -0.48 0 135)
			(size 0.59 0.64)
			(layers "B.Cu" "B.Mask" "B.Paste")
			(roundrect_rratio 0.25)
			(net 222 "/Com Express 7 Interfaces/PCIe_{B1x4}.RX0+")
			(pintype "passive")
			(teardrops
				(best_length_ratio 0.2)
				(max_length 1)
				(best_width_ratio 0.9)
				(max_width 2)
				(curved_edges yes)
				(filter_ratio 0.9)
				(enabled yes)
				(allow_two_segments yes)
				(prefer_zone_connections yes)
			)
		)
		(pad "2" smd roundrect
			(at 0.48 0 135)
			(size 0.59 0.64)
			(layers "B.Cu" "B.Mask" "B.Paste")
			(roundrect_rratio 0.25)
			(net 957 "/PCIe redriver/PCIe_{I}_C.RX0+")
			(pintype "passive")
			(teardrops
				(best_length_ratio 0.2)
				(max_length 1)
				(best_width_ratio 0.9)
				(max_width 2)
				(curved_edges yes)
				(filter_ratio 0.9)
				(enabled yes)
				(allow_two_segments yes)
				(prefer_zone_connections yes)
			)
		)
	)
	(footprint "antmicro-footprints:R_0402_1005Metric"
		(layer "B.Cu")
		(at 121.25 150.81 90)
		(descr "Resistor SMD 0402")
		(tags "resistor SMD 0402")
		(property "Reference" "R216"
			(at -3.6 0.45 90)
			(layer "B.SilkS")
			(effects
				(font
					(size 0.7 0.7)
					(thickness 0.15)
				)
				(justify right bottom mirror)
			)
		)
		(property "Value" "R_0R_0402"
			(at -1.011843 -1.772047 90)
			(layer "B.Fab")
			(effects
				(font
					(size 0.7 0.7)
					(thickness 0.15)
				)
				(justify right bottom mirror)
			)
		)
		(property "Datasheet" "https://industrial.panasonic.com/cdbs/www-data/pdf/RDA0000/AOA0000C301.pdf"
			(at 0 0 90)
			(layer "F.Fab")
			(hide yes)
			(effects
				(font
					(size 1.27 1.27)
					(thickness 0.15)
				)
			)
		)
		(property "Author" "Antmicro"
			(at 272.06 29.56 0)
			(layer "B.Fab")
			(hide yes)
			(effects
				(font
					(size 1 1)
					(thickness 0.15)
				)
				(justify mirror)
			)
		)
		(property "Current" "1A"
			(at 272.06 29.56 0)
			(layer "B.Fab")
			(hide yes)
			(effects
				(font
					(size 1 1)
					(thickness 0.15)
				)
				(justify mirror)
			)
		)
		(property "License" "Apache-2.0"
			(at 272.06 29.56 0)
			(layer "B.Fab")
			(hide yes)
			(effects
				(font
					(size 1 1)
					(thickness 0.15)
				)
				(justify mirror)
			)
		)
		(property "MPN" "ERJ2GE0R00X"
			(at 272.06 29.56 0)
			(layer "B.Fab")
			(hide yes)
			(effects
				(font
					(size 1 1)
					(thickness 0.15)
				)
				(justify mirror)
			)
		)
		(property "Manufacturer" "Panasonic"
			(at 272.06 29.56 0)
			(layer "B.Fab")
			(hide yes)
			(effects
				(font
					(size 1 1)
					(thickness 0.15)
				)
				(justify mirror)
			)
		)
		(property "Public" "False"
			(at 272.06 29.56 0)
			(layer "B.Fab")
			(hide yes)
			(effects
				(font
					(size 1 1)
					(thickness 0.15)
				)
				(justify mirror)
			)
		)
		(property "Tolerance" ""
			(at 272.06 29.56 0)
			(layer "B.Fab")
			(hide yes)
			(effects
				(font
					(size 1 1)
					(thickness 0.15)
				)
				(justify mirror)
			)
		)
		(property "Val" "0R"
			(at 272.06 29.56 0)
			(layer "B.Fab")
			(hide yes)
			(effects
				(font
					(size 1 1)
					(thickness 0.15)
				)
				(justify mirror)
			)
		)
		(sheetname "PCIe redriver")
		(sheetfile "pcie_redriver.kicad_sch")
		(attr smd)
		(fp_rect
			(start -0.925 0.47)
			(end 0.925 -0.47)
			(stroke
				(width 0.05)
				(type default)
			)
			(fill no)
			(layer "B.CrtYd")
		)
		(fp_rect
			(start -0.5 0.25)
			(end 0.5 -0.25)
			(stroke
				(width 0.15)
				(type solid)
			)
			(fill no)
			(layer "B.Fab")
		)
		(pad "1" smd roundrect
			(at -0.48 0 90)
			(size 0.59 0.64)
			(layers "B.Cu" "B.Mask" "B.Paste")
			(roundrect_rratio 0.25)
			(net 2 "+3V3")
			(pintype "passive")
			(teardrops
				(best_length_ratio 0.2)
				(max_length 1)
				(best_width_ratio 0.9)
				(max_width 2)
				(curved_edges yes)
				(filter_ratio 0.9)
				(enabled yes)
				(allow_two_segments yes)
				(prefer_zone_connections yes)
			)
		)
		(pad "2" smd roundrect
			(at 0.48 0 90)
			(size 0.59 0.64)
			(layers "B.Cu" "B.Mask" "B.Paste")
			(roundrect_rratio 0.25)
			(net 631 "Net-(U39-RXDET)")
			(pintype "passive")
			(teardrops
				(best_length_ratio 0.2)
				(max_length 1)
				(best_width_ratio 0.9)
				(max_width 2)
				(curved_edges yes)
				(filter_ratio 0.9)
				(enabled yes)
				(allow_two_segments yes)
				(prefer_zone_connections yes)
			)
		)
	)
	(footprint "antmicro-footprints:C_0603_1608Metric"
		(layer "B.Cu")
		(at 148.7 71.81 180)
		(descr "Capacitor SMD 0603")
		(tags "capacitor 0603")
		(property "Reference" "C79"
			(at -3.3 -0.5 0)
			(layer "B.SilkS")
			(effects
				(font
					(size 0.7 0.7)
					(thickness 0.15)
				)
				(justify left bottom mirror)
			)
		)
		(property "Value" "C_22u_16V_0603"
			(at -1.42757 -1.770288 0)
			(layer "B.Fab")
			(effects
				(font
					(size 0.7 0.7)
					(thickness 0.15)
				)
				(justify left bottom mirror)
			)
		)
		(property "Datasheet" "https://product.samsungsem.com/mlcc/CL10A226MO7JZN.do"
			(at 0 0 180)
			(layer "F.Fab")
			(hide yes)
			(effects
				(font
					(size 1.27 1.27)
					(thickness 0.15)
				)
			)
		)
		(property "Author" "Antmicro"
			(at 297.4 143.62 0)
			(layer "B.Fab")
			(hide yes)
			(effects
				(font
					(size 1 1)
					(thickness 0.15)
				)
				(justify mirror)
			)
		)
		(property "Dielectric" ""
			(at 297.4 143.62 0)
			(layer "B.Fab")
			(hide yes)
			(effects
				(font
					(size 1 1)
					(thickness 0.15)
				)
				(justify mirror)
			)
		)
		(property "License" "Apache-2.0"
			(at 297.4 143.62 0)
			(layer "B.Fab")
			(hide yes)
			(effects
				(font
					(size 1 1)
					(thickness 0.15)
				)
				(justify mirror)
			)
		)
		(property "MPN" "CL10A226MO7JZNC"
			(at 297.4 143.62 0)
			(layer "B.Fab")
			(hide yes)
			(effects
				(font
					(size 1 1)
					(thickness 0.15)
				)
				(justify mirror)
			)
		)
		(property "Manufacturer" "Samsung Electro-Mechanics"
			(at 297.4 143.62 0)
			(layer "B.Fab")
			(hide yes)
			(effects
				(font
					(size 1 1)
					(thickness 0.15)
				)
				(justify mirror)
			)
		)
		(property "Public" "False"
			(at 297.4 143.62 0)
			(layer "B.Fab")
			(hide yes)
			(effects
				(font
					(size 1 1)
					(thickness 0.15)
				)
				(justify mirror)
			)
		)
		(property "Val" "22u"
			(at 297.4 143.62 0)
			(layer "B.Fab")
			(hide yes)
			(effects
				(font
					(size 1 1)
					(thickness 0.15)
				)
				(justify mirror)
			)
		)
		(property "Voltage" "16V"
			(at 297.4 143.62 0)
			(layer "B.Fab")
			(hide yes)
			(effects
				(font
					(size 1 1)
					(thickness 0.15)
				)
				(justify mirror)
			)
		)
		(sheetname "M.2 key E")
		(sheetfile "m2keye.kicad_sch")
		(attr smd)
		(fp_line
			(start 0.15 0.4)
			(end -0.15 0.4)
			(stroke
				(width 0.15)
				(type solid)
			)
			(layer "B.SilkS")
		)
		(fp_line
			(start 0.15 -0.4)
			(end -0.15 -0.4)
			(stroke
				(width 0.15)
				(type solid)
			)
			(layer "B.SilkS")
		)
		(fp_rect
			(start -1.25 0.65)
			(end 1.25 -0.65)
			(stroke
				(width 0.05)
				(type solid)
			)
			(fill no)
			(layer "B.CrtYd")
		)
		(fp_rect
			(start -0.8 0.4)
			(end 0.8 -0.4)
			(stroke
				(width 0.15)
				(type solid)
			)
			(fill no)
			(layer "B.Fab")
		)
		(pad "1" smd roundrect
			(at -0.7 0 180)
			(size 0.8 1)
			(layers "B.Cu" "B.Mask" "B.Paste")
			(roundrect_rratio 0.2)
			(net 1 "GND")
			(pintype "passive")
			(teardrops
				(best_length_ratio 0.2)
				(max_length 1)
				(best_width_ratio 0.9)
				(max_width 2)
				(curved_edges yes)
				(filter_ratio 0.9)
				(enabled yes)
				(allow_two_segments yes)
				(prefer_zone_connections yes)
			)
		)
		(pad "2" smd roundrect
			(at 0.7 0 180)
			(size 0.8 1)
			(layers "B.Cu" "B.Mask" "B.Paste")
			(roundrect_rratio 0.2)
			(net 2 "+3V3")
			(pintype "passive")
			(teardrops
				(best_length_ratio 0.2)
				(max_length 1)
				(best_width_ratio 0.9)
				(max_width 2)
				(curved_edges yes)
				(filter_ratio 0.9)
				(enabled yes)
				(allow_two_segments yes)
				(prefer_zone_connections yes)
			)
		)
	)
	(footprint "antmicro-footprints:C_0603_1608Metric"
		(layer "B.Cu")
		(at 116.9 87.11)
		(descr "Capacitor SMD 0603")
		(tags "capacitor 0603")
		(property "Reference" "C20"
			(at -1.1 1.55 0)
			(layer "B.SilkS")
			(effects
				(font
					(size 0.7 0.7)
					(thickness 0.15)
				)
				(justify right bottom mirror)
			)
		)
		(property "Value" "C_22u_16V_0603"
			(at -1.42757 -1.770288 0)
			(layer "B.Fab")
			(effects
				(font
					(size 0.7 0.7)
					(thickness 0.15)
				)
				(justify right bottom mirror)
			)
		)
		(property "Datasheet" "https://product.samsungsem.com/mlcc/CL10A226MO7JZN.do"
			(at 0 0 0)
			(layer "F.Fab")
			(hide yes)
			(effects
				(font
					(size 1.27 1.27)
					(thickness 0.15)
				)
			)
		)
		(property "Author" "Antmicro"
			(at 0 0 0)
			(layer "B.Fab")
			(hide yes)
			(effects
				(font
					(size 1 1)
					(thickness 0.15)
				)
				(justify mirror)
			)
		)
		(property "Dielectric" ""
			(at 0 0 0)
			(layer "B.Fab")
			(hide yes)
			(effects
				(font
					(size 1 1)
					(thickness 0.15)
				)
				(justify mirror)
			)
		)
		(property "License" "Apache-2.0"
			(at 0 0 0)
			(layer "B.Fab")
			(hide yes)
			(effects
				(font
					(size 1 1)
					(thickness 0.15)
				)
				(justify mirror)
			)
		)
		(property "MPN" "CL10A226MO7JZNC"
			(at 0 0 0)
			(layer "B.Fab")
			(hide yes)
			(effects
				(font
					(size 1 1)
					(thickness 0.15)
				)
				(justify mirror)
			)
		)
		(property "Manufacturer" "Samsung Electro-Mechanics"
			(at 0 0 0)
			(layer "B.Fab")
			(hide yes)
			(effects
				(font
					(size 1 1)
					(thickness 0.15)
				)
				(justify mirror)
			)
		)
		(property "Public" "False"
			(at 0 0 0)
			(layer "B.Fab")
			(hide yes)
			(effects
				(font
					(size 1 1)
					(thickness 0.15)
				)
				(justify mirror)
			)
		)
		(property "Val" "22u"
			(at 0 0 0)
			(layer "B.Fab")
			(hide yes)
			(effects
				(font
					(size 1 1)
					(thickness 0.15)
				)
				(justify mirror)
			)
		)
		(property "Voltage" "16V"
			(at 0 0 0)
			(layer "B.Fab")
			(hide yes)
			(effects
				(font
					(size 1 1)
					(thickness 0.15)
				)
				(justify mirror)
			)
		)
		(sheetname "2xUSB3.0+RJ45")
		(sheetfile "usb3+rj45.kicad_sch")
		(attr smd)
		(fp_line
			(start 0.15 -0.4)
			(end -0.15 -0.4)
			(stroke
				(width 0.15)
				(type solid)
			)
			(layer "B.SilkS")
		)
		(fp_line
			(start 0.15 0.4)
			(end -0.15 0.4)
			(stroke
				(width 0.15)
				(type solid)
			)
			(layer "B.SilkS")
		)
		(fp_rect
			(start -1.25 0.65)
			(end 1.25 -0.65)
			(stroke
				(width 0.05)
				(type solid)
			)
			(fill no)
			(layer "B.CrtYd")
		)
		(fp_rect
			(start -0.8 0.4)
			(end 0.8 -0.4)
			(stroke
				(width 0.15)
				(type solid)
			)
			(fill no)
			(layer "B.Fab")
		)
		(pad "1" smd roundrect
			(at -0.7 0)
			(size 0.8 1)
			(layers "B.Cu" "B.Mask" "B.Paste")
			(roundrect_rratio 0.2)
			(net 1 "GND")
			(pintype "passive")
			(teardrops
				(best_length_ratio 0.2)
				(max_length 1)
				(best_width_ratio 0.9)
				(max_width 2)
				(curved_edges yes)
				(filter_ratio 0.9)
				(enabled yes)
				(allow_two_segments yes)
				(prefer_zone_connections yes)
			)
		)
		(pad "2" smd roundrect
			(at 0.7 0)
			(size 0.8 1)
			(layers "B.Cu" "B.Mask" "B.Paste")
			(roundrect_rratio 0.2)
			(net 52 "+5V")
			(pintype "passive")
			(teardrops
				(best_length_ratio 0.2)
				(max_length 1)
				(best_width_ratio 0.9)
				(max_width 2)
				(curved_edges yes)
				(filter_ratio 0.9)
				(enabled yes)
				(allow_two_segments yes)
				(prefer_zone_connections yes)
			)
		)
	)
	(footprint "antmicro-footprints:TP_SMD_0.75mm"
		(layer "B.Cu")
		(at 258.95 84.41 180)
		(property "Reference" "TP15"
			(at 0.399999 -0.4 0)
			(layer "B.SilkS")
			(effects
				(font
					(size 0.7 0.7)
					(thickness 0.15)
				)
				(justify left bottom mirror)
			)
		)
		(property "Value" "TP_0.75mm_SMD"
			(at 0 -1.2 0)
			(layer "B.Fab")
			(effects
				(font
					(size 0.7 0.7)
					(thickness 0.15)
				)
				(justify left bottom mirror)
			)
		)
		(property "Author" "Antmicro"
			(at 517.9 168.82 0)
			(layer "B.Fab")
			(hide yes)
			(effects
				(font
					(size 1 1)
					(thickness 0.15)
				)
				(justify mirror)
			)
		)
		(property "License" "Apache-2.0"
			(at 517.9 168.82 0)
			(layer "B.Fab")
			(hide yes)
			(effects
				(font
					(size 1 1)
					(thickness 0.15)
				)
				(justify mirror)
			)
		)
		(property "MPN" ""
			(at 517.9 168.82 0)
			(layer "B.Fab")
			(hide yes)
			(effects
				(font
					(size 1 1)
					(thickness 0.15)
				)
				(justify mirror)
			)
		)
		(property "Manufacturer" ""
			(at 517.9 168.82 0)
			(layer "B.Fab")
			(hide yes)
			(effects
				(font
					(size 1 1)
					(thickness 0.15)
				)
				(justify mirror)
			)
		)
		(property "Public" "False"
			(at 517.9 168.82 0)
			(layer "B.Fab")
			(hide yes)
			(effects
				(font
					(size 1 1)
					(thickness 0.15)
				)
				(justify mirror)
			)
		)
		(sheetname "Misc")
		(sheetfile "misc.kicad_sch")
		(attr exclude_from_pos_files exclude_from_bom)
		(fp_circle
			(center 0 0)
			(end 0.475 0)
			(stroke
				(width 0.05)
				(type default)
			)
			(fill no)
			(layer "B.CrtYd")
		)
		(pad "1" smd circle
			(at 0 0 180)
			(size 0.75 0.75)
			(layers "B.Cu" "B.Mask")
			(net 707 "Net-(U24-TACH3)")
			(pinfunction "1")
			(pintype "passive")
			(teardrops
				(best_length_ratio 0.4)
				(max_length 1)
				(best_width_ratio 0.9)
				(max_width 2)
				(curved_edges yes)
				(filter_ratio 0.9)
				(enabled yes)
				(allow_two_segments yes)
				(prefer_zone_connections yes)
			)
		)
	)
	(gr_line
		(start 180.15 93.11)
		(end 180.150001 111.110001)
		(stroke
			(width 0.12)
			(type default)
		)
		(layer "Edge.Cuts")
	)
	(gr_line
		(start 319.959131 143.31)
		(end 315.43 143.31)
		(stroke
			(width 0.12)
			(type solid)
		)
		(layer "Edge.Cuts")
	)
	(gr_line
		(start 94.49 171.81)
		(end 94.49 67.81)
		(stroke
			(width 0.12)
			(type solid)
		)
		(layer "Edge.Cuts")
	)
	(gr_line
		(start 319.959131 67.81)
		(end 319.959131 143.310002)
		(stroke
			(width 0.12)
			(type solid)
		)
		(layer "Edge.Cuts")
	)
	(gr_line
		(start 94.49 67.81)
		(end 319.959131 67.81)
		(stroke
			(width 0.12)
			(type solid)
		)
		(layer "Edge.Cuts")
	)
	(gr_line
		(start 183.709217 91.61)
		(end 181.469998 91.610003)
		(stroke
			(width 0.12)
			(type default)
		)
		(layer "Edge.Cuts")
	)
	(gr_rect
		(start 208.5 92.11)
		(end 257.45 112.11)
		(stroke
			(width 0.12)
			(type solid)
		)
		(fill no)
		(layer "Edge.Cuts")
	)
	(gr_line
		(start 315.43 149.285)
		(end 315.43 143.31)
		(stroke
			(width 0.12)
			(type default)
		)
		(layer "Edge.Cuts")
	)
	(gr_arc
		(start 184.949999 111.031724)
		(mid 185.129191 112.449469)
		(end 183.709213 112.610005)
		(stroke
			(width 0.12)
			(type default)
		)
		(layer "Edge.Cuts")
	)
	(gr_line
		(start 315.43 171.81)
		(end 94.49 171.81)
		(stroke
			(width 0.12)
			(type solid)
		)
		(layer "Edge.Cuts")
	)
	(gr_arc
		(start 183.709217 91.61)
		(mid 185.129189 91.770535)
		(end 184.95 93.188276)
		(stroke
			(width 0.12)
			(type default)
		)
		(layer "Edge.Cuts")
	)
	(gr_line
		(start 184.949999 111.031724)
		(end 184.95 93.188277)
		(stroke
			(width 0.12)
			(type default)
		)
		(layer "Edge.Cuts")
	)
	(gr_line
		(start 315.43 171.535)
		(end 315.43 171.81)
		(stroke
			(width 0.12)
			(type default)
		)
		(layer "Edge.Cuts")
	)
	(gr_arc
		(start 181.469999 112.609998)
		(mid 180.06 112.519999)
		(end 180.150001 111.110001)
		(stroke
			(width 0.12)
			(type default)
		)
		(layer "Edge.Cuts")
	)
	(gr_line
		(start 181.469999 112.609998)
		(end 183.709213 112.610005)
		(stroke
			(width 0.12)
			(type default)
		)
		(layer "Edge.Cuts")
	)
	(gr_arc
		(start 180.15 93.11)
		(mid 180.06 91.700002)
		(end 181.469997 91.610004)
		(stroke
			(width 0.12)
			(type default)
		)
		(layer "Edge.Cuts")
	)
	(gr_text "COM Express 7 Baseboard\nRev. 1.1.2   2/2025"
		(at 111.2 125.16 0)
		(layer "F.Cu")
		(effects
			(font
				(size 0.7 0.7)
				(thickness 0.125)
			)
			(justify left)
		)
	)
	(segment
		(start 318.359131 137.875)
		(end 319.334131 136.9)
		(width 0.2)
		(layer "F.Cu")
		(net 0)
	)
	(segment
		(start 315.005 137.875)
		(end 318.359131 137.875)
		(width 0.2)
		(layer "F.Cu")
		(net 0)
	)
	(via
		(at 319.334131 136.9)
		(size 0.45)
		(drill 0.1)
		(layers "F.Cu" "B.Cu")
		(net 0)
	)
	(segment
		(start 193.70861 77.632163)
		(end 193.70861 78.102163)
		(width 0.2)
		(layer "F.Cu")
		(net 1)
	)
	(segment
		(start 304.197 75.04)
		(end 304.197 74.035)
		(width 0.3)
		(layer "F.Cu")
		(net 1)
	)
	(segment
		(start 260.282708 77.772)
		(end 261.017707 77.772)
		(width 0.3)
		(layer "F.Cu")
		(net 1)
	)
	(segment
		(start 261.38 88.269999)
		(end 261.54 88.429999)
		(width 0.3)
		(layer "F.Cu")
		(net 1)
	)
	(segment
		(start 190.415533 138.453915)
		(end 191.081627 138.453915)
		(width 0.125)
		(layer "F.Cu")
		(net 1)
	)
	(segment
		(start 188.70861 77.632163)
		(end 188.70861 78.102163)
		(width 0.2)
		(layer "F.Cu")
		(net 1)
	)
	(segment
		(start 225.525 150.125)
		(end 225.525 151.136)
		(width 0.2)
		(layer "F.Cu")
		(net 1)
	)
	(segment
		(start 197.525 155.625)
		(end 197.525 156.685)
		(width 0.2)
		(layer "F.Cu")
		(net 1)
	)
	(segment
		(start 188.025 152.125)
		(end 187.65 152.5)
		(width 0.2)
		(layer "F.Cu")
		(net 1)
	)
	(segment
		(start 178.025 157.775)
		(end 178.025 156.685)
		(width 0.2)
		(layer "F.Cu")
		(net 1)
	)
	(segment
		(start 253.328251 128.131748)
		(end 254.451252 128.131748)
		(width 0.125)
		(layer "F.Cu")
		(net 1)
	)
	(segment
		(start 196.025 155.45)
		(end 196.025 156.685)
		(width 0.2)
		(layer "F.Cu")
		(net 1)
	)
	(segment
		(start 205.525 167.15)
		(end 205.525 168.685)
		(width 0.2)
		(layer "F.Cu")
		(net 1)
	)
	(segment
		(start 152.5685 86.5595)
		(end 153.5735 86.5595)
		(width 0.3)
		(layer "F.Cu")
		(net 1)
	)
	(segment
		(start 195.95 152.25)
		(end 195.95 151.21)
		(width 0.2)
		(layer "F.Cu")
		(net 1)
	)
	(segment
		(start 212.025 167.525)
		(end 212 167.5)
		(width 0.2)
		(layer "F.Cu")
		(net 1)
	)
	(segment
		(start 200.95 160.57)
		(end 201.52 160)
		(width 0.125)
		(layer "F.Cu")
		(net 1)
	)
	(segment
		(start 308.019 83.287)
		(end 308.019 82.754)
		(width 0.125)
		(layer "F.Cu")
		(net 1)
	)
	(segment
		(start 230.525 168.675)
		(end 230.525 169.865)
		(width 0.2)
		(layer "F.Cu")
		(net 1)
	)
	(segment
		(start 129.5 108.32)
		(end 129.5 107.78)
		(width 0.2)
		(layer "F.Cu")
		(net 1)
	)
	(segment
		(start 217.025 167.575)
		(end 217 167.55)
		(width 0.2)
		(layer "F.Cu")
		(net 1)
	)
	(segment
		(start 259.98 88.27)
		(end 261.38 88.269999)
		(width 0.3)
		(layer "F.Cu")
		(net 1)
	)
	(segment
		(start 312.169999 103.348999)
		(end 312.169999 102.900001)
		(width 0.2)
		(layer "F.Cu")
		(net 1)
	)
	(segment
		(start 212.025 156.685)
		(end 212.025 155.525)
		(width 0.2)
		(layer "F.Cu")
		(net 1)
	)
	(segment
		(start 181.025 169.874)
		(end 181 169.899)
		(width 0.2)
		(layer "F.Cu")
		(net 1)
	)
	(segment
		(start 253.4 162)
		(end 255.374 160.026)
		(width 0.3)
		(layer "F.Cu")
		(net 1)
	)
	(segment
		(start 212.025 151.136)
		(end 212.025 149.946)
		(width 0.2)
		(layer "F.Cu")
		(net 1)
	)
	(segment
		(start 189.525 152.175)
		(end 189.35 152.35)
		(width 0.2)
		(layer "F.Cu")
		(net 1)
	)
	(segment
		(start 230.525 164.275)
		(end 230.88 164.63)
		(width 0.2)
		(layer "F.Cu")
		(net 1)
	)
	(segment
		(start 188.025 151.135)
		(end 188.025 152.125)
		(width 0.2)
		(layer "F.Cu")
		(net 1)
	)
	(segment
		(start 225.5 164.3)
		(end 225.5 163.16)
		(width 0.2)
		(layer "F.Cu")
		(net 1)
	)
	(segment
		(start 205.525 161.946)
		(end 205.55 161.921)
		(width 0.2)
		(layer "F.Cu")
		(net 1)
	)
	(segment
		(start 209.025 151.135)
		(end 209.025 152.275)
		(width 0.2)
		(layer "F.Cu")
		(net 1)
	)
	(segment
		(start 219.025 150.025)
		(end 219.025 151.136)
		(width 0.2)
		(layer "F.Cu")
		(net 1)
	)
	(segment
		(start 120.687 74.277)
		(end 120.5 74.09)
		(width 0.3)
		(layer "F.Cu")
		(net 1)
	)
	(segment
		(start 200.95 160.975)
		(end 200.95 160.57)
		(width 0.125)
		(layer "F.Cu")
		(net 1)
	)
	(segment
		(start 210.6 161.8)
		(end 210.525 161.875)
		(width 0.2)
		(layer "F.Cu")
		(net 1)
	)
	(segment
		(start 176.025 169.975)
		(end 176.025 168.684)
		(width 0.2)
		(layer "F.Cu")
		(net 1)
	)
	(segment
		(start 176.525 151.135)
		(end 176.525 149.925)
		(width 0.2)
		(layer "F.Cu")
		(net 1)
	)
	(segment
		(start 97.502 151.472)
		(end 97.502 152.098)
		(width 0.2)
		(layer "F.Cu")
		(net 1)
	)
	(segment
		(start 239.25 156.861)
		(end 239.250001 156.295)
		(width 0.125)
		(layer "F.Cu")
		(net 1)
	)
	(segment
		(start 201.025 161.925)
		(end 201.025 163.136)
		(width 0.2)
		(layer "F.Cu")
		(net 1)
	)
	(segment
		(start 243.077 127.959)
		(end 243.077 127.203)
		(width 0.3)
		(layer "F.Cu")
		(net 1)
	)
	(segment
		(start 190.70861 77.632163)
		(end 190.70861 78.102163)
		(width 0.2)
		(layer "F.Cu")
		(net 1)
	)
	(segment
		(start 223.525 151.134)
		(end 223.525 152.324)
		(width 0.2)
		(layer "F.Cu")
		(net 1)
	)
	(segment
		(start 179.525 149.975)
		(end 179.5 149.95)
		(width 0.2)
		(layer "F.Cu")
		(net 1)
	)
	(segment
		(start 319.45 168.11)
		(end 317.7 168.11)
		(width 0.55)
		(layer "F.Cu")
		(net 1)
	)
	(segment
		(start 222.025 157.775)
		(end 222 157.8)
		(width 0.2)
		(layer "F.Cu")
		(net 1)
	)
	(segment
		(start 186 161.7)
		(end 186.025 161.725)
		(width 0.2)
		(layer "F.Cu")
		(net 1)
	)
	(segment
		(start 194.525 161.946)
		(end 194.55 161.921)
		(width 0.2)
		(layer "F.Cu")
		(net 1)
	)
	(segment
		(start 310.175 82.32)
		(end 308.625 82.32)
		(width 0.3)
		(layer "F.Cu")
		(net 1)
	)
	(segment
		(start 113.851 147.361)
		(end 114.4 147.361)
		(width 0.125)
		(layer "F.Cu")
		(net 1)
	)
	(segment
		(start 195.95 151.21)
		(end 196.025 151.135)
		(width 0.2)
		(layer "F.Cu")
		(net 1)
	)
	(segment
		(start 212.025 168.685)
		(end 212.025 167.525)
		(width 0.2)
		(layer "F.Cu")
		(net 1)
	)
	(segment
		(start 239.250001 156.295)
		(end 238.5 155.544999)
		(width 0.125)
		(layer "F.Cu")
		(net 1)
	)
	(segment
		(start 184.525 157.875)
		(end 184.5 157.9)
		(width 0.2)
		(layer "F.Cu")
		(net 1)
	)
	(segment
		(start 307.550001 79.335)
		(end 307.55 78.786002)
		(width 0.2)
		(layer "F.Cu")
		(net 1)
	)
	(segment
		(start 152.5685 71.0605)
		(end 153.5735 71.0605)
		(width 0.3)
		(layer "F.Cu")
		(net 1)
	)
	(segment
		(start 143.19 147.11)
		(end 143.19 148.591)
		(width 0.3)
		(layer "F.Cu")
		(net 1)
	)
	(segment
		(start 199.94639 82.787837)
		(end 199.949 82.785227)
		(width 0.2)
		(layer "F.Cu")
		(net 1)
	)
	(segment
		(start 230.6 152.3)
		(end 230.525 152.225)
		(width 0.2)
		(layer "F.Cu")
		(net 1)
	)
	(segment
		(start 184.45 152.25)
		(end 184.525 152.175)
		(width 0.2)
		(layer "F.Cu")
		(net 1)
	)
	(segment
		(start 195.70861 77.632163)
		(end 195.70861 78.102163)
		(width 0.2)
		(layer "F.Cu")
		(net 1)
	)
	(segment
		(start 176.025 155.625)
		(end 175.9 155.5)
		(width 0.2)
		(layer "F.Cu")
		(net 1)
	)
	(segment
		(start 186.025 167.45)
		(end 186.025 168.684)
		(width 0.2)
		(layer "F.Cu")
		(net 1)
	)
	(segment
		(start 306.475 149.435)
		(end 306.15 149.11)
		(width 0.125)
		(layer "F.Cu")
		(net 1)
	)
	(segment
		(start 217.525 149.946)
		(end 217.55 149.921)
		(width 0.2)
		(layer "F.Cu")
		(net 1)
	)
	(segment
		(start 189.3 157.9)
		(end 189.525 157.675)
		(width 0.2)
		(layer "F.Cu")
		(net 1)
	)
	(segment
		(start 303.5 92.56)
		(end 303.1 92.56)
		(width 0.125)
		(layer "F.Cu")
		(net 1)
	)
	(segment
		(start 213.525 155.525)
		(end 213.5 155.5)
		(width 0.2)
		(layer "F.Cu")
		(net 1)
	)
	(segment
		(start 210.525 156.685)
		(end 210.525 155.525)
		(width 0.2)
		(layer "F.Cu")
		(net 1)
	)
	(segment
		(start 124.36 133.88)
		(end 124.36 132.88)
		(width 0.125)
		(layer "F.Cu")
		(net 1)
	)
	(segment
		(start 212.025 161.475)
		(end 212.025 163.136)
		(width 0.2)
		(layer "F.Cu")
		(net 1)
	)
	(segment
		(start 208.45 167.5)
		(end 208.525 167.575)
		(width 0.2)
		(layer "F.Cu")
		(net 1)
	)
	(segment
		(start 193.95 141.923328)
		(end 193.95 141.925)
		(width 0.125)
		(layer "F.Cu")
		(net 1)
	)
	(segment
		(start 215.525 168.685)
		(end 215.525 167.525)
		(width 0.2)
		(layer "F.Cu")
		(net 1)
	)
	(segment
		(start 219.025 157.75)
		(end 219.025 156.685)
		(width 0.2)
		(layer "F.Cu")
		(net 1)
	)
	(segment
		(start 152.5685 80.5595)
		(end 153.5735 80.5595)
		(width 0.3)
		(layer "F.Cu")
		(net 1)
	)
	(segment
		(start 232.822707 77.772)
		(end 231.407707 77.772)
		(width 0.3)
		(layer "F.Cu")
		(net 1)
	)
	(segment
		(start 302.825 92.285)
		(end 302.825001 91.259)
		(width 0.125)
		(layer "F.Cu")
		(net 1)
	)
	(segment
		(start 107.6 152.585)
		(end 107.6 151.813)
		(width 0.2)
		(layer "F.Cu")
		(net 1)
	)
	(segment
		(start 225.525 168.685)
		(end 225.525 169.725)
		(width 0.125)
		(layer "F.Cu")
		(net 1)
	)
	(segment
		(start 223.525 157.775)
		(end 223.5 157.8)
		(width 0.2)
		(layer "F.Cu")
		(net 1)
	)
	(segment
		(start 113.38 145.86)
		(end 113.38 144.86)
		(width 0.125)
		(layer "F.Cu")
		(net 1)
	)
	(segment
		(start 213.525 156.685)
		(end 213.525 155.525)
		(width 0.2)
		(layer "F.Cu")
		(net 1)
	)
	(segment
		(start 302.98 90.06)
		(end 302.825 90.215)
		(width 0.45)
		(layer "F.Cu")
		(net 1)
	)
	(segment
		(start 313.648 167.26)
		(end 313.898 167.01)
		(width 0.2)
		(layer "F.Cu")
		(net 1)
	)
	(segment
		(start 311.714999 119.158999)
		(end 311.714999 119.62)
		(width 0.2)
		(layer "F.Cu")
		(net 1)
	)
	(segment
		(start 186.025 161.725)
		(end 186.025 163.136)
		(width 0.2)
		(layer "F.Cu")
		(net 1)
	)
	(segment
		(start 311.714999 102.945001)
		(end 311.74 102.92)
		(width 0.2)
		(layer "F.Cu")
		(net 1)
	)
	(segment
		(start 226.9 149.65)
		(end 227.025 149.775)
		(width 0.2)
		(layer "F.Cu")
		(net 1)
	)
	(segment
		(start 302.825 90.215)
		(end 302.825 91.259)
		(width 0.45)
		(layer "F.Cu")
		(net 1)
	)
	(segment
		(start 307.925001 82.66)
		(end 307.625001 82.66)
		(width 0.125)
		(layer "F.Cu")
		(net 1)
	)
	(segment
		(start 261.017707 77.772)
		(end 261.950708 76.838999)
		(width 0.3)
		(layer "F.Cu")
		(net 1)
	)
	(segment
		(start 197.55 155.6)
		(end 197.525 155.625)
		(width 0.2)
		(layer "F.Cu")
		(net 1)
	)
	(segment
		(start 236.7 154.94)
		(end 236.7 155.51)
		(width 0.2)
		(layer "F.Cu")
		(net 1)
	)
	(segment
		(start 213.55 152.3)
		(end 213.55 151.161)
		(width 0.2)
		(layer "F.Cu")
		(net 1)
	)
	(segment
		(start 205.525 152.275)
		(end 205.5 152.3)
		(width 0.2)
		(layer "F.Cu")
		(net 1)
	)
	(segment
		(start 227 157.8)
		(end 227 156.7)
		(width 0.2)
		(layer "F.Cu")
		(net 1)
	)
	(segment
		(start 220.6 160.5)
		(end 220 159.9)
		(width 0.3)
		(layer "F.Cu")
		(net 1)
	)
	(segment
		(start 120.92 147.361)
		(end 120.4 147.361)
		(width 0.125)
		(layer "F.Cu")
		(net 1)
	)
	(segment
		(start 210.525 155.525)
		(end 210.5 155.5)
		(width 0.2)
		(layer "F.Cu")
		(net 1)
	)
	(segment
		(start 145.0705 75.3085)
		(end 146.0755 75.3085)
		(width 0.3)
		(layer "F.Cu")
		(net 1)
	)
	(segment
		(start 247.287708 77.772)
		(end 248.215708 76.844)
		(width 0.3)
		(layer "F.Cu")
		(net 1)
	)
	(segment
		(start 201.025 169.85)
		(end 201.025 168.684)
		(width 0.2)
		(layer "F.Cu")
		(net 1)
	)
	(segment
		(start 220.7 169.9)
		(end 220.525 169.725)
		(width 0.2)
		(layer "F.Cu")
		(net 1)
	)
	(segment
		(start 182.525 150)
		(end 182.55 149.975)
		(width 0.2)
		(layer "F.Cu")
		(net 1)
	)
	(segment
		(start 246.552709 77.772)
		(end 245.117709 77.772)
		(width 0.3)
		(layer "F.Cu")
		(net 1)
	)
	(segment
		(start 176.025 161.725)
		(end 176.025 163.136)
		(width 0.2)
		(layer "F.Cu")
		(net 1)
	)
	(segment
		(start 179.525 157.875)
		(end 179.5 157.9)
		(width 0.2)
		(layer "F.Cu")
		(net 1)
	)
	(segment
		(start 261.950708 76.838999)
		(end 261.950708 75.76)
		(width 0.3)
		(layer "F.Cu")
		(net 1)
	)
	(segment
		(start 210.525 151.135)
		(end 210.525 152.275)
		(width 0.2)
		(layer "F.Cu")
		(net 1)
	)
	(segment
		(start 305.175 146.765)
		(end 305.175 147.809)
		(width 0.45)
		(layer "F.Cu")
		(net 1)
	)
	(segment
		(start 203.40639 82.857837)
		(end 203.399 82.850447)
		(width 0.2)
		(layer "F.Cu")
		(net 1)
	)
	(segment
		(start 192.52554 141.948436)
		(end 193.250324 141.223652)
		(width 0.125)
		(layer "F.Cu")
		(net 1)
	)
	(segment
		(start 220.95 149.75)
		(end 220.525 150.175)
		(width 0.2)
		(layer "F.Cu")
		(net 1)
	)
	(segment
		(start 222.025 156.685)
		(end 222.025 157.775)
		(width 0.2)
		(layer "F.Cu")
		(net 1)
	)
	(segment
		(start 199.5 152.1)
		(end 199.525 152.075)
		(width 0.2)
		(layer "F.Cu")
		(net 1)
	)
	(segment
		(start 125.033 147.112)
		(end 125.033 148.593)
		(width 0.3)
		(layer "F.Cu")
		(net 1)
	)
	(segment
		(start 196.025 169.874)
		(end 196 169.899)
		(width 0.2)
		(layer "F.Cu")
		(net 1)
	)
	(segment
		(start 213.525 167.525)
		(end 213.5 167.5)
		(width 0.2)
		(layer "F.Cu")
		(net 1)
	)
	(segment
		(start 210.525 167.525)
		(end 210.5 167.5)
		(width 0.2)
		(layer "F.Cu")
		(net 1)
	)
	(segment
		(start 154.4995 80.5595)
		(end 154.5 80.56)
		(width 0.3)
		(layer "F.Cu")
		(net 1)
	)
	(segment
		(start 217.025 161.625)
		(end 217.025 163.135)
		(width 0.2)
		(layer "F.Cu")
		(net 1)
	)
	(segment
		(start 200.675 170.2)
		(end 201.025 169.85)
		(width 0.2)
		(layer "F.Cu")
		(net 1)
	)
	(segment
		(start 304.125 93.86)
		(end 304.125 93.185)
		(width 0.125)
		(layer "F.Cu")
		(net 1)
	)
	(segment
		(start 220.525 169.725)
		(end 220.525 168.684)
		(width 0.2)
		(layer "F.Cu")
		(net 1)
	)
	(segment
		(start 220.525 157.75)
		(end 220.525 156.685)
		(width 0.2)
		(layer "F.Cu")
		(net 1)
	)
	(segment
		(start 298.699 75.04)
		(end 298.699 74.035)
		(width 0.3)
		(layer "F.Cu")
		(net 1)
	)
	(segment
		(start 117.059998 76.8)
		(end 116.135 76.8)
		(width 0.3)
		(layer "F.Cu")
		(net 1)
	)
	(segment
		(start 306.15 149.11)
		(end 305.85 149.11)
		(width 0.125)
		(layer "F.Cu")
		(net 1)
	)
	(segment
		(start 152.5685 89.5585)
		(end 153.5735 89.5585)
		(width 0.3)
		(layer "F.Cu")
		(net 1)
	)
	(segment
		(start 307.518 82.767)
		(end 307.518 83.287)
		(width 0.125)
		(layer "F.Cu")
		(net 1)
	)
	(segment
		(start 226 160)
		(end 225.4 159.4)
		(width 0.3)
		(layer "F.Cu")
		(net 1)
	)
	(segment
		(start 176.025 156.685)
		(end 176.025 155.625)
		(width 0.2)
		(layer "F.Cu")
		(net 1)
	)
	(segment
		(start 225.5 163.16)
		(end 225.525 163.135)
		(width 0.2)
		(layer "F.Cu")
		(net 1)
	)
	(segment
		(start 152.5685 83.5595)
		(end 153.5735 83.5595)
		(width 0.3)
		(layer "F.Cu")
		(net 1)
	)
	(segment
		(start 313.648 163.96)
		(end 314.363 163.96)
		(width 0.2)
		(layer "F.Cu")
		(net 1)
	)
	(segment
		(start 213.525 168.685)
		(end 213.525 167.525)
		(width 0.2)
		(layer "F.Cu")
		(net 1)
	)
	(segment
		(start 186.025 157.875)
		(end 186 157.9)
		(width 0.2)
		(layer "F.Cu")
		(net 1)
	)
	(segment
		(start 220.525 150.175)
		(end 220.525 151.136)
		(width 0.2)
		(layer "F.Cu")
		(net 1)
	)
	(segment
		(start 223.525 157.7)
		(end 223.525 156.684)
		(width 0.2)
		(layer "F.Cu")
		(net 1)
	)
	(segment
		(start 312.169999 119.158999)
		(end 312.169999 118.710001)
		(width 0.2)
		(layer "F.Cu")
		(net 1)
	)
	(segment
		(start 311.714999 118.755001)
		(end 311.74 118.73)
		(width 0.2)
		(layer "F.Cu")
		(net 1)
	)
	(segment
		(start 227.025 149.775)
		(end 227.025 151.136)
		(width 0.2)
		(layer "F.Cu")
		(net 1)
	)
	(segment
		(start 220.5 162)
		(end 220.525 162.025)
		(width 0.2)
		(layer "F.Cu")
		(net 1)
	)
	(segment
		(start 305.85 149.11)
		(end 305.45 149.11)
		(width 0.125)
		(layer "F.Cu")
		(net 1)
	)
	(segment
		(start 196.05 155.425)
		(end 196.025 155.45)
		(width 0.2)
		(layer "F.Cu")
		(net 1)
	)
	(segment
		(start 129.32 108.5)
		(end 129.5 108.32)
		(width 0.2)
		(layer "F.Cu")
		(net 1)
	)
	(segment
		(start 205.575 167.1)
		(end 205.525 167.15)
		(width 0.2)
		(layer "F.Cu")
		(net 1)
	)
	(segment
		(start 311.714999 103.348999)
		(end 311.714999 103.81)
		(width 0.2)
		(layer "F.Cu")
		(net 1)
	)
	(segment
		(start 230.525 152.225)
		(end 230.525 151.134)
		(width 0.2)
		(layer "F.Cu")
		(net 1)
	)
	(segment
		(start 191.025 152.25)
		(end 191.05 152.275)
		(width 0.2)
		(layer "F.Cu")
		(net 1)
	)
	(segment
		(start 255.374 160.026)
		(end 256.523145 160.026)
		(width 0.3)
		(layer "F.Cu")
		(net 1)
	)
	(segment
		(start 108.35 133.51)
		(end 109.505 133.51)
		(width 0.5)
		(layer "F.Cu")
		(net 1)
	)
	(segment
		(start 248.215708 76.844)
		(end 248.215708 75.76)
		(width 0.3)
		(layer "F.Cu")
		(net 1)
	)
	(segment
		(start 196.025 168.685)
		(end 196.025 167.475)
		(width 0.2)
		(layer "F.Cu")
		(net 1)
	)
	(segment
		(start 319.45 156.91)
		(end 317.7 156.91)
		(width 0.55)
		(layer "F.Cu")
		(net 1)
	)
	(segment
		(start 215.47 78.11)
		(end 214.45 78.11)
		(width 0.2)
		(layer "F.Cu")
		(net 1)
	)
	(segment
		(start 230.525 158.025)
		(end 230.525 156.684)
		(width 0.2)
		(layer "F.Cu")
		(net 1)
	)
	(segment
		(start 213.525 161.875)
		(end 213.525 163.136)
		(width 0.2)
		(layer "F.Cu")
		(net 1)
	)
	(segment
		(start 217 161.6)
		(end 217.025 161.625)
		(width 0.2)
		(layer "F.Cu")
		(net 1)
	)
	(segment
		(start 108.05 133.81)
		(end 108.35 133.51)
		(width 0.5)
		(layer "F.Cu")
		(net 1)
	)
	(segment
		(start 319.45 158.51)
		(end 317.7 158.51)
		(width 0.55)
		(layer "F.Cu")
		(net 1)
	)
	(segment
		(start 191.025 151.135)
		(end 191.025 152.25)
		(width 0.2)
		(layer "F.Cu")
		(net 1)
	)
	(segment
		(start 191.025 168.685)
		(end 191.025 167.5)
		(width 0.2)
		(layer "F.Cu")
		(net 1)
	)
	(segment
		(start 213.45 161.8)
		(end 213.525 161.875)
		(width 0.2)
		(layer "F.Cu")
		(net 1)
	)
	(segment
		(start 234.490708 76.838998)
		(end 233.557706 77.772)
		(width 0.3)
		(layer "F.Cu")
		(net 1)
	)
	(segment
		(start 184.525 152.175)
		(end 184.525 151.135)
		(width 0.2)
		(layer "F.Cu")
		(net 1)
	)
	(segment
		(start 178.025 151.135)
		(end 178.025 149.95)
		(width 0.2)
		(layer "F.Cu")
		(net 1)
	)
	(segment
		(start 212.025 163.135)
		(end 212.025 164.325)
		(width 0.2)
		(layer "F.Cu")
		(net 1)
	)
	(segment
		(start 310.314999 120.558999)
		(end 310.808999 120.558999)
		(width 0.2)
		(layer "F.Cu")
		(net 1)
	)
	(segment
		(start 191.025 168.684)
		(end 191.025 169.874)
		(width 0.2)
		(layer "F.Cu")
		(net 1)
	)
	(segment
		(start 191.025 157.875)
		(end 191 157.9)
		(width 0.2)
		(layer "F.Cu")
		(net 1)
	)
	(segment
		(start 319.45 160.91)
		(end 317.7 160.91)
		(width 0.55)
		(layer "F.Cu")
		(net 1)
	)
	(segment
		(start 225.525 157.725)
		(end 225.525 156.684)
		(width 0.2)
		(layer "F.Cu")
		(net 1)
	)
	(segment
		(start 307.55 78.786002)
		(end 307.993999 78.342002)
		(width 0.2)
		(layer "F.Cu")
		(net 1)
	)
	(segment
		(start 191.025 163.136)
		(end 191.025 161.946)
		(width 0.2)
		(layer "F.Cu")
		(net 1)
	)
	(segment
		(start 143.19 148.591)
		(end 143.377 148.778)
		(width 0.3)
		(layer "F.Cu")
		(net 1)
	)
	(segment
		(start 311.714999 106.148999)
		(end 311.714999 105.675001)
		(width 0.2)
		(layer "F.Cu")
		(net 1)
	)
	(segment
		(start 212.025 149.946)
		(end 212.05 149.921)
		(width 0.2)
		(layer "F.Cu")
		(net 1)
	)
	(segment
		(start 193.250324 141.223652)
		(end 193.95 141.923328)
		(width 0.125)
		(layer "F.Cu")
		(net 1)
	)
	(segment
		(start 220 159.8)
		(end 220 159.9)
		(width 0.3)
		(layer "F.Cu")
		(net 1)
	)
	(segment
		(start 113.38 146.86)
		(end 113.38 145.86)
		(width 0.125)
		(layer "F.Cu")
		(net 1)
	)
	(segment
		(start 212.025 164.325)
		(end 212.05 164.35)
		(width 0.2)
		(layer "F.Cu")
		(net 1)
	)
	(segment
		(start 188.025 157.575)
		(end 188.025 156.685)
		(width 0.2)
		(layer "F.Cu")
		(net 1)
	)
	(segment
		(start 215.525 164.325)
		(end 215.525 163.135)
		(width 0.2)
		(layer "F.Cu")
		(net 1)
	)
	(segment
		(start 197.525 151.135)
		(end 197.525 150.125)
		(width 0.2)
		(layer "F.Cu")
		(net 1)
	)
	(segment
		(start 302.825 105.485)
		(end 302.825 104.809)
		(width 0.125)
		(layer "F.Cu")
		(net 1)
	)
	(segment
		(start 201.025 156.685)
		(end 201.025 157.95)
		(width 0.2)
		(layer "F.Cu")
		(net 1)
	)
	(segment
		(start 215.525 167.525)
		(end 215.55 167.5)
		(width 0.2)
		(layer "F.Cu")
		(net 1)
	)
	(segment
		(start 178.025 149.95)
		(end 178 149.925)
		(width 0.2)
		(layer "F.Cu")
		(net 1)
	)
	(segment
		(start 205.525 163.136)
		(end 205.525 161.946)
		(width 0.2)
		(layer "F.Cu")
		(net 1)
	)
	(segment
		(start 236.7 155.51)
		(end 236.96 155.77)
		(width 0.2)
		(layer "F.Cu")
		(net 1)
	)
	(segment
		(start 230.525 163.135)
		(end 230.525 164.275)
		(width 0.2)
		(layer "F.Cu")
		(net 1)
	)
	(segment
		(start 302.98 103.61)
		(end 302.825 103.765)
		(width 0.45)
		(layer "F.Cu")
		(net 1)
	)
	(segment
		(start 215.45 164.4)
		(end 215.525 164.325)
		(width 0.2)
		(layer "F.Cu")
		(net 1)
	)
	(segment
		(start 307.625001 82.66)
		(end 307.518 82.767)
		(width 0.125)
		(layer "F.Cu")
		(net 1)
	)
	(segment
		(start 205.525 156.685)
		(end 205.525 155.425)
		(width 0.2)
		(layer "F.Cu")
		(net 1)
	)
	(segment
		(start 176 170)
		(end 176.025 169.975)
		(width 0.2)
		(layer "F.Cu")
		(net 1)
	)
	(segment
		(start 190.39432 138.432701)
		(end 189.687213 137.725595)
		(width 0.125)
		(layer "F.Cu")
		(net 1)
	)
	(segment
		(start 286.699 74.96)
		(end 286.2 74.96)
		(width 0.3)
		(layer "F.Cu")
		(net 1)
	)
	(segment
		(start 240.8 131.88)
		(end 240.8 131.66)
		(width 0.2)
		(layer "F.Cu")
		(net 1)
	)
	(segment
		(start 112.535 137.91)
		(end 113.04 137.91)
		(width 0.2)
		(layer "F.Cu")
		(net 1)
	)
	(segment
		(start 194.525 169.874)
		(end 194.5 169.899)
		(width 0.2)
		(layer "F.Cu")
		(net 1)
	)
	(segment
		(start 121.46 73.13)
		(end 120.5 74.09)
		(width 0.3)
		(layer "F.Cu")
		(net 1)
	)
	(segment
		(start 152.5685 85.0595)
		(end 153.5735 85.0595)
		(width 0.3)
		(layer "F.Cu")
		(net 1)
	)
	(segment
		(start 246.552709 77.772)
		(end 247.287708 77.772)
		(width 0.3)
		(layer "F.Cu")
		(net 1)
	)
	(segment
		(start 303.1 92.56)
		(end 302.825 92.285)
		(width 0.125)
		(layer "F.Cu")
		(net 1)
	)
	(segment
		(start 189.525 151.135)
		(end 189.525 152.175)
		(width 0.2)
		(layer "F.Cu")
		(net 1)
	)
	(segment
		(start 110.7 151.813)
		(end 110.7 152.585)
		(width 0.2)
		(layer "F.Cu")
		(net 1)
	)
	(segment
		(start 142.52 133.88)
		(end 142.52 132.88)
		(width 0.125)
		(layer "F.Cu")
		(net 1)
	)
	(segment
		(start 258.730708 77.605)
		(end 258.897708 77.772)
		(width 0.3)
		(layer "F.Cu")
		(net 1)
	)
	(segment
		(start 308.625 82.32)
		(end 307.518 81.213)
		(width 0.3)
		(layer "F.Cu")
		(net 1)
	)
	(segment
		(start 319.45 157.71)
		(end 317.7 157.71)
		(width 0.55)
		(layer "F.Cu")
		(net 1)
	)
	(segment
		(start 181.025 151.135)
		(end 181.025 149.975)
		(width 0.2)
		(layer "F.Cu")
		(net 1)
	)
	(segment
		(start 199.949 82.785227)
		(end 199.949 81.85)
		(width 0.2)
		(layer "F.Cu")
		(net 1)
	)
	(segment
		(start 201 161.9)
		(end 201.025 161.925)
		(width 0.2)
		(layer "F.Cu")
		(net 1)
	)
	(segment
		(start 179.525 151.135)
		(end 179.525 149.975)
		(width 0.2)
		(layer "F.Cu")
		(net 1)
	)
	(segment
		(start 152.5685 72.5595)
		(end 153.5735 72.5595)
		(width 0.3)
		(layer "F.Cu")
		(net 1)
	)
	(segment
		(start 121.5 73.13)
		(end 121.46 73.13)
		(width 0.3)
		(layer "F.Cu")
		(net 1)
	)
	(segment
		(start 112.97 132.41)
		(end 112.98 132.4)
		(width 0.2)
		(layer "F.Cu")
		(net 1)
	)
	(segment
		(start 319.45 163.31)
		(end 317.7 163.31)
		(width 0.55)
		(layer "F.Cu")
		(net 1)
	)
	(segment
		(start 312.169999 119.158999)
		(end 312.169999 119.62)
		(width 0.2)
		(layer "F.Cu")
		(net 1)
	)
	(segment
		(start 194.525 163.136)
		(end 194.525 161.946)
		(width 0.2)
		(layer "F.Cu")
		(net 1)
	)
	(segment
		(start 217.025 164.275)
		(end 217.05 164.3)
		(width 0.2)
		(layer "F.Cu")
		(net 1)
	)
	(segment
		(start 197.525 150.125)
		(end 197.55 150.1)
		(width 0.2)
		(layer "F.Cu")
		(net 1)
	)
	(segment
		(start 205.525 155.425)
		(end 205.55 155.4)
		(width 0.2)
		(layer "F.Cu")
		(net 1)
	)
	(segment
		(start 187.65 157.95)
		(end 188.025 157.575)
		(width 0.2)
		(layer "F.Cu")
		(net 1)
	)
	(segment
		(start 204.025 167.525)
		(end 204 167.5)
		(width 0.2)
		(layer "F.Cu")
		(net 1)
	)
	(segment
		(start 186.70861 77.632163)
		(end 186.70861 78.102163)
		(width 0.2)
		(layer "F.Cu")
		(net 1)
	)
	(segment
		(start 303.697 75.04)
		(end 303.697 74.035)
		(width 0.3)
		(layer "F.Cu")
		(net 1)
	)
	(segment
		(start 314.363 167.01)
		(end 315.135 167.01)
		(width 0.2)
		(layer "F.Cu")
		(net 1)
	)
	(segment
		(start 253.4 165.53)
		(end 253.4 162)
		(width 0.3)
		(layer "F.Cu")
		(net 1)
	)
	(segment
		(start 112.535 132.41)
		(end 112.97 132.41)
		(width 0.2)
		(layer "F.Cu")
		(net 1)
	)
	(segment
		(start 304.697 75.04)
		(end 304.697 74.035)
		(width 0.3)
		(layer "F.Cu")
		(net 1)
	)
	(segment
		(start 196.025 163.136)
		(end 196.025 161.946)
		(width 0.2)
		(layer "F.Cu")
		(net 1)
	)
	(segment
		(start 113.38 146.89)
		(end 113.851 147.361)
		(width 0.125)
		(layer "F.Cu")
		(net 1)
	)
	(segment
		(start 223.525 157.7)
		(end 223.525 157.775)
		(width 0.2)
		(layer "F.Cu")
		(net 1)
	)
	(segment
		(start 152.5685 79.0595)
		(end 153.5735 79.0595)
		(width 0.3)
		(layer "F.Cu")
		(net 1)
	)
	(segment
		(start 176.025 150)
		(end 175.95 149.925)
		(width 0.2)
		(layer "F.Cu")
		(net 1)
	)
	(segment
		(start 97.502 152.098)
		(end 97.5 152.1)
		(width 0.2)
		(layer "F.Cu")
		(net 1)
	)
	(segment
		(start 307.993999 78.342002)
		(end 310.075 78.342002)
		(width 0.2)
		(layer "F.Cu")
		(net 1)
	)
	(segment
		(start 302.825 103.765)
		(end 302.825 104.809)
		(width 0.45)
		(layer "F.Cu")
		(net 1)
	)
	(segment
		(start 199.5 152.2)
		(end 199.5 152.1)
		(width 0.2)
		(layer "F.Cu")
		(net 1)
	)
	(segment
		(start 248.968 131.233)
		(end 249.245 131.51)
		(width 0.3)
		(layer "F.Cu")
		(net 1)
	)
	(segment
		(start 220.525 162.025)
		(end 220.525 163.135)
		(width 0.2)
		(layer "F.Cu")
		(net 1)
	)
	(segment
		(start 303.697 75.04)
		(end 304.697 75.04)
		(width 0.3)
		(layer "F.Cu")
		(net 1)
	)
	(segment
		(start 285.248 74.96)
		(end 286.2 74.96)
		(width 0.3)
		(layer "F.Cu")
		(net 1)
	)
	(segment
		(start 309.257 155.76)
		(end 309.257 155.182)
		(width 0.3)
		(layer "F.Cu")
		(net 1)
	)
	(segment
		(start 222.025 152.324)
		(end 222 152.349)
		(width 0.2)
		(layer "F.Cu")
		(net 1)
	)
	(segment
		(start 305.827 150.41)
		(end 305.827 149.133)
		(width 0.125)
		(layer "F.Cu")
		(net 1)
	)
	(segment
		(start 314.363 160.91)
		(end 315.135 160.91)
		(width 0.2)
		(layer "F.Cu")
		(net 1)
	)
	(segment
		(start 310.314999 104.748999)
		(end 310.808999 104.748999)
		(width 0.2)
		(layer "F.Cu")
		(net 1)
	)
	(segment
		(start 225.525 169.725)
		(end 225.55 169.75)
		(width 0.125)
		(layer "F.Cu")
		(net 1)
	)
	(segment
		(start 215.025 168.685)
		(end 215.025 167.525)
		(width 0.2)
		(layer "F.Cu")
		(net 1)
	)
	(segment
		(start 184.525 156.685)
		(end 184.525 157.875)
		(width 0.2)
		(layer "F.Cu")
		(net 1)
	)
	(segment
		(start 311.714999 119.158999)
		(end 311.714999 118.755001)
		(width 0.2)
		(layer "F.Cu")
		(net 1)
	)
	(segment
		(start 215.525 155.675)
		(end 215.525 156.685)
		(width 0.2)
		(layer "F.Cu")
		(net 1)
	)
	(segment
		(start 181.025 161.775)
		(end 181.025 163.136)
		(width 0.2)
		(layer "F.Cu")
		(net 1)
	)
	(segment
		(start 205.525 151.135)
		(end 205.525 152.275)
		(width 0.2)
		(layer "F.Cu")
		(net 1)
	)
	(segment
		(start 219.025 157.75)
		(end 219.025 157.775)
		(width 0.2)
		(layer "F.Cu")
		(net 1)
	)
	(segment
		(start 210.525 152.275)
		(end 210.5 152.3)
		(width 0.2)
		(layer "F.Cu")
		(net 1)
	)
	(segment
		(start 107.6 151.813)
		(end 107.6 151.2)
		(width 0.2)
		(layer "F.Cu")
		(net 1)
	)
	(segment
		(start 182.525 151.135)
		(end 182.525 150)
		(width 0.2)
		(layer "F.Cu")
		(net 1)
	)
	(segment
		(start 308.019 82.754)
		(end 307.925001 82.66)
		(width 0.125)
		(layer "F.Cu")
		(net 1)
	)
	(segment
		(start 112.4 149.88)
		(end 112.89 149.88)
		(width 0.125)
		(layer "F.Cu")
		(net 1)
	)
	(segment
		(start 215.025 167.525)
		(end 215 167.5)
		(width 0.2)
		(layer "F.Cu")
		(net 1)
	)
	(segment
		(start 196.025 168.684)
		(end 196.025 169.874)
		(width 0.2)
		(layer "F.Cu")
		(net 1)
	)
	(segment
		(start 215.025 161.775)
		(end 215.025 163.135)
		(width 0.2)
		(layer "F.Cu")
		(net 1)
	)
	(segment
		(start 181.025 168.684)
		(end 181.025 169.874)
		(width 0.2)
		(layer "F.Cu")
		(net 1)
	)
	(segment
		(start 191.081627 138.453915)
		(end 191.469829 138.065713)
		(width 0.125)
		(layer "F.Cu")
		(net 1)
	)
	(segment
		(start 197.70861 77.632163)
		(end 197.70861 78.102163)
		(width 0.2)
		(layer "F.Cu")
		(net 1)
	)
	(segment
		(start 215.15 161.65)
		(end 215.025 161.775)
		(width 0.2)
		(layer "F.Cu")
		(net 1)
	)
	(segment
		(start 210.525 161.875)
		(end 210.525 163.136)
		(width 0.2)
		(layer "F.Cu")
		(net 1)
	)
	(segment
		(start 214.68 126.249)
		(end 214.68 127.727)
		(width 0.2)
		(layer "F.Cu")
		(net 1)
	)
	(segment
		(start 311.714999 103.348999)
		(end 311.714999 102.945001)
		(width 0.2)
		(layer "F.Cu")
		(net 1)
	)
	(segment
		(start 191.025 169.874)
		(end 191 169.899)
		(width 0.2)
		(layer "F.Cu")
		(net 1)
	)
	(segment
		(start 181.1 161.7)
		(end 181.025 161.775)
		(width 0.2)
		(layer "F.Cu")
		(net 1)
	)
	(segment
		(start 208.525 167.575)
		(end 208.525 168.685)
		(width 0.2)
		(layer "F.Cu")
		(net 1)
	)
	(segment
		(start 176.025 151.135)
		(end 176.025 150)
		(width 0.2)
		(layer "F.Cu")
		(net 1)
	)
	(segment
		(start 240.8 131.66)
		(end 239.95 130.81)
		(width 0.2)
		(layer "F.Cu")
		(net 1)
	)
	(segment
		(start 305.827 149.133)
		(end 305.85 149.11)
		(width 0.125)
		(layer "F.Cu")
		(net 1)
	)
	(segment
		(start 181.025 156.685)
		(end 181.025 157.875)
		(width 0.2)
		(layer "F.Cu")
		(net 1)
	)
	(segment
		(start 152.5685 82.0595)
		(end 153.5735 82.0595)
		(width 0.3)
		(layer "F.Cu")
		(net 1)
	)
	(segment
		(start 243.077 127.203)
		(end 243.57 126.71)
		(width 0.3)
		(layer "F.Cu")
		(net 1)
	)
	(segment
		(start 210.525 168.685)
		(end 210.525 167.525)
		(width 0.2)
		(layer "F.Cu")
		(net 1)
	)
	(segment
		(start 153.5735 80.5595)
		(end 154.4995 80.5595)
		(width 0.3)
		(layer "F.Cu")
		(net 1)
	)
	(segment
		(start 222.025 151.134)
		(end 222.025 152.324)
		(width 0.2)
		(layer "F.Cu")
		(net 1)
	)
	(segment
		(start 313.898 167.01)
		(end 314.363 167.01)
		(width 0.2)
		(layer "F.Cu")
		(net 1)
	)
	(segment
		(start 217.025 168.685)
		(end 217.025 167.575)
		(width 0.2)
		(layer "F.Cu")
		(net 1)
	)
	(segment
		(start 305.45 149.11)
		(end 305.175 148.835)
		(width 0.125)
		(layer "F.Cu")
		(net 1)
	)
	(segment
		(start 218.8 149.8)
		(end 219.025 150.025)
		(width 0.2)
		(layer "F.Cu")
		(net 1)
	)
	(segment
		(start 306.65 155.23)
		(end 306.65 154.31)
		(width 0.125)
		(layer "F.Cu")
		(net 1)
	)
	(segment
		(start 212.025 155.525)
		(end 212 155.5)
		(width 0.2)
		(layer "F.Cu")
		(net 1)
	)
	(segment
		(start 213.55 151.161)
		(end 213.525 151.136)
		(width 0.2)
		(layer "F.Cu")
		(net 1)
	)
	(segment
		(start 192.525539 141.948436)
		(end 192.52554 141.948436)
		(width 0.125)
		(layer "F.Cu")
		(net 1)
	)
	(segment
		(start 236.7 154.94)
		(end 238.03 154.94)
		(width 0.2)
		(layer "F.Cu")
		(net 1)
	)
	(segment
		(start 230.7 158.2)
		(end 230.525 158.025)
		(width 0.2)
		(layer "F.Cu")
		(net 1)
	)
	(segment
		(start 110.7 152.585)
		(end 110.7 153.3)
		(width 0.2)
		(layer "F.Cu")
		(net 1)
	)
	(segment
		(start 210.525 164.325)
		(end 210.5 164.35)
		(width 0.2)
		(layer "F.Cu")
		(net 1)
	)
	(segment
		(start 114.834999 73.925)
		(end 114.834999 75.5)
		(width 0.3)
		(layer "F.Cu")
		(net 1)
	)
	(segment
		(start 312.169999 103.348999)
		(end 312.169999 103.81)
		(width 0.2)
		(layer "F.Cu")
		(net 1)
	)
	(segment
		(start 248.968 130.138)
		(end 248.968 131.233)
		(width 0.3)
		(layer "F.Cu")
		(net 1)
	)
	(segment
		(start 177.9 157.9)
		(end 178.025 157.775)
		(width 0.2)
		(layer "F.Cu")
		(net 1)
	)
	(segment
		(start 189.525 157.675)
		(end 189.525 156.685)
		(width 0.2)
		(layer "F.Cu")
		(net 1)
	)
	(segment
		(start 215.7 155.5)
		(end 215.525 155.675)
		(width 0.2)
		(layer "F.Cu")
		(net 1)
	)
	(segment
		(start 194.525 168.685)
		(end 194.525 167.45)
		(width 0.2)
		(layer "F.Cu")
		(net 1)
	)
	(segment
		(start 305.33 146.61)
		(end 305.175 146.765)
		(width 0.45)
		(layer "F.Cu")
		(net 1)
	)
	(segment
		(start 304.125 107.41)
		(end 304.125 106.785)
		(width 0.125)
		(layer "F.Cu")
		(net 1)
	)
	(segment
		(start 225.25 149.85)
		(end 225.525 150.125)
		(width 0.2)
		(layer "F.Cu")
		(net 1)
	)
	(segment
		(start 152.5685 88.0585)
		(end 153.5735 88.0585)
		(width 0.3)
		(layer "F.Cu")
		(net 1)
	)
	(segment
		(start 315.135 160.91)
		(end 319.448 160.91)
		(width 0.2)
		(layer "F.Cu")
		(net 1)
	)
	(segment
		(start 230.88 164.63)
		(end 231.31 164.63)
		(width 0.2)
		(layer "F.Cu")
		(net 1)
	)
	(segment
		(start 176.525 156.685)
		(end 176.525 155.575)
		(width 0.2)
		(layer "F.Cu")
		(net 1)
	)
	(segment
		(start 230.525 169.865)
		(end 230.5 169.89)
		(width 0.2)
		(layer "F.Cu")
		(net 1)
	)
	(segment
		(start 217.025 163.135)
		(end 217.025 164.275)
		(width 0.2)
		(layer "F.Cu")
		(net 1)
	)
	(segment
		(start 307.518 81.213)
		(end 307.518 80.538)
		(width 0.3)
		(layer "F.Cu")
		(net 1)
	)
	(segment
		(start 215.525 149.946)
		(end 215.55 149.921)
		(width 0.2)
		(layer "F.Cu")
		(net 1)
	)
	(segment
		(start 220.525 157.75)
		(end 220.525 157.775)
		(width 0.2)
		(layer "F.Cu")
		(net 1)
	)
	(segment
		(start 182.525 156.685)
		(end 182.525 157.875)
		(width 0.2)
		(layer "F.Cu")
		(net 1)
	)
	(segment
		(start 159.05 162.547)
		(end 159.05 160.86)
		(width 0.2)
		(layer "F.Cu")
		(net 1)
	)
	(segment
		(start 186.025 156.685)
		(end 186.025 157.875)
		(width 0.2)
		(layer "F.Cu")
		(net 1)
	)
	(segment
		(start 300.198 75.04)
		(end 300.198 74.035)
		(width 0.3)
		(layer "F.Cu")
		(net 1)
	)
	(segment
		(start 223.525 152.324)
		(end 223.5 152.349)
		(width 0.2)
		(layer "F.Cu")
		(net 1)
	)
	(segment
		(start 183.70861 72.802163)
		(end 184.70861 72.802163)
		(width 0.2)
		(layer "F.Cu")
		(net 1)
	)
	(segment
		(start 111.763 137.91)
		(end 112.535 137.91)
		(width 0.2)
		(layer "F.Cu")
		(net 1)
	)
	(segment
		(start 191.025 156.685)
		(end 191.025 157.875)
		(width 0.2)
		(layer "F.Cu")
		(net 1)
	)
	(segment
		(start 182.525 157.875)
		(end 182.5 157.9)
		(width 0.2)
		(layer "F.Cu")
		(net 1)
	)
	(segment
		(start 186.025 152.175)
		(end 185.975 152.225)
		(width 0.2)
		(layer "F.Cu")
		(net 1)
	)
	(segment
		(start 196.025 161.946)
		(end 196.05 161.921)
		(width 0.2)
		(layer "F.Cu")
		(net 1)
	)
	(segment
		(start 191.025 161.946)
		(end 191.05 161.921)
		(width 0.2)
		(layer "F.Cu")
		(net 1)
	)
	(segment
		(start 176 161.7)
		(end 176.025 161.725)
		(width 0.2)
		(layer "F.Cu")
		(net 1)
	)
	(segment
		(start 112.4 144.84)
		(end 113.4 144.84)
		(width 0.125)
		(layer "F.Cu")
		(net 1)
	)
	(segment
		(start 201.025 152.175)
		(end 201.025 151.135)
		(width 0.2)
		(layer "F.Cu")
		(net 1)
	)
	(segment
		(start 121.4 147.841)
		(end 120.92 147.361)
		(width 0.125)
		(layer "F.Cu")
		(net 1)
	)
	(segment
		(start 199.525 156.685)
		(end 199.525 157.875)
		(width 0.2)
		(layer "F.Cu")
		(net 1)
	)
	(segment
		(start 112.535 132.41)
		(end 111.763 132.41)
		(width 0.2)
		(layer "F.Cu")
		(net 1)
	)
	(segment
		(start 217.525 157.65)
		(end 217.525 157.775)
		(width 0.2)
		(layer "F.Cu")
		(net 1)
	)
	(segment
		(start 220.6 159.2)
		(end 220 159.8)
		(width 0.3)
		(layer "F.Cu")
		(net 1)
	)
	(segment
		(start 215.525 151.136)
		(end 215.525 149.946)
		(width 0.2)
		(layer "F.Cu")
		(net 1)
	)
	(segment
		(start 210.525 163.135)
		(end 210.525 164.325)
		(width 0.2)
		(layer "F.Cu")
		(net 1)
	)
	(segment
		(start 241.75 127.83)
		(end 242.948 127.83)
		(width 0.125)
		(layer "F.Cu")
		(net 1)
	)
	(segment
		(start 199.525 152.075)
		(end 199.525 151.135)
		(width 0.2)
		(layer "F.Cu")
		(net 1)
	)
	(segment
		(start 125.033 148.593)
		(end 125.22 148.78)
		(width 0.3)
		(layer "F.Cu")
		(net 1)
	)
	(segment
		(start 220.525 157.775)
		(end 220.5 157.8)
		(width 0.2)
		(layer "F.Cu")
		(net 1)
	)
	(segment
		(start 203.399 82.850447)
		(end 203.399 81.85)
		(width 0.2)
		(layer "F.Cu")
		(net 1)
	)
	(segment
		(start 306.475 150.41)
		(end 306.475 149.435)
		(width 0.125)
		(layer "F.Cu")
		(net 1)
	)
	(segment
		(start 194.525 168.684)
		(end 194.525 169.874)
		(width 0.2)
		(layer "F.Cu")
		(net 1)
	)
	(segment
		(start 186.025 151.135)
		(end 186.025 152.175)
		(width 0.2)
		(layer "F.Cu")
		(net 1)
	)
	(segment
		(start 217.525 157.775)
		(end 217.5 157.8)
		(width 0.2)
		(layer "F.Cu")
		(net 1)
	)
	(segment
		(start 217.525 157.65)
		(end 217.525 156.685)
		(width 0.2)
		(layer "F.Cu")
		(net 1)
	)
	(segment
		(start 234.490708 75.76)
		(end 234.490708 76.838998)
		(width 0.3)
		(layer "F.Cu")
		(net 1)
	)
	(segment
		(start 176.525 155.575)
		(end 176.6 155.5)
		(width 0.2)
		(layer "F.Cu")
		(net 1)
	)
	(segment
		(start 120.687 75.758)
		(end 120.687 74.277)
		(width 0.3)
		(layer "F.Cu")
		(net 1)
	)
	(segment
		(start 212 161.45)
		(end 212.025 161.475)
		(width 0.2)
		(layer "F.Cu")
		(net 1)
	)
	(segment
		(start 315.135 163.96)
		(end 314.363 163.96)
		(width 0.2)
		(layer "F.Cu")
		(net 1)
	)
	(segment
		(start 179.525 156.685)
		(end 179.525 157.875)
		(width 0.2)
		(layer "F.Cu")
		(net 1)
	)
	(segment
		(start 113.4 149.88)
		(end 112.89 149.88)
		(width 0.125)
		(layer "F.Cu")
		(net 1)
	)
	(segment
		(start 181.025 157.875)
		(end 181 157.9)
		(width 0.2)
		(layer "F.Cu")
		(net 1)
	)
	(segment
		(start 304.125 106.785)
		(end 302.825 105.485)
		(width 0.125)
		(layer "F.Cu")
		(net 1)
	)
	(segment
		(start 311.714999 121.958999)
		(end 311.714999 121.485001)
		(width 0.2)
		(layer "F.Cu")
		(net 1)
	)
	(segment
		(start 226 160)
		(end 225.4 160.6)
		(width 0.3)
		(layer "F.Cu")
		(net 1)
	)
	(segment
		(start 305.175 148.835)
		(end 305.175 147.809)
		(width 0.125)
		(layer "F.Cu")
		(net 1)
	)
	(segment
		(start 130.4 87.497001)
		(end 130.4 85.810001)
		(width 0.2)
		(layer "F.Cu")
		(net 1)
	)
	(segment
		(start 219.025 157.775)
		(end 219 157.8)
		(width 0.2)
		(layer "F.Cu")
		(net 1)
	)
	(segment
		(start 304.125 93.185)
		(end 303.5 92.56)
		(width 0.125)
		(layer "F.Cu")
		(net 1)
	)
	(segment
		(start 217.525 151.136)
		(end 217.525 149.946)
		(width 0.2)
		(layer "F.Cu")
		(net 1)
	)
	(segment
		(start 97.502 151.472)
		(end 97.502 150.7)
		(width 0.2)
		(layer "F.Cu")
		(net 1)
	)
	(segment
		(start 204.025 168.685)
		(end 204.025 167.525)
		(width 0.2)
		(layer "F.Cu")
		(net 1)
	)
	(segment
		(start 201.05 152.2)
		(end 201.025 152.175)
		(width 0.2)
		(layer "F.Cu")
		(net 1)
	)
	(segment
		(start 233.557706 77.772)
		(end 232.822707 77.772)
		(width 0.3)
		(layer "F.Cu")
		(net 1)
	)
	(segment
		(start 258.897708 77.772)
		(end 260.282708 77.772)
		(width 0.3)
		(layer "F.Cu")
		(net 1)
	)
	(via
		(at 141.8 104.4)
		(size 0.45)
		(drill 0.1)
		(layers "F.Cu" "B.Cu")
		(remove_unused_layers yes)
		(keep_end_layers yes)
		(zone_layer_connections "In1.Cu" "In4.Cu" "In6.Cu")
		(teardrops
			(best_length_ratio 0.4)
			(max_length 1)
			(best_width_ratio 0.9)
			(max_width 2)
			(curved_edges yes)
			(filter_ratio 0.9)
			(enabled yes)
			(allow_two_segments yes)
			(prefer_zone_connections yes)
		)
		(net 1)
	)
	(via
		(at 149.45 134.86)
		(size 0.45)
		(drill 0.1)
		(layers "F.Cu" "B.Cu")
		(remove_unused_layers yes)
		(keep_end_layers yes)
		(zone_layer_connections "In1.Cu" "In4.Cu" "In6.Cu")
		(teardrops
			(best_length_ratio 0.4)
			(max_length 1)
			(best_width_ratio 0.9)
			(max_width 2)
			(curved_edges yes)
			(filter_ratio 0.9)
			(enabled yes)
			(allow_two_segments yes)
			(prefer_zone_connections yes)
		)
		(net 1)
	)
	(via
		(at 113.45 69.16)
		(size 0.45)
		(drill 0.1)
		(layers "F.Cu" "B.Cu")
		(remove_unused_layers yes)
		(keep_end_layers yes)
		(zone_layer_connections "In1.Cu" "In4.Cu" "In6.Cu")
		(teardrops
			(best_length_ratio 0.4)
			(max_length 1)
			(best_width_ratio 0.9)
			(max_width 2)
			(curved_edges yes)
			(filter_ratio 0.9)
			(enabled yes)
			(allow_two_segments yes)
			(prefer_zone_connections yes)
		)
		(net 1)
	)
	(via
		(at 254.95 170.81)
		(size 0.45)
		(drill 0.1)
		(layers "F.Cu" "B.Cu")
		(remove_unused_layers yes)
		(keep_end_layers yes)
		(zone_layer_connections "In1.Cu" "In4.Cu" "In6.Cu")
		(teardrops
			(best_length_ratio 0.4)
			(max_length 1)
			(best_width_ratio 0.9)
			(max_width 2)
			(curved_edges yes)
			(filter_ratio 0.9)
			(enabled yes)
			(allow_two_segments yes)
			(prefer_zone_connections yes)
		)
		(net 1)
	)
	(via
		(at 132.3 71.51)
		(size 0.45)
		(drill 0.1)
		(layers "F.Cu" "B.Cu")
		(remove_unused_layers yes)
		(keep_end_layers yes)
		(zone_layer_connections "In1.Cu" "In4.Cu" "In6.Cu")
		(teardrops
			(best_length_ratio 0.4)
			(max_length 1)
			(best_width_ratio 0.9)
			(max_width 2)
			(curved_edges yes)
			(filter_ratio 0.9)
			(enabled yes)
			(allow_two_segments yes)
			(prefer_zone_connections yes)
		)
		(net 1)
	)
	(via
		(at 192.45 68.81)
		(size 0.45)
		(drill 0.1)
		(layers "F.Cu" "B.Cu")
		(remove_unused_layers yes)
		(keep_end_layers yes)
		(free yes)
		(zone_layer_connections "In1.Cu" "In4.Cu" "In6.Cu")
		(teardrops
			(best_length_ratio 0.4)
			(max_length 1)
			(best_width_ratio 0.9)
			(max_width 2)
			(curved_edges yes)
			(filter_ratio 0.9)
			(enabled yes)
			(allow_two_segments yes)
			(prefer_zone_connections yes)
		)
		(net 1)
	)
	(via
		(at 177.18 99.36)
		(size 0.45)
		(drill 0.1)
		(layers "F.Cu" "B.Cu")
		(remove_unused_layers yes)
		(keep_end_layers yes)
		(zone_layer_connections "In1.Cu" "In4.Cu" "In6.Cu")
		(teardrops
			(best_length_ratio 0.4)
			(max_length 1)
			(best_width_ratio 0.9)
			(max_width 2)
			(curved_edges yes)
			(filter_ratio 0.9)
			(enabled yes)
			(allow_two_segments yes)
			(prefer_zone_connections yes)
		)
		(net 1)
	)
	(via
		(at 289.45 155.81)
		(size 0.45)
		(drill 0.1)
		(layers "F.Cu" "B.Cu")
		(remove_unused_layers yes)
		(keep_end_layers yes)
		(zone_layer_connections "In1.Cu" "In4.Cu" "In6.Cu")
		(teardrops
			(best_length_ratio 0.4)
			(max_length 1)
			(best_width_ratio 0.9)
			(max_width 2)
			(curved_edges yes)
			(filter_ratio 0.9)
			(enabled yes)
			(allow_two_segments yes)
			(prefer_zone_connections yes)
		)
		(net 1)
	)
	(via
		(at 254.95 114.31)
		(size 0.45)
		(drill 0.1)
		(layers "F.Cu" "B.Cu")
		(remove_unused_layers yes)
		(keep_end_layers yes)
		(zone_layer_connections "In1.Cu" "In4.Cu" "In6.Cu")
		(teardrops
			(best_length_ratio 0.4)
			(max_length 1)
			(best_width_ratio 0.9)
			(max_width 2)
			(curved_edges yes)
			(filter_ratio 0.9)
			(enabled yes)
			(allow_two_segments yes)
			(prefer_zone_connections yes)
		)
		(net 1)
	)
	(via
		(at 263.95 118.81)
		(size 0.45)
		(drill 0.1)
		(layers "F.Cu" "B.Cu")
		(remove_unused_layers yes)
		(keep_end_layers yes)
		(zone_layer_connections "In1.Cu" "In4.Cu" "In6.Cu")
		(teardrops
			(best_length_ratio 0.4)
			(max_length 1)
			(best_width_ratio 0.9)
			(max_width 2)
			(curved_edges yes)
			(filter_ratio 0.9)
			(enabled yes)
			(allow_two_segments yes)
			(prefer_zone_connections yes)
		)
		(net 1)
	)
	(via
		(at 265.45 108.31)
		(size 0.45)
		(drill 0.1)
		(layers "F.Cu" "B.Cu")
		(remove_unused_layers yes)
		(keep_end_layers yes)
		(zone_layer_connections "In1.Cu" "In4.Cu" "In6.Cu")
		(teardrops
			(best_length_ratio 0.4)
			(max_length 1)
			(best_width_ratio 0.9)
			(max_width 2)
			(curved_edges yes)
			(filter_ratio 0.9)
			(enabled yes)
			(allow_two_segments yes)
			(prefer_zone_connections yes)
		)
		(net 1)
	)
	(via
		(at 315.4645 115.4465)
		(size 0.45)
		(drill 0.1)
		(layers "F.Cu" "B.Cu")
		(remove_unused_layers yes)
		(keep_end_layers yes)
		(free yes)
		(zone_layer_connections "In1.Cu" "In4.Cu" "In6.Cu")
		(teardrops
			(best_length_ratio 0.4)
			(max_length 1)
			(best_width_ratio 0.9)
			(max_width 2)
			(curved_edges yes)
			(filter_ratio 0.9)
			(enabled yes)
			(allow_two_segments yes)
			(prefer_zone_connections yes)
		)
		(net 1)
	)
	(via
		(at 296.45 105.31)
		(size 0.45)
		(drill 0.1)
		(layers "F.Cu" "B.Cu")
		(remove_unused_layers yes)
		(keep_end_layers yes)
		(zone_layer_connections "In1.Cu" "In4.Cu" "In6.Cu")
		(teardrops
			(best_length_ratio 0.4)
			(max_length 1)
			(best_width_ratio 0.9)
			(max_width 2)
			(curved_edges yes)
			(filter_ratio 0.9)
			(enabled yes)
			(allow_two_segments yes)
			(prefer_zone_connections yes)
		)
		(net 1)
	)
	(via
		(at 200.45 103.31)
		(size 0.45)
		(drill 0.1)
		(layers "F.Cu" "B.Cu")
		(remove_unused_layers yes)
		(keep_end_layers yes)
		(zone_layer_connections "In1.Cu" "In4.Cu" "In6.Cu")
		(teardrops
			(best_length_ratio 0.4)
			(max_length 1)
			(best_width_ratio 0.9)
			(max_width 2)
			(curved_edges yes)
			(filter_ratio 0.9)
			(enabled yes)
			(allow_two_segments yes)
			(prefer_zone_connections yes)
		)
		(net 1)
	)
	(via
		(at 278.95 138.31)
		(size 0.45)
		(drill 0.1)
		(layers "F.Cu" "B.Cu")
		(remove_unused_layers yes)
		(keep_end_layers yes)
		(zone_layer_connections "In1.Cu" "In4.Cu" "In6.Cu")
		(teardrops
			(best_length_ratio 0.4)
			(max_length 1)
			(best_width_ratio 0.9)
			(max_width 2)
			(curved_edges yes)
			(filter_ratio 0.9)
			(enabled yes)
			(allow_two_segments yes)
			(prefer_zone_connections yes)
		)
		(net 1)
	)
	(via
		(at 101.31 159.62)
		(size 0.45)
		(drill 0.1)
		(layers "F.Cu" "B.Cu")
		(remove_unused_layers yes)
		(keep_end_layers yes)
		(zone_layer_connections "In1.Cu" "In4.Cu" "In6.Cu")
		(teardrops
			(best_length_ratio 0.4)
			(max_length 1)
			(best_width_ratio 0.9)
			(max_width 2)
			(curved_edges yes)
			(filter_ratio 0.9)
			(enabled yes)
			(allow_two_segments yes)
			(prefer_zone_connections yes)
		)
		(net 1)
	)
	(via
		(at 204.7 88.81)
		(size 0.45)
		(drill 0.1)
		(layers "F.Cu" "B.Cu")
		(remove_unused_layers yes)
		(keep_end_layers yes)
		(zone_layer_connections "In1.Cu" "In4.Cu" "In6.Cu")
		(teardrops
			(best_length_ratio 0.4)
			(max_length 1)
			(best_width_ratio 0.9)
			(max_width 2)
			(curved_edges yes)
			(filter_ratio 0.9)
			(enabled yes)
			(allow_two_segments yes)
			(prefer_zone_connections yes)
		)
		(net 1)
	)
	(via
		(at 166.775 162.525)
		(size 0.45)
		(drill 0.1)
		(layers "F.Cu" "B.Cu")
		(teardrops
			(best_length_ratio 0.4)
			(max_length 1)
			(best_width_ratio 0.9)
			(max_width 2)
			(curved_edges yes)
			(filter_ratio 0.9)
			(enabled yes)
			(allow_two_segments yes)
			(prefer_zone_connections yes)
		)
		(net 1)
	)
	(via
		(at 156.95 89.31)
		(size 0.45)
		(drill 0.1)
		(layers "F.Cu" "B.Cu")
		(remove_unused_layers yes)
		(keep_end_layers yes)
		(zone_layer_connections "In1.Cu" "In4.Cu" "In6.Cu")
		(teardrops
			(best_length_ratio 0.4)
			(max_length 1)
			(best_width_ratio 0.9)
			(max_width 2)
			(curved_edges yes)
			(filter_ratio 0.9)
			(enabled yes)
			(allow_two_segments yes)
			(prefer_zone_connections yes)
		)
		(net 1)
	)
	(via
		(at 272.95 170.81)
		(size 0.45)
		(drill 0.1)
		(layers "F.Cu" "B.Cu")
		(remove_unused_layers yes)
		(keep_end_layers yes)
		(zone_layer_connections "In1.Cu" "In4.Cu" "In6.Cu")
		(teardrops
			(best_length_ratio 0.4)
			(max_length 1)
			(best_width_ratio 0.9)
			(max_width 2)
			(curved_edges yes)
			(filter_ratio 0.9)
			(enabled yes)
			(allow_two_segments yes)
			(prefer_zone_connections yes)
		)
		(net 1)
	)
	(via
		(at 163.95 70.31)
		(size 0.45)
		(drill 0.1)
		(layers "F.Cu" "B.Cu")
		(remove_unused_layers yes)
		(keep_end_layers yes)
		(zone_layer_connections "In1.Cu" "In4.Cu" "In6.Cu")
		(teardrops
			(best_length_ratio 0.4)
			(max_length 1)
			(best_width_ratio 0.9)
			(max_width 2)
			(curved_edges yes)
			(filter_ratio 0.9)
			(enabled yes)
			(allow_two_segments yes)
			(prefer_zone_connections yes)
		)
		(net 1)
	)
	(via
		(at 289.45 94.31)
		(size 0.45)
		(drill 0.1)
		(layers "F.Cu" "B.Cu")
		(remove_unused_layers yes)
		(keep_end_layers yes)
		(zone_layer_connections "In1.Cu" "In4.Cu" "In6.Cu")
		(teardrops
			(best_length_ratio 0.4)
			(max_length 1)
			(best_width_ratio 0.9)
			(max_width 2)
			(curved_edges yes)
			(filter_ratio 0.9)
			(enabled yes)
			(allow_two_segments yes)
			(prefer_zone_connections yes)
		)
		(net 1)
	)
	(via
		(at 96.95 93.81)
		(size 0.45)
		(drill 0.1)
		(layers "F.Cu" "B.Cu")
		(remove_unused_layers yes)
		(keep_end_layers yes)
		(zone_layer_connections "In1.Cu" "In4.Cu" "In6.Cu")
		(teardrops
			(best_length_ratio 0.4)
			(max_length 1)
			(best_width_ratio 0.9)
			(max_width 2)
			(curved_edges yes)
			(filter_ratio 0.9)
			(enabled yes)
			(allow_two_segments yes)
			(prefer_zone_connections yes)
		)
		(net 1)
	)
	(via
		(at 97.28 169.47)
		(size 0.45)
		(drill 0.1)
		(layers "F.Cu" "B.Cu")
		(remove_unused_layers yes)
		(keep_end_layers yes)
		(zone_layer_connections "In1.Cu" "In4.Cu" "In6.Cu")
		(teardrops
			(best_length_ratio 0.4)
			(max_length 1)
			(best_width_ratio 0.9)
			(max_width 2)
			(curved_edges yes)
			(filter_ratio 0.9)
			(enabled yes)
			(allow_two_segments yes)
			(prefer_zone_connections yes)
		)
		(net 1)
	)
	(via
		(at 252.45 166.41)
		(size 0.45)
		(drill 0.1)
		(layers "F.Cu" "B.Cu")
		(remove_unused_layers yes)
		(keep_end_layers yes)
		(zone_layer_connections "In1.Cu" "In4.Cu" "In6.Cu")
		(teardrops
			(best_length_ratio 0.4)
			(max_length 1)
			(best_width_ratio 0.9)
			(max_width 2)
			(curved_edges yes)
			(filter_ratio 0.9)
			(enabled yes)
			(allow_two_segments yes)
			(prefer_zone_connections yes)
		)
		(net 1)
	)
	(via
		(at 312.0895 134.21)
		(size 0.45)
		(drill 0.1)
		(layers "F.Cu" "B.Cu")
		(remove_unused_layers yes)
		(keep_end_layers yes)
		(zone_layer_connections "In1.Cu" "In4.Cu" "In6.Cu")
		(teardrops
			(best_length_ratio 0.4)
			(max_length 1)
			(best_width_ratio 0.9)
			(max_width 2)
			(curved_edges yes)
			(filter_ratio 0.9)
			(enabled yes)
			(allow_two_segments yes)
			(prefer_zone_connections yes)
		)
		(net 1)
	)
	(via
		(at 279.45 113.81)
		(size 0.45)
		(drill 0.1)
		(layers "F.Cu" "B.Cu")
		(remove_unused_layers yes)
		(keep_end_layers yes)
		(zone_layer_connections "In1.Cu" "In4.Cu" "In6.Cu")
		(teardrops
			(best_length_ratio 0.4)
			(max_length 1)
			(best_width_ratio 0.9)
			(max_width 2)
			(curved_edges yes)
			(filter_ratio 0.9)
			(enabled yes)
			(allow_two_segments yes)
			(prefer_zone_connections yes)
		)
		(net 1)
	)
	(via
		(at 133.45 165.81)
		(size 0.45)
		(drill 0.1)
		(layers "F.Cu" "B.Cu")
		(remove_unused_layers yes)
		(keep_end_layers yes)
		(zone_layer_connections "In1.Cu" "In4.Cu" "In6.Cu")
		(teardrops
			(best_length_ratio 0.4)
			(max_length 1)
			(best_width_ratio 0.9)
			(max_width 2)
			(curved_edges yes)
			(filter_ratio 0.9)
			(enabled yes)
			(allow_two_segments yes)
			(prefer_zone_connections yes)
		)
		(net 1)
	)
	(via
		(at 153.45 140.86)
		(size 0.45)
		(drill 0.1)
		(layers "F.Cu" "B.Cu")
		(remove_unused_layers yes)
		(keep_end_layers yes)
		(zone_layer_connections "In1.Cu" "In4.Cu" "In6.Cu")
		(teardrops
			(best_length_ratio 0.4)
			(max_length 1)
			(best_width_ratio 0.9)
			(max_width 2)
			(curved_edges yes)
			(filter_ratio 0.9)
			(enabled yes)
			(allow_two_segments yes)
			(prefer_zone_connections yes)
		)
		(net 1)
	)
	(via
		(at 251.95 123.31)
		(size 0.45)
		(drill 0.1)
		(layers "F.Cu" "B.Cu")
		(remove_unused_layers yes)
		(keep_end_layers yes)
		(zone_layer_connections "In1.Cu" "In4.Cu" "In6.Cu")
		(teardrops
			(best_length_ratio 0.4)
			(max_length 1)
			(best_width_ratio 0.9)
			(max_width 2)
			(curved_edges yes)
			(filter_ratio 0.9)
			(enabled yes)
			(allow_two_segments yes)
			(prefer_zone_connections yes)
		)
		(net 1)
	)
	(via
		(at 285.45 113.81)
		(size 0.45)
		(drill 0.1)
		(layers "F.Cu" "B.Cu")
		(remove_unused_layers yes)
		(keep_end_layers yes)
		(zone_layer_connections "In1.Cu" "In4.Cu" "In6.Cu")
		(teardrops
			(best_length_ratio 0.4)
			(max_length 1)
			(best_width_ratio 0.9)
			(max_width 2)
			(curved_edges yes)
			(filter_ratio 0.9)
			(enabled yes)
			(allow_two_segments yes)
			(prefer_zone_connections yes)
		)
		(net 1)
	)
	(via
		(at 95.45 126.81)
		(size 0.45)
		(drill 0.1)
		(layers "F.Cu" "B.Cu")
		(remove_unused_layers yes)
		(keep_end_layers yes)
		(zone_layer_connections "In1.Cu" "In4.Cu" "In6.Cu")
		(teardrops
			(best_length_ratio 0.4)
			(max_length 1)
			(best_width_ratio 0.9)
			(max_width 2)
			(curved_edges yes)
			(filter_ratio 0.9)
			(enabled yes)
			(allow_two_segments yes)
			(prefer_zone_connections yes)
		)
		(net 1)
	)
	(via
		(at 113.93 137.86)
		(size 0.45)
		(drill 0.1)
		(layers "F.Cu" "B.Cu")
		(remove_unused_layers yes)
		(keep_end_layers yes)
		(zone_layer_connections "In1.Cu" "In4.Cu" "In6.Cu")
		(teardrops
			(best_length_ratio 0.4)
			(max_length 1)
			(best_width_ratio 0.9)
			(max_width 2)
			(curved_edges yes)
			(filter_ratio 0.9)
			(enabled yes)
			(allow_two_segments yes)
			(prefer_zone_connections yes)
		)
		(net 1)
	)
	(via
		(at 317.464501 95.6365)
		(size 0.45)
		(drill 0.1)
		(layers "F.Cu" "B.Cu")
		(remove_unused_layers yes)
		(keep_end_layers yes)
		(zone_layer_connections "In1.Cu" "In4.Cu" "In6.Cu")
		(teardrops
			(best_length_ratio 0.4)
			(max_length 1)
			(best_width_ratio 0.9)
			(max_width 2)
			(curved_edges yes)
			(filter_ratio 0.9)
			(enabled yes)
			(allow_two_segments yes)
			(prefer_zone_connections yes)
		)
		(net 1)
	)
	(via
		(at 189.05 167.45)
		(size 0.45)
		(drill 0.1)
		(layers "F.Cu" "B.Cu")
		(teardrops
			(best_length_ratio 0.4)
			(max_length 1)
			(best_width_ratio 0.9)
			(max_width 2)
			(curved_edges yes)
			(filter_ratio 0.9)
			(enabled yes)
			(allow_two_segments yes)
			(prefer_zone_connections yes)
		)
		(net 1)
	)
	(via
		(at 309.95 86.31)
		(size 0.45)
		(drill 0.1)
		(layers "F.Cu" "B.Cu")
		(remove_unused_layers yes)
		(keep_end_layers yes)
		(zone_layer_connections "In1.Cu" "In4.Cu" "In6.Cu")
		(teardrops
			(best_length_ratio 0.4)
			(max_length 1)
			(best_width_ratio 0.9)
			(max_width 2)
			(curved_edges yes)
			(filter_ratio 0.9)
			(enabled yes)
			(allow_two_segments yes)
			(prefer_zone_connections yes)
		)
		(net 1)
	)
	(via
		(at 311.4645 116.4465)
		(size 0.45)
		(drill 0.1)
		(layers "F.Cu" "B.Cu")
		(remove_unused_layers yes)
		(keep_end_layers yes)
		(free yes)
		(zone_layer_connections "In1.Cu" "In4.Cu" "In6.Cu")
		(teardrops
			(best_length_ratio 0.4)
			(max_length 1)
			(best_width_ratio 0.9)
			(max_width 2)
			(curved_edges yes)
			(filter_ratio 0.9)
			(enabled yes)
			(allow_two_segments yes)
			(prefer_zone_connections yes)
		)
		(net 1)
	)
	(via
		(at 199.5 152.2)
		(size 0.45)
		(drill 0.1)
		(layers "F.Cu" "B.Cu")
		(teardrops
			(best_length_ratio 0.4)
			(max_length 1)
			(best_width_ratio 0.9)
			(max_width 2)
			(curved_edges yes)
			(filter_ratio 0.9)
			(enabled yes)
			(allow_two_segments yes)
			(prefer_zone_connections yes)
		)
		(net 1)
	)
	(via
		(at 140.45 157.31)
		(size 0.45)
		(drill 0.1)
		(layers "F.Cu" "B.Cu")
		(remove_unused_layers yes)
		(keep_end_layers yes)
		(zone_layer_connections "In1.Cu" "In4.Cu" "In6.Cu")
		(teardrops
			(best_length_ratio 0.4)
			(max_length 1)
			(best_width_ratio 0.9)
			(max_width 2)
			(curved_edges yes)
			(filter_ratio 0.9)
			(enabled yes)
			(allow_two_segments yes)
			(prefer_zone_connections yes)
		)
		(net 1)
	)
	(via
		(at 120.45 164.81)
		(size 0.45)
		(drill 0.1)
		(layers "F.Cu" "B.Cu")
		(remove_unused_layers yes)
		(keep_end_layers yes)
		(zone_layer_connections "In1.Cu" "In4.Cu" "In6.Cu")
		(teardrops
			(best_length_ratio 0.4)
			(max_length 1)
			(best_width_ratio 0.9)
			(max_width 2)
			(curved_edges yes)
			(filter_ratio 0.9)
			(enabled yes)
			(allow_two_segments yes)
			(prefer_zone_connections yes)
		)
		(net 1)
	)
	(via
		(at 200.675 170.2)
		(size 0.45)
		(drill 0.1)
		(layers "F.Cu" "B.Cu")
		(teardrops
			(best_length_ratio 0.4)
			(max_length 1)
			(best_width_ratio 0.9)
			(max_width 2)
			(curved_edges yes)
			(filter_ratio 0.9)
			(enabled yes)
			(allow_two_segments yes)
			(prefer_zone_connections yes)
		)
		(net 1)
	)
	(via
		(at 126.45 164.81)
		(size 0.45)
		(drill 0.1)
		(layers "F.Cu" "B.Cu")
		(remove_unused_layers yes)
		(keep_end_layers yes)
		(zone_layer_connections "In1.Cu" "In4.Cu" "In6.Cu")
		(teardrops
			(best_length_ratio 0.4)
			(max_length 1)
			(best_width_ratio 0.9)
			(max_width 2)
			(curved_edges yes)
			(filter_ratio 0.9)
			(enabled yes)
			(allow_two_segments yes)
			(prefer_zone_connections yes)
		)
		(net 1)
	)
	(via
		(at 195.71247 133.823072)
		(size 0.45)
		(drill 0.1)
		(layers "F.Cu" "B.Cu")
		(remove_unused_layers yes)
		(keep_end_layers yes)
		(zone_layer_connections "In1.Cu" "In4.Cu" "In6.Cu")
		(teardrops
			(best_length_ratio 0.4)
			(max_length 1)
			(best_width_ratio 0.9)
			(max_width 2)
			(curved_edges yes)
			(filter_ratio 0.9)
			(enabled yes)
			(allow_two_segments yes)
			(prefer_zone_connections yes)
		)
		(net 1)
	)
	(via
		(at 129.3 74.51)
		(size 0.45)
		(drill 0.1)
		(layers "F.Cu" "B.Cu")
		(remove_unused_layers yes)
		(keep_end_layers yes)
		(zone_layer_connections "In1.Cu" "In4.Cu" "In6.Cu")
		(teardrops
			(best_length_ratio 0.4)
			(max_length 1)
			(best_width_ratio 0.9)
			(max_width 2)
			(curved_edges yes)
			(filter_ratio 0.9)
			(enabled yes)
			(allow_two_segments yes)
			(prefer_zone_connections yes)
		)
		(net 1)
	)
	(via
		(at 117.45 165.81)
		(size 0.45)
		(drill 0.1)
		(layers "F.Cu" "B.Cu")
		(remove_unused_layers yes)
		(keep_end_layers yes)
		(zone_layer_connections "In1.Cu" "In4.Cu" "In6.Cu")
		(teardrops
			(best_length_ratio 0.4)
			(max_length 1)
			(best_width_ratio 0.9)
			(max_width 2)
			(curved_edges yes)
			(filter_ratio 0.9)
			(enabled yes)
			(allow_two_segments yes)
			(prefer_zone_connections yes)
		)
		(net 1)
	)
	(via
		(at 236.37 126.84)
		(size 0.45)
		(drill 0.1)
		(layers "F.Cu" "B.Cu")
		(remove_unused_layers yes)
		(keep_end_layers yes)
		(free yes)
		(zone_layer_connections "In1.Cu" "In4.Cu" "In6.Cu")
		(teardrops
			(best_length_ratio 0.4)
			(max_length 1)
			(best_width_ratio 0.9)
			(max_width 2)
			(curved_edges yes)
			(filter_ratio 0.9)
			(enabled yes)
			(allow_two_segments yes)
			(prefer_zone_connections yes)
		)
		(net 1)
	)
	(via
		(at 199.35 133.025)
		(size 0.45)
		(drill 0.1)
		(layers "F.Cu" "B.Cu")
		(teardrops
			(best_length_ratio 0.4)
			(max_length 1)
			(best_width_ratio 0.9)
			(max_width 2)
			(curved_edges yes)
			(filter_ratio 0.9)
			(enabled yes)
			(allow_two_segments yes)
			(prefer_zone_connections yes)
		)
		(net 1)
	)
	(via
		(at 242.95 120.31)
		(size 0.45)
		(drill 0.1)
		(layers "F.Cu" "B.Cu")
		(remove_unused_layers yes)
		(keep_end_layers yes)
		(zone_layer_connections "In1.Cu" "In4.Cu" "In6.Cu")
		(teardrops
			(best_length_ratio 0.4)
			(max_length 1)
			(best_width_ratio 0.9)
			(max_width 2)
			(curved_edges yes)
			(filter_ratio 0.9)
			(enabled yes)
			(allow_two_segments yes)
			(prefer_zone_connections yes)
		)
		(net 1)
	)
	(via
		(at 294.95 123.31)
		(size 0.45)
		(drill 0.1)
		(layers "F.Cu" "B.Cu")
		(remove_unused_layers yes)
		(keep_end_layers yes)
		(zone_layer_connections "In1.Cu" "In4.Cu" "In6.Cu")
		(teardrops
			(best_length_ratio 0.4)
			(max_length 1)
			(best_width_ratio 0.9)
			(max_width 2)
			(curved_edges yes)
			(filter_ratio 0.9)
			(enabled yes)
			(allow_two_segments yes)
			(prefer_zone_connections yes)
		)
		(net 1)
	)
	(via
		(at 128.29 133.86)
		(size 0.45)
		(drill 0.1)
		(layers "F.Cu" "B.Cu")
		(remove_unused_layers yes)
		(keep_end_layers yes)
		(zone_layer_connections "In1.Cu" "In4.Cu" "In6.Cu")
		(teardrops
			(best_length_ratio 0.4)
			(max_length 1)
			(best_width_ratio 0.9)
			(max_width 2)
			(curved_edges yes)
			(filter_ratio 0.9)
			(enabled yes)
			(allow_two_segments yes)
			(prefer_zone_connections yes)
		)
		(net 1)
	)
	(via
		(at 135.95 160.31)
		(size 0.45)
		(drill 0.1)
		(layers "F.Cu" "B.Cu")
		(remove_unused_layers yes)
		(keep_end_layers yes)
		(zone_layer_connections "In1.Cu" "In4.Cu" "In6.Cu")
		(teardrops
			(best_length_ratio 0.4)
			(max_length 1)
			(best_width_ratio 0.9)
			(max_width 2)
			(curved_edges yes)
			(filter_ratio 0.9)
			(enabled yes)
			(allow_two_segments yes)
			(prefer_zone_connections yes)
		)
		(net 1)
	)
	(via
		(at 100.45 127.81)
		(size 0.45)
		(drill 0.1)
		(layers "F.Cu" "B.Cu")
		(remove_unused_layers yes)
		(keep_end_layers yes)
		(zone_layer_connections "In1.Cu" "In4.Cu" "In6.Cu")
		(teardrops
			(best_length_ratio 0.4)
			(max_length 1)
			(best_width_ratio 0.9)
			(max_width 2)
			(curved_edges yes)
			(filter_ratio 0.9)
			(enabled yes)
			(allow_two_segments yes)
			(prefer_zone_connections yes)
		)
		(net 1)
	)
	(via
		(at 283.95 166.41)
		(size 0.45)
		(drill 0.1)
		(layers "F.Cu" "B.Cu")
		(remove_unused_layers yes)
		(keep_end_layers yes)
		(zone_layer_connections "In1.Cu" "In4.Cu" "In6.Cu")
		(teardrops
			(best_length_ratio 0.4)
			(max_length 1)
			(best_width_ratio 0.9)
			(max_width 2)
			(curved_edges yes)
			(filter_ratio 0.9)
			(enabled yes)
			(allow_two_segments yes)
			(prefer_zone_connections yes)
		)
		(net 1)
	)
	(via
		(at 300.95 108.31)
		(size 0.45)
		(drill 0.1)
		(layers "F.Cu" "B.Cu")
		(remove_unused_layers yes)
		(keep_end_layers yes)
		(zone_layer_connections "In1.Cu" "In4.Cu" "In6.Cu")
		(teardrops
			(best_length_ratio 0.4)
			(max_length 1)
			(best_width_ratio 0.9)
			(max_width 2)
			(curved_edges yes)
			(filter_ratio 0.9)
			(enabled yes)
			(allow_two_segments yes)
			(prefer_zone_connections yes)
		)
		(net 1)
	)
	(via
		(at 251.95 120.31)
		(size 0.45)
		(drill 0.1)
		(layers "F.Cu" "B.Cu")
		(remove_unused_layers yes)
		(keep_end_layers yes)
		(zone_layer_connections "In1.Cu" "In4.Cu" "In6.Cu")
		(teardrops
			(best_length_ratio 0.4)
			(max_length 1)
			(best_width_ratio 0.9)
			(max_width 2)
			(curved_edges yes)
			(filter_ratio 0.9)
			(enabled yes)
			(allow_two_segments yes)
			(prefer_zone_connections yes)
		)
		(net 1)
	)
	(via
		(at 294.45 137.81)
		(size 0.45)
		(drill 0.1)
		(layers "F.Cu" "B.Cu")
		(remove_unused_layers yes)
		(keep_end_layers yes)
		(zone_layer_connections "In1.Cu" "In4.Cu" "In6.Cu")
		(teardrops
			(best_length_ratio 0.4)
			(max_length 1)
			(best_width_ratio 0.9)
			(max_width 2)
			(curved_edges yes)
			(filter_ratio 0.9)
			(enabled yes)
			(allow_two_segments yes)
			(prefer_zone_connections yes)
		)
		(net 1)
	)
	(via
		(at 139.45 151.31)
		(size 0.45)
		(drill 0.1)
		(layers "F.Cu" "B.Cu")
		(remove_unused_layers yes)
		(keep_end_layers yes)
		(zone_layer_connections "In1.Cu" "In4.Cu" "In6.Cu")
		(teardrops
			(best_length_ratio 0.4)
			(max_length 1)
			(best_width_ratio 0.9)
			(max_width 2)
			(curved_edges yes)
			(filter_ratio 0.9)
			(enabled yes)
			(allow_two_segments yes)
			(prefer_zone_connections yes)
		)
		(net 1)
	)
	(via
		(at 138.29 135.86)
		(size 0.45)
		(drill 0.1)
		(layers "F.Cu" "B.Cu")
		(remove_unused_layers yes)
		(keep_end_layers yes)
		(zone_layer_connections "In1.Cu" "In4.Cu" "In6.Cu")
		(teardrops
			(best_length_ratio 0.4)
			(max_length 1)
			(best_width_ratio 0.9)
			(max_width 2)
			(curved_edges yes)
			(filter_ratio 0.9)
			(enabled yes)
			(allow_two_segments yes)
			(prefer_zone_connections yes)
		)
		(net 1)
	)
	(via
		(at 299.95 86.81)
		(size 0.45)
		(drill 0.1)
		(layers "F.Cu" "B.Cu")
		(remove_unused_layers yes)
		(keep_end_layers yes)
		(zone_layer_connections "In1.Cu" "In4.Cu" "In6.Cu")
		(teardrops
			(best_length_ratio 0.4)
			(max_length 1)
			(best_width_ratio 0.9)
			(max_width 2)
			(curved_edges yes)
			(filter_ratio 0.9)
			(enabled yes)
			(allow_two_segments yes)
			(prefer_zone_connections yes)
		)
		(net 1)
	)
	(via
		(at 280.45 142.81)
		(size 0.45)
		(drill 0.1)
		(layers "F.Cu" "B.Cu")
		(remove_unused_layers yes)
		(keep_end_layers yes)
		(zone_layer_connections "In1.Cu" "In4.Cu" "In6.Cu")
		(teardrops
			(best_length_ratio 0.4)
			(max_length 1)
			(best_width_ratio 0.9)
			(max_width 2)
			(curved_edges yes)
			(filter_ratio 0.9)
			(enabled yes)
			(allow_two_segments yes)
			(prefer_zone_connections yes)
		)
		(net 1)
	)
	(via
		(at 148.35 115.35)
		(size 0.45)
		(drill 0.1)
		(layers "F.Cu" "B.Cu")
		(remove_unused_layers yes)
		(keep_end_layers yes)
		(zone_layer_connections "In1.Cu" "In4.Cu" "In6.Cu")
		(teardrops
			(best_length_ratio 0.4)
			(max_length 1)
			(best_width_ratio 0.9)
			(max_width 2)
			(curved_edges yes)
			(filter_ratio 0.9)
			(enabled yes)
			(allow_two_segments yes)
			(prefer_zone_connections yes)
		)
		(net 1)
	)
	(via
		(at 136.45 78.31)
		(size 0.45)
		(drill 0.1)
		(layers "F.Cu" "B.Cu")
		(remove_unused_layers yes)
		(keep_end_layers yes)
		(zone_layer_connections "In1.Cu" "In4.Cu" "In6.Cu")
		(teardrops
			(best_length_ratio 0.4)
			(max_length 1)
			(best_width_ratio 0.9)
			(max_width 2)
			(curved_edges yes)
			(filter_ratio 0.9)
			(enabled yes)
			(allow_two_segments yes)
			(prefer_zone_connections yes)
		)
		(net 1)
	)
	(via
		(at 225.525 157.725)
		(size 0.45)
		(drill 0.1)
		(layers "F.Cu" "B.Cu")
		(teardrops
			(best_length_ratio 0.4)
			(max_length 1)
			(best_width_ratio 0.9)
			(max_width 2)
			(curved_edges yes)
			(filter_ratio 0.9)
			(enabled yes)
			(allow_two_segments yes)
			(prefer_zone_connections yes)
		)
		(net 1)
	)
	(via
		(at 273.45 166.41)
		(size 0.45)
		(drill 0.1)
		(layers "F.Cu" "B.Cu")
		(remove_unused_layers yes)
		(keep_end_layers yes)
		(zone_layer_connections "In1.Cu" "In4.Cu" "In6.Cu")
		(teardrops
			(best_length_ratio 0.4)
			(max_length 1)
			(best_width_ratio 0.9)
			(max_width 2)
			(curved_edges yes)
			(filter_ratio 0.9)
			(enabled yes)
			(allow_two_segments yes)
			(prefer_zone_connections yes)
		)
		(net 1)
	)
	(via
		(at 227 157.8)
		(size 0.45)
		(drill 0.1)
		(layers "F.Cu" "B.Cu")
		(teardrops
			(best_length_ratio 0.4)
			(max_length 1)
			(best_width_ratio 0.9)
			(max_width 2)
			(curved_edges yes)
			(filter_ratio 0.9)
			(enabled yes)
			(allow_two_segments yes)
			(prefer_zone_connections yes)
		)
		(net 1)
	)
	(via
		(at 285.95 97.81)
		(size 0.45)
		(drill 0.1)
		(layers "F.Cu" "B.Cu")
		(remove_unused_layers yes)
		(keep_end_layers yes)
		(zone_layer_connections "In1.Cu" "In4.Cu" "In6.Cu")
		(teardrops
			(best_length_ratio 0.4)
			(max_length 1)
			(best_width_ratio 0.9)
			(max_width 2)
			(curved_edges yes)
			(filter_ratio 0.9)
			(enabled yes)
			(allow_two_segments yes)
			(prefer_zone_connections yes)
		)
		(net 1)
	)
	(via
		(at 176.1 166.9)
		(size 0.45)
		(drill 0.1)
		(layers "F.Cu" "B.Cu")
		(teardrops
			(best_length_ratio 0.4)
			(max_length 1)
			(best_width_ratio 0.9)
			(max_width 2)
			(curved_edges yes)
			(filter_ratio 0.9)
			(enabled yes)
			(allow_two_segments yes)
			(prefer_zone_connections yes)
		)
		(net 1)
	)
	(via
		(at 256.45 121.81)
		(size 0.45)
		(drill 0.1)
		(layers "F.Cu" "B.Cu")
		(remove_unused_layers yes)
		(keep_end_layers yes)
		(zone_layer_connections "In1.Cu" "In4.Cu" "In6.Cu")
		(teardrops
			(best_length_ratio 0.4)
			(max_length 1)
			(best_width_ratio 0.9)
			(max_width 2)
			(curved_edges yes)
			(filter_ratio 0.9)
			(enabled yes)
			(allow_two_segments yes)
			(prefer_zone_connections yes)
		)
		(net 1)
	)
	(via
		(at 277.95 112.31)
		(size 0.45)
		(drill 0.1)
		(layers "F.Cu" "B.Cu")
		(remove_unused_layers yes)
		(keep_end_layers yes)
		(zone_layer_connections "In1.Cu" "In4.Cu" "In6.Cu")
		(teardrops
			(best_length_ratio 0.4)
			(max_length 1)
			(best_width_ratio 0.9)
			(max_width 2)
			(curved_edges yes)
			(filter_ratio 0.9)
			(enabled yes)
			(allow_two_segments yes)
			(prefer_zone_connections yes)
		)
		(net 1)
	)
	(via
		(at 300.95 149.31)
		(size 0.45)
		(drill 0.1)
		(layers "F.Cu" "B.Cu")
		(remove_unused_layers yes)
		(keep_end_layers yes)
		(zone_layer_connections "In1.Cu" "In4.Cu" "In6.Cu")
		(teardrops
			(best_length_ratio 0.4)
			(max_length 1)
			(best_width_ratio 0.9)
			(max_width 2)
			(curved_edges yes)
			(filter_ratio 0.9)
			(enabled yes)
			(allow_two_segments yes)
			(prefer_zone_connections yes)
		)
		(net 1)
	)
	(via
		(at 124.45 164.81)
		(size 0.45)
		(drill 0.1)
		(layers "F.Cu" "B.Cu")
		(remove_unused_layers yes)
		(keep_end_layers yes)
		(zone_layer_connections "In1.Cu" "In4.Cu" "In6.Cu")
		(teardrops
			(best_length_ratio 0.4)
			(max_length 1)
			(best_width_ratio 0.9)
			(max_width 2)
			(curved_edges yes)
			(filter_ratio 0.9)
			(enabled yes)
			(allow_two_segments yes)
			(prefer_zone_connections yes)
		)
		(net 1)
	)
	(via
		(at 199.95 87.31)
		(size 0.45)
		(drill 0.1)
		(layers "F.Cu" "B.Cu")
		(remove_unused_layers yes)
		(keep_end_layers yes)
		(zone_layer_connections "In1.Cu" "In4.Cu" "In6.Cu")
		(teardrops
			(best_length_ratio 0.4)
			(max_length 1)
			(best_width_ratio 0.9)
			(max_width 2)
			(curved_edges yes)
			(filter_ratio 0.9)
			(enabled yes)
			(allow_two_segments yes)
			(prefer_zone_connections yes)
		)
		(net 1)
	)
	(via
		(at 154.2 122.6)
		(size 0.45)
		(drill 0.1)
		(layers "F.Cu" "B.Cu")
		(remove_unused_layers yes)
		(keep_end_layers yes)
		(zone_layer_connections "In1.Cu" "In4.Cu" "In6.Cu")
		(teardrops
			(best_length_ratio 0.4)
			(max_length 1)
			(best_width_ratio 0.9)
			(max_width 2)
			(curved_edges yes)
			(filter_ratio 0.9)
			(enabled yes)
			(allow_two_segments yes)
			(prefer_zone_connections yes)
		)
		(net 1)
	)
	(via
		(at 280.45 136.81)
		(size 0.45)
		(drill 0.1)
		(layers "F.Cu" "B.Cu")
		(remove_unused_layers yes)
		(keep_end_layers yes)
		(zone_layer_connections "In1.Cu" "In4.Cu" "In6.Cu")
		(teardrops
			(best_length_ratio 0.4)
			(max_length 1)
			(best_width_ratio 0.9)
			(max_width 2)
			(curved_edges yes)
			(filter_ratio 0.9)
			(enabled yes)
			(allow_two_segments yes)
			(prefer_zone_connections yes)
		)
		(net 1)
	)
	(via
		(at 225.45 90.81)
		(size 0.45)
		(drill 0.1)
		(layers "F.Cu" "B.Cu")
		(remove_unused_layers yes)
		(keep_end_layers yes)
		(zone_layer_connections "In1.Cu" "In4.Cu" "In6.Cu")
		(teardrops
			(best_length_ratio 0.4)
			(max_length 1)
			(best_width_ratio 0.9)
			(max_width 2)
			(curved_edges yes)
			(filter_ratio 0.9)
			(enabled yes)
			(allow_two_segments yes)
			(prefer_zone_connections yes)
		)
		(net 1)
	)
	(via
		(at 191.975198 128.446375)
		(size 0.45)
		(drill 0.1)
		(layers "F.Cu" "B.Cu")
		(remove_unused_layers yes)
		(keep_end_layers yes)
		(free yes)
		(zone_layer_connections "In1.Cu" "In4.Cu" "In6.Cu")
		(teardrops
			(best_length_ratio 0.4)
			(max_length 1)
			(best_width_ratio 0.9)
			(max_width 2)
			(curved_edges yes)
			(filter_ratio 0.9)
			(enabled yes)
			(allow_two_segments yes)
			(prefer_zone_connections yes)
		)
		(net 1)
	)
	(via
		(at 239.95 133.81)
		(size 0.45)
		(drill 0.1)
		(layers "F.Cu" "B.Cu")
		(remove_unused_layers yes)
		(keep_end_layers yes)
		(zone_layer_connections "In1.Cu" "In4.Cu" "In6.Cu")
		(teardrops
			(best_length_ratio 0.4)
			(max_length 1)
			(best_width_ratio 0.9)
			(max_width 2)
			(curved_edges yes)
			(filter_ratio 0.9)
			(enabled yes)
			(allow_two_segments yes)
			(prefer_zone_connections yes)
		)
		(net 1)
	)
	(via
		(at 283.45 81.31)
		(size 0.45)
		(drill 0.1)
		(layers "F.Cu" "B.Cu")
		(remove_unused_layers yes)
		(keep_end_layers yes)
		(zone_layer_connections "In1.Cu" "In4.Cu" "In6.Cu")
		(teardrops
			(best_length_ratio 0.4)
			(max_length 1)
			(best_width_ratio 0.9)
			(max_width 2)
			(curved_edges yes)
			(filter_ratio 0.9)
			(enabled yes)
			(allow_two_segments yes)
			(prefer_zone_connections yes)
		)
		(net 1)
	)
	(via
		(at 146.95 69.81)
		(size 0.45)
		(drill 0.1)
		(layers "F.Cu" "B.Cu")
		(remove_unused_layers yes)
		(keep_end_layers yes)
		(zone_layer_connections "In1.Cu" "In4.Cu" "In6.Cu")
		(teardrops
			(best_length_ratio 0.4)
			(max_length 1)
			(best_width_ratio 0.9)
			(max_width 2)
			(curved_edges yes)
			(filter_ratio 0.9)
			(enabled yes)
			(allow_two_segments yes)
			(prefer_zone_connections yes)
		)
		(net 1)
	)
	(via
		(at 182.71 113.535)
		(size 0.45)
		(drill 0.1)
		(layers "F.Cu" "B.Cu")
		(remove_unused_layers yes)
		(keep_end_layers yes)
		(zone_layer_connections "In1.Cu" "In4.Cu" "In6.Cu")
		(teardrops
			(best_length_ratio 0.4)
			(max_length 1)
			(best_width_ratio 0.9)
			(max_width 2)
			(curved_edges yes)
			(filter_ratio 0.9)
			(enabled yes)
			(allow_two_segments yes)
			(prefer_zone_connections yes)
		)
		(net 1)
	)
	(via
		(at 137 108)
		(size 0.45)
		(drill 0.1)
		(layers "F.Cu" "B.Cu")
		(remove_unused_layers yes)
		(keep_end_layers yes)
		(zone_layer_connections "In1.Cu" "In4.Cu" "In6.Cu")
		(teardrops
			(best_length_ratio 0.4)
			(max_length 1)
			(best_width_ratio 0.9)
			(max_width 2)
			(curved_edges yes)
			(filter_ratio 0.9)
			(enabled yes)
			(allow_two_segments yes)
			(prefer_zone_connections yes)
		)
		(net 1)
	)
	(via
		(at 101.95 80.81)
		(size 0.45)
		(drill 0.1)
		(layers "F.Cu" "B.Cu")
		(remove_unused_layers yes)
		(keep_end_layers yes)
		(zone_layer_connections "In1.Cu" "In4.Cu" "In6.Cu")
		(teardrops
			(best_length_ratio 0.4)
			(max_length 1)
			(best_width_ratio 0.9)
			(max_width 2)
			(curved_edges yes)
			(filter_ratio 0.9)
			(enabled yes)
			(allow_two_segments yes)
			(prefer_zone_connections yes)
		)
		(net 1)
	)
	(via
		(at 295.7 74.96)
		(size 0.45)
		(drill 0.1)
		(layers "F.Cu" "B.Cu")
		(remove_unused_layers yes)
		(keep_end_layers yes)
		(free yes)
		(zone_layer_connections "In1.Cu" "In4.Cu" "In6.Cu")
		(teardrops
			(best_length_ratio 0.4)
			(max_length 1)
			(best_width_ratio 0.9)
			(max_width 2)
			(curved_edges yes)
			(filter_ratio 0.9)
			(enabled yes)
			(allow_two_segments yes)
			(prefer_zone_connections yes)
		)
		(net 1)
	)
	(via
		(at 238.45 132.31)
		(size 0.45)
		(drill 0.1)
		(layers "F.Cu" "B.Cu")
		(remove_unused_layers yes)
		(keep_end_layers yes)
		(zone_layer_connections "In1.Cu" "In4.Cu" "In6.Cu")
		(teardrops
			(best_length_ratio 0.4)
			(max_length 1)
			(best_width_ratio 0.9)
			(max_width 2)
			(curved_edges yes)
			(filter_ratio 0.9)
			(enabled yes)
			(allow_two_segments yes)
			(prefer_zone_connections yes)
		)
		(net 1)
	)
	(via
		(at 191.469829 138.065713)
		(size 0.45)
		(drill 0.1)
		(layers "F.Cu" "B.Cu")
		(remove_unused_layers yes)
		(keep_end_layers yes)
		(zone_layer_connections "In1.Cu" "In4.Cu" "In6.Cu")
		(teardrops
			(best_length_ratio 0.4)
			(max_length 1)
			(best_width_ratio 0.9)
			(max_width 2)
			(curved_edges yes)
			(filter_ratio 0.9)
			(enabled yes)
			(allow_two_segments yes)
			(prefer_zone_connections yes)
		)
		(net 1)
	)
	(via
		(at 280.95 109.31)
		(size 0.45)
		(drill 0.1)
		(layers "F.Cu" "B.Cu")
		(remove_unused_layers yes)
		(keep_end_layers yes)
		(zone_layer_connections "In1.Cu" "In4.Cu" "In6.Cu")
		(teardrops
			(best_length_ratio 0.4)
			(max_length 1)
			(best_width_ratio 0.9)
			(max_width 2)
			(curved_edges yes)
			(filter_ratio 0.9)
			(enabled yes)
			(allow_two_segments yes)
			(prefer_zone_connections yes)
		)
		(net 1)
	)
	(via
		(at 195.45 68.81)
		(size 0.45)
		(drill 0.1)
		(layers "F.Cu" "B.Cu")
		(remove_unused_layers yes)
		(keep_end_layers yes)
		(free yes)
		(zone_layer_connections "In1.Cu" "In4.Cu" "In6.Cu")
		(teardrops
			(best_length_ratio 0.4)
			(max_length 1)
			(best_width_ratio 0.9)
			(max_width 2)
			(curved_edges yes)
			(filter_ratio 0.9)
			(enabled yes)
			(allow_two_segments yes)
			(prefer_zone_connections yes)
		)
		(net 1)
	)
	(via
		(at 103.45 128.81)
		(size 0.45)
		(drill 0.1)
		(layers "F.Cu" "B.Cu")
		(remove_unused_layers yes)
		(keep_end_layers yes)
		(zone_layer_connections "In1.Cu" "In4.Cu" "In6.Cu")
		(teardrops
			(best_length_ratio 0.4)
			(max_length 1)
			(best_width_ratio 0.9)
			(max_width 2)
			(curved_edges yes)
			(filter_ratio 0.9)
			(enabled yes)
			(allow_two_segments yes)
			(prefer_zone_connections yes)
		)
		(net 1)
	)
	(via
		(at 144.45 86.31)
		(size 0.45)
		(drill 0.1)
		(layers "F.Cu" "B.Cu")
		(remove_unused_layers yes)
		(keep_end_layers yes)
		(zone_layer_connections "In1.Cu" "In4.Cu" "In6.Cu")
		(teardrops
			(best_length_ratio 0.4)
			(max_length 1)
			(best_width_ratio 0.9)
			(max_width 2)
			(curved_edges yes)
			(filter_ratio 0.9)
			(enabled yes)
			(allow_two_segments yes)
			(prefer_zone_connections yes)
		)
		(net 1)
	)
	(via
		(at 129.32 108.5)
		(size 0.45)
		(drill 0.1)
		(layers "F.Cu" "B.Cu")
		(net 1)
	)
	(via
		(at 98.45 116.81)
		(size 0.45)
		(drill 0.1)
		(layers "F.Cu" "B.Cu")
		(remove_unused_layers yes)
		(keep_end_layers yes)
		(zone_layer_connections "In1.Cu" "In4.Cu" "In6.Cu")
		(teardrops
			(best_length_ratio 0.4)
			(max_length 1)
			(best_width_ratio 0.9)
			(max_width 2)
			(curved_edges yes)
			(filter_ratio 0.9)
			(enabled yes)
			(allow_two_segments yes)
			(prefer_zone_connections yes)
		)
		(net 1)
	)
	(via
		(at 136.29 146.81)
		(size 0.45)
		(drill 0.1)
		(layers "F.Cu" "B.Cu")
		(remove_unused_layers yes)
		(keep_end_layers yes)
		(zone_layer_connections "In1.Cu" "In4.Cu" "In6.Cu")
		(teardrops
			(best_length_ratio 0.4)
			(max_length 1)
			(best_width_ratio 0.9)
			(max_width 2)
			(curved_edges yes)
			(filter_ratio 0.9)
			(enabled yes)
			(allow_two_segments yes)
			(prefer_zone_connections yes)
		)
		(net 1)
	)
	(via
		(at 307.85 150.11)
		(size 0.45)
		(drill 0.1)
		(layers "F.Cu" "B.Cu")
		(remove_unused_layers yes)
		(keep_end_layers yes)
		(zone_layer_connections "In1.Cu" "In4.Cu" "In6.Cu")
		(teardrops
			(best_length_ratio 0.4)
			(max_length 1)
			(best_width_ratio 0.9)
			(max_width 2)
			(curved_edges yes)
			(filter_ratio 0.9)
			(enabled yes)
			(allow_two_segments yes)
			(prefer_zone_connections yes)
		)
		(net 1)
	)
	(via
		(at 107.8 143.55)
		(size 0.45)
		(drill 0.1)
		(layers "F.Cu" "B.Cu")
		(teardrops
			(best_length_ratio 0.4)
			(max_length 1)
			(best_width_ratio 0.9)
			(max_width 2)
			(curved_edges yes)
			(filter_ratio 0.9)
			(enabled yes)
			(allow_two_segments yes)
			(prefer_zone_connections yes)
		)
		(net 1)
	)
	(via
		(at 268.65 139.9)
		(size 0.45)
		(drill 0.1)
		(layers "F.Cu" "B.Cu")
		(remove_unused_layers yes)
		(keep_end_layers yes)
		(zone_layer_connections "In1.Cu" "In4.Cu" "In6.Cu")
		(teardrops
			(best_length_ratio 0.4)
			(max_length 1)
			(best_width_ratio 0.9)
			(max_width 2)
			(curved_edges yes)
			(filter_ratio 0.9)
			(enabled yes)
			(allow_two_segments yes)
			(prefer_zone_connections yes)
		)
		(net 1)
	)
	(via
		(at 296.45 124.81)
		(size 0.45)
		(drill 0.1)
		(layers "F.Cu" "B.Cu")
		(remove_unused_layers yes)
		(keep_end_layers yes)
		(zone_layer_connections "In1.Cu" "In4.Cu" "In6.Cu")
		(teardrops
			(best_length_ratio 0.4)
			(max_length 1)
			(best_width_ratio 0.9)
			(max_width 2)
			(curved_edges yes)
			(filter_ratio 0.9)
			(enabled yes)
			(allow_two_segments yes)
			(prefer_zone_connections yes)
		)
		(net 1)
	)
	(via
		(at 196.95 80.81)
		(size 0.45)
		(drill 0.1)
		(layers "F.Cu" "B.Cu")
		(remove_unused_layers yes)
		(keep_end_layers yes)
		(zone_layer_connections "In1.Cu" "In4.Cu" "In6.Cu")
		(teardrops
			(best_length_ratio 0.4)
			(max_length 1)
			(best_width_ratio 0.9)
			(max_width 2)
			(curved_edges yes)
			(filter_ratio 0.9)
			(enabled yes)
			(allow_two_segments yes)
			(prefer_zone_connections yes)
		)
		(net 1)
	)
	(via
		(at 166.45 88.31)
		(size 0.45)
		(drill 0.1)
		(layers "F.Cu" "B.Cu")
		(remove_unused_layers yes)
		(keep_end_layers yes)
		(free yes)
		(zone_layer_connections "In1.Cu" "In4.Cu" "In6.Cu")
		(teardrops
			(best_length_ratio 0.4)
			(max_length 1)
			(best_width_ratio 0.9)
			(max_width 2)
			(curved_edges yes)
			(filter_ratio 0.9)
			(enabled yes)
			(allow_two_segments yes)
			(prefer_zone_connections yes)
		)
		(net 1)
	)
	(via
		(at 100.1 150)
		(size 0.45)
		(drill 0.1)
		(layers "F.Cu" "B.Cu")
		(remove_unused_layers yes)
		(keep_end_layers yes)
		(zone_layer_connections "In1.Cu" "In4.Cu" "In6.Cu")
		(teardrops
			(best_length_ratio 0.4)
			(max_length 1)
			(best_width_ratio 0.9)
			(max_width 2)
			(curved_edges yes)
			(filter_ratio 0.9)
			(enabled yes)
			(allow_two_segments yes)
			(prefer_zone_connections yes)
		)
		(net 1)
	)
	(via
		(at 98.45 90.81)
		(size 0.45)
		(drill 0.1)
		(layers "F.Cu" "B.Cu")
		(remove_unused_layers yes)
		(keep_end_layers yes)
		(zone_layer_connections "In1.Cu" "In4.Cu" "In6.Cu")
		(teardrops
			(best_length_ratio 0.4)
			(max_length 1)
			(best_width_ratio 0.9)
			(max_width 2)
			(curved_edges yes)
			(filter_ratio 0.9)
			(enabled yes)
			(allow_two_segments yes)
			(prefer_zone_connections yes)
		)
		(net 1)
	)
	(via
		(at 119.45 94.31)
		(size 0.45)
		(drill 0.1)
		(layers "F.Cu" "B.Cu")
		(remove_unused_layers yes)
		(keep_end_layers yes)
		(zone_layer_connections "In1.Cu" "In4.Cu" "In6.Cu")
		(teardrops
			(best_length_ratio 0.4)
			(max_length 1)
			(best_width_ratio 0.9)
			(max_width 2)
			(curved_edges yes)
			(filter_ratio 0.9)
			(enabled yes)
			(allow_two_segments yes)
			(prefer_zone_connections yes)
		)
		(net 1)
	)
	(via
		(at 288.95 105.81)
		(size 0.45)
		(drill 0.1)
		(layers "F.Cu" "B.Cu")
		(remove_unused_layers yes)
		(keep_end_layers yes)
		(zone_layer_connections "In1.Cu" "In4.Cu" "In6.Cu")
		(teardrops
			(best_length_ratio 0.4)
			(max_length 1)
			(best_width_ratio 0.9)
			(max_width 2)
			(curved_edges yes)
			(filter_ratio 0.9)
			(enabled yes)
			(allow_two_segments yes)
			(prefer_zone_connections yes)
		)
		(net 1)
	)
	(via
		(at 130.29 145.86)
		(size 0.45)
		(drill 0.1)
		(layers "F.Cu" "B.Cu")
		(remove_unused_layers yes)
		(keep_end_layers yes)
		(zone_layer_connections "In1.Cu" "In4.Cu" "In6.Cu")
		(teardrops
			(best_length_ratio 0.4)
			(max_length 1)
			(best_width_ratio 0.9)
			(max_width 2)
			(curved_edges yes)
			(filter_ratio 0.9)
			(enabled yes)
			(allow_two_segments yes)
			(prefer_zone_connections yes)
		)
		(net 1)
	)
	(via
		(at 187.3 125.1)
		(size 0.45)
		(drill 0.1)
		(layers "F.Cu" "B.Cu")
		(remove_unused_layers yes)
		(keep_end_layers yes)
		(zone_layer_connections "In1.Cu" "In4.Cu" "In6.Cu")
		(teardrops
			(best_length_ratio 0.4)
			(max_length 1)
			(best_width_ratio 0.9)
			(max_width 2)
			(curved_edges yes)
			(filter_ratio 0.9)
			(enabled yes)
			(allow_two_segments yes)
			(prefer_zone_connections yes)
		)
		(net 1)
	)
	(via
		(at 113.8 92.66)
		(size 0.45)
		(drill 0.1)
		(layers "F.Cu" "B.Cu")
		(remove_unused_layers yes)
		(keep_end_layers yes)
		(zone_layer_connections "In1.Cu" "In4.Cu" "In6.Cu")
		(teardrops
			(best_length_ratio 0.4)
			(max_length 1)
			(best_width_ratio 0.9)
			(max_width 2)
			(curved_edges yes)
			(filter_ratio 0.9)
			(enabled yes)
			(allow_two_segments yes)
			(prefer_zone_connections yes)
		)
		(net 1)
	)
	(via
		(at 221.45 123.81)
		(size 0.45)
		(drill 0.1)
		(layers "F.Cu" "B.Cu")
		(remove_unused_layers yes)
		(keep_end_layers yes)
		(zone_layer_connections "In1.Cu" "In4.Cu" "In6.Cu")
		(teardrops
			(best_length_ratio 0.4)
			(max_length 1)
			(best_width_ratio 0.9)
			(max_width 2)
			(curved_edges yes)
			(filter_ratio 0.9)
			(enabled yes)
			(allow_two_segments yes)
			(prefer_zone_connections yes)
		)
		(net 1)
	)
	(via
		(at 261.45 166.41)
		(size 0.45)
		(drill 0.1)
		(layers "F.Cu" "B.Cu")
		(remove_unused_layers yes)
		(keep_end_layers yes)
		(zone_layer_connections "In1.Cu" "In4.Cu" "In6.Cu")
		(teardrops
			(best_length_ratio 0.4)
			(max_length 1)
			(best_width_ratio 0.9)
			(max_width 2)
			(curved_edges yes)
			(filter_ratio 0.9)
			(enabled yes)
			(allow_two_segments yes)
			(prefer_zone_connections yes)
		)
		(net 1)
	)
	(via
		(at 134.45 91.81)
		(size 0.45)
		(drill 0.1)
		(layers "F.Cu" "B.Cu")
		(remove_unused_layers yes)
		(keep_end_layers yes)
		(zone_layer_connections "In1.Cu" "In4.Cu" "In6.Cu")
		(teardrops
			(best_length_ratio 0.4)
			(max_length 1)
			(best_width_ratio 0.9)
			(max_width 2)
			(curved_edges yes)
			(filter_ratio 0.9)
			(enabled yes)
			(allow_two_segments yes)
			(prefer_zone_connections yes)
		)
		(net 1)
	)
	(via
		(at 146.45 134.86)
		(size 0.45)
		(drill 0.1)
		(layers "F.Cu" "B.Cu")
		(remove_unused_layers yes)
		(keep_end_layers yes)
		(zone_layer_connections "In1.Cu" "In4.Cu" "In6.Cu")
		(teardrops
			(best_length_ratio 0.4)
			(max_length 1)
			(best_width_ratio 0.9)
			(max_width 2)
			(curved_edges yes)
			(filter_ratio 0.9)
			(enabled yes)
			(allow_two_segments yes)
			(prefer_zone_connections yes)
		)
		(net 1)
	)
	(via
		(at 270.95 170.81)
		(size 0.45)
		(drill 0.1)
		(layers "F.Cu" "B.Cu")
		(remove_unused_layers yes)
		(keep_end_layers yes)
		(zone_layer_connections "In1.Cu" "In4.Cu" "In6.Cu")
		(teardrops
			(best_length_ratio 0.4)
			(max_length 1)
			(best_width_ratio 0.9)
			(max_width 2)
			(curved_edges yes)
			(filter_ratio 0.9)
			(enabled yes)
			(allow_two_segments yes)
			(prefer_zone_connections yes)
		)
		(net 1)
	)
	(via
		(at 244.8 132.834)
		(size 0.45)
		(drill 0.1)
		(layers "F.Cu" "B.Cu")
		(remove_unused_layers yes)
		(keep_end_layers yes)
		(zone_layer_connections "In1.Cu" "In4.Cu" "In6.Cu")
		(teardrops
			(best_length_ratio 0.4)
			(max_length 1)
			(best_width_ratio 0.9)
			(max_width 2)
			(curved_edges yes)
			(filter_ratio 0.9)
			(enabled yes)
			(allow_two_segments yes)
			(prefer_zone_connections yes)
		)
		(net 1)
	)
	(via
		(at 186.025 167.45)
		(size 0.45)
		(drill 0.1)
		(layers "F.Cu" "B.Cu")
		(teardrops
			(best_length_ratio 0.4)
			(max_length 1)
			(best_width_ratio 0.9)
			(max_width 2)
			(curved_edges yes)
			(filter_ratio 0.9)
			(enabled yes)
			(allow_two_segments yes)
			(prefer_zone_connections yes)
		)
		(net 1)
	)
	(via
		(at 281.95 100.81)
		(size 0.45)
		(drill 0.1)
		(layers "F.Cu" "B.Cu")
		(remove_unused_layers yes)
		(keep_end_layers yes)
		(zone_layer_connections "In1.Cu" "In4.Cu" "In6.Cu")
		(teardrops
			(best_length_ratio 0.4)
			(max_length 1)
			(best_width_ratio 0.9)
			(max_width 2)
			(curved_edges yes)
			(filter_ratio 0.9)
			(enabled yes)
			(allow_two_segments yes)
			(prefer_zone_connections yes)
		)
		(net 1)
	)
	(via
		(at 148.45 135.86)
		(size 0.45)
		(drill 0.1)
		(layers "F.Cu" "B.Cu")
		(remove_unused_layers yes)
		(keep_end_layers yes)
		(zone_layer_connections "In1.Cu" "In4.Cu" "In6.Cu")
		(teardrops
			(best_length_ratio 0.4)
			(max_length 1)
			(best_width_ratio 0.9)
			(max_width 2)
			(curved_edges yes)
			(filter_ratio 0.9)
			(enabled yes)
			(allow_two_segments yes)
			(prefer_zone_connections yes)
		)
		(net 1)
	)
	(via
		(at 259.45 114.31)
		(size 0.45)
		(drill 0.1)
		(layers "F.Cu" "B.Cu")
		(remove_unused_layers yes)
		(keep_end_layers yes)
		(free yes)
		(zone_layer_connections "In1.Cu" "In4.Cu" "In6.Cu")
		(teardrops
			(best_length_ratio 0.4)
			(max_length 1)
			(best_width_ratio 0.9)
			(max_width 2)
			(curved_edges yes)
			(filter_ratio 0.9)
			(enabled yes)
			(allow_two_segments yes)
			(prefer_zone_connections yes)
		)
		(net 1)
	)
	(via
		(at 165.6 150.2)
		(size 0.45)
		(drill 0.1)
		(layers "F.Cu" "B.Cu")
		(teardrops
			(best_length_ratio 0.4)
			(max_length 1)
			(best_width_ratio 0.9)
			(max_width 2)
			(curved_edges yes)
			(filter_ratio 0.9)
			(enabled yes)
			(allow_two_segments yes)
			(prefer_zone_connections yes)
		)
		(net 1)
	)
	(via
		(at 194.096518 130.567696)
		(size 0.45)
		(drill 0.1)
		(layers "F.Cu" "B.Cu")
		(remove_unused_layers yes)
		(keep_end_layers yes)
		(free yes)
		(zone_layer_connections "In1.Cu" "In4.Cu" "In6.Cu")
		(teardrops
			(best_length_ratio 0.4)
			(max_length 1)
			(best_width_ratio 0.9)
			(max_width 2)
			(curved_edges yes)
			(filter_ratio 0.9)
			(enabled yes)
			(allow_two_segments yes)
			(prefer_zone_connections yes)
		)
		(net 1)
	)
	(via
		(at 236.95 114.31)
		(size 0.45)
		(drill 0.1)
		(layers "F.Cu" "B.Cu")
		(remove_unused_layers yes)
		(keep_end_layers yes)
		(free yes)
		(zone_layer_connections "In1.Cu" "In4.Cu" "In6.Cu")
		(teardrops
			(best_length_ratio 0.4)
			(max_length 1)
			(best_width_ratio 0.9)
			(max_width 2)
			(curved_edges yes)
			(filter_ratio 0.9)
			(enabled yes)
			(allow_two_segments yes)
			(prefer_zone_connections yes)
		)
		(net 1)
	)
	(via
		(at 225.45 82.31)
		(size 0.45)
		(drill 0.1)
		(layers "F.Cu" "B.Cu")
		(remove_unused_layers yes)
		(keep_end_layers yes)
		(free yes)
		(zone_layer_connections "In1.Cu" "In4.Cu" "In6.Cu")
		(teardrops
			(best_length_ratio 0.4)
			(max_length 1)
			(best_width_ratio 0.9)
			(max_width 2)
			(curved_edges yes)
			(filter_ratio 0.9)
			(enabled yes)
			(allow_two_segments yes)
			(prefer_zone_connections yes)
		)
		(net 1)
	)
	(via
		(at 134.45 78.31)
		(size 0.45)
		(drill 0.1)
		(layers "F.Cu" "B.Cu")
		(remove_unused_layers yes)
		(keep_end_layers yes)
		(zone_layer_connections "In1.Cu" "In4.Cu" "In6.Cu")
		(teardrops
			(best_length_ratio 0.4)
			(max_length 1)
			(best_width_ratio 0.9)
			(max_width 2)
			(curved_edges yes)
			(filter_ratio 0.9)
			(enabled yes)
			(allow_two_segments yes)
			(prefer_zone_connections yes)
		)
		(net 1)
	)
	(via
		(at 166.95 70.31)
		(size 0.45)
		(drill 0.1)
		(layers "F.Cu" "B.Cu")
		(remove_unused_layers yes)
		(keep_end_layers yes)
		(zone_layer_connections "In1.Cu" "In4.Cu" "In6.Cu")
		(teardrops
			(best_length_ratio 0.4)
			(max_length 1)
			(best_width_ratio 0.9)
			(max_width 2)
			(curved_edges yes)
			(filter_ratio 0.9)
			(enabled yes)
			(allow_two_segments yes)
			(prefer_zone_connections yes)
		)
		(net 1)
	)
	(via
		(at 280.95 115.31)
		(size 0.45)
		(drill 0.1)
		(layers "F.Cu" "B.Cu")
		(remove_unused_layers yes)
		(keep_end_layers yes)
		(zone_layer_connections "In1.Cu" "In4.Cu" "In6.Cu")
		(teardrops
			(best_length_ratio 0.4)
			(max_length 1)
			(best_width_ratio 0.9)
			(max_width 2)
			(curved_edges yes)
			(filter_ratio 0.9)
			(enabled yes)
			(allow_two_segments yes)
			(prefer_zone_connections yes)
		)
		(net 1)
	)
	(via
		(at 98.45 129.81)
		(size 0.45)
		(drill 0.1)
		(layers "F.Cu" "B.Cu")
		(remove_unused_layers yes)
		(keep_end_layers yes)
		(zone_layer_connections "In1.Cu" "In4.Cu" "In6.Cu")
		(teardrops
			(best_length_ratio 0.4)
			(max_length 1)
			(best_width_ratio 0.9)
			(max_width 2)
			(curved_edges yes)
			(filter_ratio 0.9)
			(enabled yes)
			(allow_two_segments yes)
			(prefer_zone_connections yes)
		)
		(net 1)
	)
	(via
		(at 283.95 115.31)
		(size 0.45)
		(drill 0.1)
		(layers "F.Cu" "B.Cu")
		(remove_unused_layers yes)
		(keep_end_layers yes)
		(zone_layer_connections "In1.Cu" "In4.Cu" "In6.Cu")
		(teardrops
			(best_length_ratio 0.4)
			(max_length 1)
			(best_width_ratio 0.9)
			(max_width 2)
			(curved_edges yes)
			(filter_ratio 0.9)
			(enabled yes)
			(allow_two_segments yes)
			(prefer_zone_connections yes)
		)
		(net 1)
	)
	(via
		(at 300.95 70.31)
		(size 0.45)
		(drill 0.1)
		(layers "F.Cu" "B.Cu")
		(remove_unused_layers yes)
		(keep_end_layers yes)
		(zone_layer_connections "In1.Cu" "In4.Cu" "In6.Cu")
		(teardrops
			(best_length_ratio 0.4)
			(max_length 1)
			(best_width_ratio 0.9)
			(max_width 2)
			(curved_edges yes)
			(filter_ratio 0.9)
			(enabled yes)
			(allow_two_segments yes)
			(prefer_zone_connections yes)
		)
		(net 1)
	)
	(via
		(at 173.2 99.35)
		(size 0.45)
		(drill 0.1)
		(layers "F.Cu" "B.Cu")
		(remove_unused_layers yes)
		(keep_end_layers yes)
		(zone_layer_connections "In1.Cu" "In4.Cu" "In6.Cu")
		(teardrops
			(best_length_ratio 0.4)
			(max_length 1)
			(best_width_ratio 0.9)
			(max_width 2)
			(curved_edges yes)
			(filter_ratio 0.9)
			(enabled yes)
			(allow_two_segments yes)
			(prefer_zone_connections yes)
		)
		(net 1)
	)
	(via
		(at 166.45 79.31)
		(size 0.45)
		(drill 0.1)
		(layers "F.Cu" "B.Cu")
		(remove_unused_layers yes)
		(keep_end_layers yes)
		(free yes)
		(zone_layer_connections "In1.Cu" "In4.Cu" "In6.Cu")
		(teardrops
			(best_length_ratio 0.4)
			(max_length 1)
			(best_width_ratio 0.9)
			(max_width 2)
			(curved_edges yes)
			(filter_ratio 0.9)
			(enabled yes)
			(allow_two_segments yes)
			(prefer_zone_connections yes)
		)
		(net 1)
	)
	(via
		(at 247.95 166.41)
		(size 0.45)
		(drill 0.1)
		(layers "F.Cu" "B.Cu")
		(remove_unused_layers yes)
		(keep_end_layers yes)
		(free yes)
		(zone_layer_connections "In1.Cu" "In4.Cu" "In6.Cu")
		(teardrops
			(best_length_ratio 0.4)
			(max_length 1)
			(best_width_ratio 0.9)
			(max_width 2)
			(curved_edges yes)
			(filter_ratio 0.9)
			(enabled yes)
			(allow_two_segments yes)
			(prefer_zone_connections yes)
		)
		(net 1)
	)
	(via
		(at 97.45 132.81)
		(size 0.45)
		(drill 0.1)
		(layers "F.Cu" "B.Cu")
		(remove_unused_layers yes)
		(keep_end_layers yes)
		(zone_layer_connections "In1.Cu" "In4.Cu" "In6.Cu")
		(teardrops
			(best_length_ratio 0.4)
			(max_length 1)
			(best_width_ratio 0.9)
			(max_width 2)
			(curved_edges yes)
			(filter_ratio 0.9)
			(enabled yes)
			(allow_two_segments yes)
			(prefer_zone_connections yes)
		)
		(net 1)
	)
	(via
		(at 99.45 130.81)
		(size 0.45)
		(drill 0.1)
		(layers "F.Cu" "B.Cu")
		(remove_unused_layers yes)
		(keep_end_layers yes)
		(zone_layer_connections "In1.Cu" "In4.Cu" "In6.Cu")
		(teardrops
			(best_length_ratio 0.4)
			(max_length 1)
			(best_width_ratio 0.9)
			(max_width 2)
			(curved_edges yes)
			(filter_ratio 0.9)
			(enabled yes)
			(allow_two_segments yes)
			(prefer_zone_connections yes)
		)
		(net 1)
	)
	(via
		(at 113.8 134.45)
		(size 0.45)
		(drill 0.1)
		(layers "F.Cu" "B.Cu")
		(remove_unused_layers yes)
		(keep_end_layers yes)
		(zone_layer_connections "In1.Cu" "In4.Cu" "In6.Cu")
		(teardrops
			(best_length_ratio 0.4)
			(max_length 1)
			(best_width_ratio 0.9)
			(max_width 2)
			(curved_edges yes)
			(filter_ratio 0.9)
			(enabled yes)
			(allow_two_segments yes)
			(prefer_zone_connections yes)
		)
		(net 1)
	)
	(via
		(at 305.45 113.81)
		(size 0.45)
		(drill 0.1)
		(layers "F.Cu" "B.Cu")
		(remove_unused_layers yes)
		(keep_end_layers yes)
		(zone_layer_connections "In1.Cu" "In4.Cu" "In6.Cu")
		(teardrops
			(best_length_ratio 0.4)
			(max_length 1)
			(best_width_ratio 0.9)
			(max_width 2)
			(curved_edges yes)
			(filter_ratio 0.9)
			(enabled yes)
			(allow_two_segments yes)
			(prefer_zone_connections yes)
		)
		(net 1)
	)
	(via
		(at 265.45 120.31)
		(size 0.45)
		(drill 0.1)
		(layers "F.Cu" "B.Cu")
		(remove_unused_layers yes)
		(keep_end_layers yes)
		(zone_layer_connections "In1.Cu" "In4.Cu" "In6.Cu")
		(teardrops
			(best_length_ratio 0.4)
			(max_length 1)
			(best_width_ratio 0.9)
			(max_width 2)
			(curved_edges yes)
			(filter_ratio 0.9)
			(enabled yes)
			(allow_two_segments yes)
			(prefer_zone_connections yes)
		)
		(net 1)
	)
	(via
		(at 99.458 160.6)
		(size 0.45)
		(drill 0.1)
		(layers "F.Cu" "B.Cu")
		(remove_unused_layers yes)
		(keep_end_layers yes)
		(zone_layer_connections "In1.Cu" "In4.Cu" "In6.Cu")
		(teardrops
			(best_length_ratio 0.4)
			(max_length 1)
			(best_width_ratio 0.9)
			(max_width 2)
			(curved_edges yes)
			(filter_ratio 0.9)
			(enabled yes)
			(allow_two_segments yes)
			(prefer_zone_connections yes)
		)
		(net 1)
	)
	(via
		(at 194.5 169.899)
		(size 0.45)
		(drill 0.1)
		(layers "F.Cu" "B.Cu")
		(teardrops
			(best_length_ratio 0.4)
			(max_length 1)
			(best_width_ratio 0.9)
			(max_width 2)
			(curved_edges yes)
			(filter_ratio 0.9)
			(enabled yes)
			(allow_two_segments yes)
			(prefer_zone_connections yes)
		)
		(net 1)
	)
	(via
		(at 126.95 155.81)
		(size 0.45)
		(drill 0.1)
		(layers "F.Cu" "B.Cu")
		(remove_unused_layers yes)
		(keep_end_layers yes)
		(zone_layer_connections "In1.Cu" "In4.Cu" "In6.Cu")
		(teardrops
			(best_length_ratio 0.4)
			(max_length 1)
			(best_width_ratio 0.9)
			(max_width 2)
			(curved_edges yes)
			(filter_ratio 0.9)
			(enabled yes)
			(allow_two_segments yes)
			(prefer_zone_connections yes)
		)
		(net 1)
	)
	(via
		(at 308.95 170.81)
		(size 0.45)
		(drill 0.1)
		(layers "F.Cu" "B.Cu")
		(remove_unused_layers yes)
		(keep_end_layers yes)
		(zone_layer_connections "In1.Cu" "In4.Cu" "In6.Cu")
		(teardrops
			(best_length_ratio 0.4)
			(max_length 1)
			(best_width_ratio 0.9)
			(max_width 2)
			(curved_edges yes)
			(filter_ratio 0.9)
			(enabled yes)
			(allow_two_segments yes)
			(prefer_zone_connections yes)
		)
		(net 1)
	)
	(via
		(at 189.35 152.35)
		(size 0.45)
		(drill 0.1)
		(layers "F.Cu" "B.Cu")
		(teardrops
			(best_length_ratio 0.4)
			(max_length 1)
			(best_width_ratio 0.9)
			(max_width 2)
			(curved_edges yes)
			(filter_ratio 0.9)
			(enabled yes)
			(allow_two_segments yes)
			(prefer_zone_connections yes)
		)
		(net 1)
	)
	(via
		(at 105.45 128.81)
		(size 0.45)
		(drill 0.1)
		(layers "F.Cu" "B.Cu")
		(remove_unused_layers yes)
		(keep_end_layers yes)
		(zone_layer_connections "In1.Cu" "In4.Cu" "In6.Cu")
		(teardrops
			(best_length_ratio 0.4)
			(max_length 1)
			(best_width_ratio 0.9)
			(max_width 2)
			(curved_edges yes)
			(filter_ratio 0.9)
			(enabled yes)
			(allow_two_segments yes)
			(prefer_zone_connections yes)
		)
		(net 1)
	)
	(via
		(at 114.45 112.31)
		(size 0.45)
		(drill 0.1)
		(layers "F.Cu" "B.Cu")
		(remove_unused_layers yes)
		(keep_end_layers yes)
		(zone_layer_connections "In1.Cu" "In4.Cu" "In6.Cu")
		(teardrops
			(best_length_ratio 0.4)
			(max_length 1)
			(best_width_ratio 0.9)
			(max_width 2)
			(curved_edges yes)
			(filter_ratio 0.9)
			(enabled yes)
			(allow_two_segments yes)
			(prefer_zone_connections yes)
		)
		(net 1)
	)
	(via
		(at 146.65 115.8)
		(size 0.45)
		(drill 0.1)
		(layers "F.Cu" "B.Cu")
		(remove_unused_layers yes)
		(keep_end_layers yes)
		(zone_layer_connections "In1.Cu" "In4.Cu" "In6.Cu")
		(teardrops
			(best_length_ratio 0.4)
			(max_length 1)
			(best_width_ratio 0.9)
			(max_width 2)
			(curved_edges yes)
			(filter_ratio 0.9)
			(enabled yes)
			(allow_two_segments yes)
			(prefer_zone_connections yes)
		)
		(net 1)
	)
	(via
		(at 132.45 157.62)
		(size 0.45)
		(drill 0.1)
		(layers "F.Cu" "B.Cu")
		(remove_unused_layers yes)
		(keep_end_layers yes)
		(zone_layer_connections "In1.Cu" "In4.Cu" "In6.Cu")
		(teardrops
			(best_length_ratio 0.4)
			(max_length 1)
			(best_width_ratio 0.9)
			(max_width 2)
			(curved_edges yes)
			(filter_ratio 0.9)
			(enabled yes)
			(allow_two_segments yes)
			(prefer_zone_connections yes)
		)
		(net 1)
	)
	(via
		(at 177.18 106.86)
		(size 0.45)
		(drill 0.1)
		(layers "F.Cu" "B.Cu")
		(remove_unused_layers yes)
		(keep_end_layers yes)
		(zone_layer_connections "In1.Cu" "In4.Cu" "In6.Cu")
		(teardrops
			(best_length_ratio 0.4)
			(max_length 1)
			(best_width_ratio 0.9)
			(max_width 2)
			(curved_edges yes)
			(filter_ratio 0.9)
			(enabled yes)
			(allow_two_segments yes)
			(prefer_zone_connections yes)
		)
		(net 1)
	)
	(via
		(at 96.45 137.81)
		(size 0.45)
		(drill 0.1)
		(layers "F.Cu" "B.Cu")
		(remove_unused_layers yes)
		(keep_end_layers yes)
		(zone_layer_connections "In1.Cu" "In4.Cu" "In6.Cu")
		(teardrops
			(best_length_ratio 0.4)
			(max_length 1)
			(best_width_ratio 0.9)
			(max_width 2)
			(curved_edges yes)
			(filter_ratio 0.9)
			(enabled yes)
			(allow_two_segments yes)
			(prefer_zone_connections yes)
		)
		(net 1)
	)
	(via
		(at 110.45 114.81)
		(size 0.45)
		(drill 0.1)
		(layers "F.Cu" "B.Cu")
		(remove_unused_layers yes)
		(keep_end_layers yes)
		(zone_layer_connections "In1.Cu" "In4.Cu" "In6.Cu")
		(teardrops
			(best_length_ratio 0.4)
			(max_length 1)
			(best_width_ratio 0.9)
			(max_width 2)
			(curved_edges yes)
			(filter_ratio 0.9)
			(enabled yes)
			(allow_two_segments yes)
			(prefer_zone_connections yes)
		)
		(net 1)
	)
	(via
		(at 109.32 162.4725)
		(size 0.45)
		(drill 0.1)
		(layers "F.Cu" "B.Cu")
		(remove_unused_layers yes)
		(keep_end_layers yes)
		(zone_layer_connections "In1.Cu" "In4.Cu" "In6.Cu")
		(teardrops
			(best_length_ratio 0.4)
			(max_length 1)
			(best_width_ratio 0.9)
			(max_width 2)
			(curved_edges yes)
			(filter_ratio 0.9)
			(enabled yes)
			(allow_two_segments yes)
			(prefer_zone_connections yes)
		)
		(net 1)
	)
	(via
		(at 290.8 101.86)
		(size 0.45)
		(drill 0.1)
		(layers "F.Cu" "B.Cu")
		(remove_unused_layers yes)
		(keep_end_layers yes)
		(free yes)
		(zone_layer_connections "In1.Cu" "In4.Cu" "In6.Cu")
		(teardrops
			(best_length_ratio 0.4)
			(max_length 1)
			(best_width_ratio 0.9)
			(max_width 2)
			(curved_edges yes)
			(filter_ratio 0.9)
			(enabled yes)
			(allow_two_segments yes)
			(prefer_zone_connections yes)
		)
		(net 1)
	)
	(via
		(at 126.45 162.81)
		(size 0.45)
		(drill 0.1)
		(layers "F.Cu" "B.Cu")
		(remove_unused_layers yes)
		(keep_end_layers yes)
		(zone_layer_connections "In1.Cu" "In4.Cu" "In6.Cu")
		(teardrops
			(best_length_ratio 0.4)
			(max_length 1)
			(best_width_ratio 0.9)
			(max_width 2)
			(curved_edges yes)
			(filter_ratio 0.9)
			(enabled yes)
			(allow_two_segments yes)
			(prefer_zone_connections yes)
		)
		(net 1)
	)
	(via
		(at 297.2 74.96)
		(size 0.45)
		(drill 0.1)
		(layers "F.Cu" "B.Cu")
		(remove_unused_layers yes)
		(keep_end_layers yes)
		(free yes)
		(zone_layer_connections "In1.Cu" "In4.Cu" "In6.Cu")
		(teardrops
			(best_length_ratio 0.4)
			(max_length 1)
			(best_width_ratio 0.9)
			(max_width 2)
			(curved_edges yes)
			(filter_ratio 0.9)
			(enabled yes)
			(allow_two_segments yes)
			(prefer_zone_connections yes)
		)
		(net 1)
	)
	(via
		(at 138.29 141.86)
		(size 0.45)
		(drill 0.1)
		(layers "F.Cu" "B.Cu")
		(remove_unused_layers yes)
		(keep_end_layers yes)
		(zone_layer_connections "In1.Cu" "In4.Cu" "In6.Cu")
		(teardrops
			(best_length_ratio 0.4)
			(max_length 1)
			(best_width_ratio 0.9)
			(max_width 2)
			(curved_edges yes)
			(filter_ratio 0.9)
			(enabled yes)
			(allow_two_segments yes)
			(prefer_zone_connections yes)
		)
		(net 1)
	)
	(via
		(at 138.95 87.31)
		(size 0.45)
		(drill 0.1)
		(layers "F.Cu" "B.Cu")
		(remove_unused_layers yes)
		(keep_end_layers yes)
		(zone_layer_connections "In1.Cu" "In4.Cu" "In6.Cu")
		(teardrops
			(best_length_ratio 0.4)
			(max_length 1)
			(best_width_ratio 0.9)
			(max_width 2)
			(curved_edges yes)
			(filter_ratio 0.9)
			(enabled yes)
			(allow_two_segments yes)
			(prefer_zone_connections yes)
		)
		(net 1)
	)
	(via
		(at 95.55696 106.030285)
		(size 0.45)
		(drill 0.1)
		(layers "F.Cu" "B.Cu")
		(remove_unused_layers yes)
		(keep_end_layers yes)
		(zone_layer_connections "In1.Cu" "In4.Cu" "In6.Cu")
		(teardrops
			(best_length_ratio 0.4)
			(max_length 1)
			(best_width_ratio 0.9)
			(max_width 2)
			(curved_edges yes)
			(filter_ratio 0.9)
			(enabled yes)
			(allow_two_segments yes)
			(prefer_zone_connections yes)
		)
		(net 1)
	)
	(via
		(at 103.45 170.81)
		(size 0.45)
		(drill 0.1)
		(layers "F.Cu" "B.Cu")
		(remove_unused_layers yes)
		(keep_end_layers yes)
		(zone_layer_connections "In1.Cu" "In4.Cu" "In6.Cu")
		(teardrops
			(best_length_ratio 0.4)
			(max_length 1)
			(best_width_ratio 0.9)
			(max_width 2)
			(curved_edges yes)
			(filter_ratio 0.9)
			(enabled yes)
			(allow_two_segments yes)
			(prefer_zone_connections yes)
		)
		(net 1)
	)
	(via
		(at 180.45 68.81)
		(size 0.45)
		(drill 0.1)
		(layers "F.Cu" "B.Cu")
		(remove_unused_layers yes)
		(keep_end_layers yes)
		(zone_layer_connections "In1.Cu" "In4.Cu" "In6.Cu")
		(teardrops
			(best_length_ratio 0.4)
			(max_length 1)
			(best_width_ratio 0.9)
			(max_width 2)
			(curved_edges yes)
			(filter_ratio 0.9)
			(enabled yes)
			(allow_two_segments yes)
			(prefer_zone_connections yes)
		)
		(net 1)
	)
	(via
		(at 202.375 166.925)
		(size 0.45)
		(drill 0.1)
		(layers "F.Cu" "B.Cu")
		(teardrops
			(best_length_ratio 0.4)
			(max_length 1)
			(best_width_ratio 0.9)
			(max_width 2)
			(curved_edges yes)
			(filter_ratio 0.9)
			(enabled yes)
			(allow_two_segments yes)
			(prefer_zone_connections yes)
		)
		(net 1)
	)
	(via
		(at 220.95 149.75)
		(size 0.45)
		(drill 0.1)
		(layers "F.Cu" "B.Cu")
		(teardrops
			(best_length_ratio 0.4)
			(max_length 1)
			(best_width_ratio 0.9)
			(max_width 2)
			(curved_edges yes)
			(filter_ratio 0.9)
			(enabled yes)
			(allow_two_segments yes)
			(prefer_zone_connections yes)
		)
		(net 1)
	)
	(via
		(at 252 126.211)
		(size 0.45)
		(drill 0.1)
		(layers "F.Cu" "B.Cu")
		(remove_unused_layers yes)
		(keep_end_layers yes)
		(zone_layer_connections "In1.Cu" "In4.Cu" "In6.Cu")
		(teardrops
			(best_length_ratio 0.4)
			(max_length 1)
			(best_width_ratio 0.9)
			(max_width 2)
			(curved_edges yes)
			(filter_ratio 0.9)
			(enabled yes)
			(allow_two_segments yes)
			(prefer_zone_connections yes)
		)
		(net 1)
	)
	(via
		(at 153.1 114.9)
		(size 0.45)
		(drill 0.1)
		(layers "F.Cu" "B.Cu")
		(remove_unused_layers yes)
		(keep_end_layers yes)
		(zone_layer_connections "In1.Cu" "In4.Cu" "In6.Cu")
		(teardrops
			(best_length_ratio 0.4)
			(max_length 1)
			(best_width_ratio 0.9)
			(max_width 2)
			(curved_edges yes)
			(filter_ratio 0.9)
			(enabled yes)
			(allow_two_segments yes)
			(prefer_zone_connections yes)
		)
		(net 1)
	)
	(via
		(at 95.45 124.81)
		(size 0.45)
		(drill 0.1)
		(layers "F.Cu" "B.Cu")
		(remove_unused_layers yes)
		(keep_end_layers yes)
		(zone_layer_connections "In1.Cu" "In4.Cu" "In6.Cu")
		(teardrops
			(best_length_ratio 0.4)
			(max_length 1)
			(best_width_ratio 0.9)
			(max_width 2)
			(curved_edges yes)
			(filter_ratio 0.9)
			(enabled yes)
			(allow_two_segments yes)
			(prefer_zone_connections yes)
		)
		(net 1)
	)
	(via
		(at 155.45 87.81)
		(size 0.45)
		(drill 0.1)
		(layers "F.Cu" "B.Cu")
		(remove_unused_layers yes)
		(keep_end_layers yes)
		(zone_layer_connections "In1.Cu" "In4.Cu" "In6.Cu")
		(teardrops
			(best_length_ratio 0.4)
			(max_length 1)
			(best_width_ratio 0.9)
			(max_width 2)
			(curved_edges yes)
			(filter_ratio 0.9)
			(enabled yes)
			(allow_two_segments yes)
			(prefer_zone_connections yes)
		)
		(net 1)
	)
	(via
		(at 98.855 128.91)
		(size 0.45)
		(drill 0.1)
		(layers "F.Cu" "B.Cu")
		(remove_unused_layers yes)
		(keep_end_layers yes)
		(zone_layer_connections "In1.Cu" "In4.Cu" "In6.Cu")
		(teardrops
			(best_length_ratio 0.4)
			(max_length 1)
			(best_width_ratio 0.9)
			(max_width 2)
			(curved_edges yes)
			(filter_ratio 0.9)
			(enabled yes)
			(allow_two_segments yes)
			(prefer_zone_connections yes)
		)
		(net 1)
	)
	(via
		(at 281.95 93.31)
		(size 0.45)
		(drill 0.1)
		(layers "F.Cu" "B.Cu")
		(remove_unused_layers yes)
		(keep_end_layers yes)
		(zone_layer_connections "In1.Cu" "In4.Cu" "In6.Cu")
		(teardrops
			(best_length_ratio 0.4)
			(max_length 1)
			(best_width_ratio 0.9)
			(max_width 2)
			(curved_edges yes)
			(filter_ratio 0.9)
			(enabled yes)
			(allow_two_segments yes)
			(prefer_zone_connections yes)
		)
		(net 1)
	)
	(via
		(at 231.85 146.65)
		(size 0.45)
		(drill 0.1)
		(layers "F.Cu" "B.Cu")
		(teardrops
			(best_length_ratio 0.4)
			(max_length 1)
			(best_width_ratio 0.9)
			(max_width 2)
			(curved_edges yes)
			(filter_ratio 0.9)
			(enabled yes)
			(allow_two_segments yes)
			(prefer_zone_connections yes)
		)
		(net 1)
	)
	(via
		(at 205.75 95.31)
		(size 0.45)
		(drill 0.1)
		(layers "F.Cu" "B.Cu")
		(remove_unused_layers yes)
		(keep_end_layers yes)
		(zone_layer_connections "In1.Cu" "In4.Cu" "In6.Cu")
		(teardrops
			(best_length_ratio 0.4)
			(max_length 1)
			(best_width_ratio 0.9)
			(max_width 2)
			(curved_edges yes)
			(filter_ratio 0.9)
			(enabled yes)
			(allow_two_segments yes)
			(prefer_zone_connections yes)
		)
		(net 1)
	)
	(via
		(at 128.29 137.86)
		(size 0.45)
		(drill 0.1)
		(layers "F.Cu" "B.Cu")
		(remove_unused_layers yes)
		(keep_end_layers yes)
		(zone_layer_connections "In1.Cu" "In4.Cu" "In6.Cu")
		(teardrops
			(best_length_ratio 0.4)
			(max_length 1)
			(best_width_ratio 0.9)
			(max_width 2)
			(curved_edges yes)
			(filter_ratio 0.9)
			(enabled yes)
			(allow_two_segments yes)
			(prefer_zone_connections yes)
		)
		(net 1)
	)
	(via
		(at 150.45 163.16)
		(size 0.45)
		(drill 0.1)
		(layers "F.Cu" "B.Cu")
		(remove_unused_layers yes)
		(keep_end_layers yes)
		(zone_layer_connections "In1.Cu" "In4.Cu" "In6.Cu")
		(teardrops
			(best_length_ratio 0.4)
			(max_length 1)
			(best_width_ratio 0.9)
			(max_width 2)
			(curved_edges yes)
			(filter_ratio 0.9)
			(enabled yes)
			(allow_two_segments yes)
			(prefer_zone_connections yes)
		)
		(net 1)
	)
	(via
		(at 182.4 166.9)
		(size 0.45)
		(drill 0.1)
		(layers "F.Cu" "B.Cu")
		(teardrops
			(best_length_ratio 0.4)
			(max_length 1)
			(best_width_ratio 0.9)
			(max_width 2)
			(curved_edges yes)
			(filter_ratio 0.9)
			(enabled yes)
			(allow_two_segments yes)
			(prefer_zone_connections yes)
		)
		(net 1)
	)
	(via
		(at 214.95 86.31)
		(size 0.45)
		(drill 0.1)
		(layers "F.Cu" "B.Cu")
		(remove_unused_layers yes)
		(keep_end_layers yes)
		(zone_layer_connections "In1.Cu" "In4.Cu" "In6.Cu")
		(teardrops
			(best_length_ratio 0.4)
			(max_length 1)
			(best_width_ratio 0.9)
			(max_width 2)
			(curved_edges yes)
			(filter_ratio 0.9)
			(enabled yes)
			(allow_two_segments yes)
			(prefer_zone_connections yes)
		)
		(net 1)
	)
	(via
		(at 242.95 114.31)
		(size 0.45)
		(drill 0.1)
		(layers "F.Cu" "B.Cu")
		(remove_unused_layers yes)
		(keep_end_layers yes)
		(zone_layer_connections "In1.Cu" "In4.Cu" "In6.Cu")
		(teardrops
			(best_length_ratio 0.4)
			(max_length 1)
			(best_width_ratio 0.9)
			(max_width 2)
			(curved_edges yes)
			(filter_ratio 0.9)
			(enabled yes)
			(allow_two_segments yes)
			(prefer_zone_connections yes)
		)
		(net 1)
	)
	(via
		(at 126.95 152.81)
		(size 0.45)
		(drill 0.1)
		(layers "F.Cu" "B.Cu")
		(remove_unused_layers yes)
		(keep_end_layers yes)
		(zone_layer_connections "In1.Cu" "In4.Cu" "In6.Cu")
		(teardrops
			(best_length_ratio 0.4)
			(max_length 1)
			(best_width_ratio 0.9)
			(max_width 2)
			(curved_edges yes)
			(filter_ratio 0.9)
			(enabled yes)
			(allow_two_segments yes)
			(prefer_zone_connections yes)
		)
		(net 1)
	)
	(via
		(at 258 136.85)
		(size 0.45)
		(drill 0.1)
		(layers "F.Cu" "B.Cu")
		(remove_unused_layers yes)
		(keep_end_layers yes)
		(zone_layer_connections "In1.Cu" "In4.Cu" "In6.Cu")
		(teardrops
			(best_length_ratio 0.4)
			(max_length 1)
			(best_width_ratio 0.9)
			(max_width 2)
			(curved_edges yes)
			(filter_ratio 0.9)
			(enabled yes)
			(allow_two_segments yes)
			(prefer_zone_connections yes)
		)
		(net 1)
	)
	(via
		(at 99.95 99.81)
		(size 0.45)
		(drill 0.1)
		(layers "F.Cu" "B.Cu")
		(remove_unused_layers yes)
		(keep_end_layers yes)
		(zone_layer_connections "In1.Cu" "In4.Cu" "In6.Cu")
		(teardrops
			(best_length_ratio 0.4)
			(max_length 1)
			(best_width_ratio 0.9)
			(max_width 2)
			(curved_edges yes)
			(filter_ratio 0.9)
			(enabled yes)
			(allow_two_segments yes)
			(prefer_zone_connections yes)
		)
		(net 1)
	)
	(via
		(at 296.95 170.81)
		(size 0.45)
		(drill 0.1)
		(layers "F.Cu" "B.Cu")
		(remove_unused_layers yes)
		(keep_end_layers yes)
		(zone_layer_connections "In1.Cu" "In4.Cu" "In6.Cu")
		(teardrops
			(best_length_ratio 0.4)
			(max_length 1)
			(best_width_ratio 0.9)
			(max_width 2)
			(curved_edges yes)
			(filter_ratio 0.9)
			(enabled yes)
			(allow_two_segments yes)
			(prefer_zone_connections yes)
		)
		(net 1)
	)
	(via
		(at 105.925 165.6)
		(size 0.45)
		(drill 0.1)
		(layers "F.Cu" "B.Cu")
		(remove_unused_layers yes)
		(keep_end_layers yes)
		(free yes)
		(zone_layer_connections "In1.Cu" "In4.Cu" "In6.Cu")
		(teardrops
			(best_length_ratio 0.4)
			(max_length 1)
			(best_width_ratio 0.9)
			(max_width 2)
			(curved_edges yes)
			(filter_ratio 0.9)
			(enabled yes)
			(allow_two_segments yes)
			(prefer_zone_connections yes)
		)
		(net 1)
	)
	(via
		(at 214.45 78.11)
		(size 0.45)
		(drill 0.1)
		(layers "F.Cu" "B.Cu")
		(remove_unused_layers yes)
		(keep_end_layers yes)
		(zone_layer_connections "In1.Cu" "In4.Cu" "In6.Cu")
		(teardrops
			(best_length_ratio 0.4)
			(max_length 1)
			(best_width_ratio 0.9)
			(max_width 2)
			(curved_edges yes)
			(filter_ratio 0.9)
			(enabled yes)
			(allow_two_segments yes)
			(prefer_zone_connections yes)
		)
		(net 1)
	)
	(via
		(at 316.4645 98.6365)
		(size 0.45)
		(drill 0.1)
		(layers "F.Cu" "B.Cu")
		(remove_unused_layers yes)
		(keep_end_layers yes)
		(free yes)
		(zone_layer_connections "In1.Cu" "In4.Cu" "In6.Cu")
		(teardrops
			(best_length_ratio 0.4)
			(max_length 1)
			(best_width_ratio 0.9)
			(max_width 2)
			(curved_edges yes)
			(filter_ratio 0.9)
			(enabled yes)
			(allow_two_segments yes)
			(prefer_zone_connections yes)
		)
		(net 1)
	)
	(via
		(at 138.45 78.31)
		(size 0.45)
		(drill 0.1)
		(layers "F.Cu" "B.Cu")
		(remove_unused_layers yes)
		(keep_end_layers yes)
		(zone_layer_connections "In1.Cu" "In4.Cu" "In6.Cu")
		(teardrops
			(best_length_ratio 0.4)
			(max_length 1)
			(best_width_ratio 0.9)
			(max_width 2)
			(curved_edges yes)
			(filter_ratio 0.9)
			(enabled yes)
			(allow_two_segments yes)
			(prefer_zone_connections yes)
		)
		(net 1)
	)
	(via
		(at 209.025 152.275)
		(size 0.45)
		(drill 0.1)
		(layers "F.Cu" "B.Cu")
		(teardrops
			(best_length_ratio 0.4)
			(max_length 1)
			(best_width_ratio 0.9)
			(max_width 2)
			(curved_edges yes)
			(filter_ratio 0.9)
			(enabled yes)
			(allow_two_segments yes)
			(prefer_zone_connections yes)
		)
		(net 1)
	)
	(via
		(at 160.455 153.85)
		(size 0.45)
		(drill 0.1)
		(layers "F.Cu" "B.Cu")
		(remove_unused_layers yes)
		(keep_end_layers yes)
		(zone_layer_connections "In1.Cu" "In4.Cu" "In6.Cu")
		(teardrops
			(best_length_ratio 0.4)
			(max_length 1)
			(best_width_ratio 0.9)
			(max_width 2)
			(curved_edges yes)
			(filter_ratio 0.9)
			(enabled yes)
			(allow_two_segments yes)
			(prefer_zone_connections yes)
		)
		(net 1)
	)
	(via
		(at 150.175 71.485)
		(size 0.45)
		(drill 0.1)
		(layers "F.Cu" "B.Cu")
		(remove_unused_layers yes)
		(keep_end_layers yes)
		(free yes)
		(zone_layer_connections "In1.Cu" "In4.Cu" "In6.Cu")
		(teardrops
			(best_length_ratio 0.4)
			(max_length 1)
			(best_width_ratio 0.9)
			(max_width 2)
			(curved_edges yes)
			(filter_ratio 0.9)
			(enabled yes)
			(allow_two_segments yes)
			(prefer_zone_connections yes)
		)
		(net 1)
	)
	(via
		(at 167.2 150.2)
		(size 0.45)
		(drill 0.1)
		(layers "F.Cu" "B.Cu")
		(teardrops
			(best_length_ratio 0.4)
			(max_length 1)
			(best_width_ratio 0.9)
			(max_width 2)
			(curved_edges yes)
			(filter_ratio 0.9)
			(enabled yes)
			(allow_two_segments yes)
			(prefer_zone_connections yes)
		)
		(net 1)
	)
	(via
		(at 159.999 159.897)
		(size 0.45)
		(drill 0.1)
		(layers "F.Cu" "B.Cu")
		(remove_unused_layers yes)
		(keep_end_layers yes)
		(zone_layer_connections "In1.Cu" "In4.Cu" "In6.Cu")
		(teardrops
			(best_length_ratio 0.4)
			(max_length 1)
			(best_width_ratio 0.9)
			(max_width 2)
			(curved_edges yes)
			(filter_ratio 0.9)
			(enabled yes)
			(allow_two_segments yes)
			(prefer_zone_connections yes)
		)
		(net 1)
	)
	(via
		(at 285.6 85.66)
		(size 0.45)
		(drill 0.1)
		(layers "F.Cu" "B.Cu")
		(remove_unused_layers yes)
		(keep_end_layers yes)
		(zone_layer_connections "In1.Cu" "In4.Cu" "In6.Cu")
		(teardrops
			(best_length_ratio 0.4)
			(max_length 1)
			(best_width_ratio 0.9)
			(max_width 2)
			(curved_edges yes)
			(filter_ratio 0.9)
			(enabled yes)
			(allow_two_segments yes)
			(prefer_zone_connections yes)
		)
		(net 1)
	)
	(via
		(at 173.2 96.3)
		(size 0.45)
		(drill 0.1)
		(layers "F.Cu" "B.Cu")
		(remove_unused_layers yes)
		(keep_end_layers yes)
		(zone_layer_connections "In1.Cu" "In4.Cu" "In6.Cu")
		(teardrops
			(best_length_ratio 0.4)
			(max_length 1)
			(best_width_ratio 0.9)
			(max_width 2)
			(curved_edges yes)
			(filter_ratio 0.9)
			(enabled yes)
			(allow_two_segments yes)
			(prefer_zone_connections yes)
		)
		(net 1)
	)
	(via
		(at 155.02 147.63)
		(size 0.45)
		(drill 0.1)
		(layers "F.Cu" "B.Cu")
		(remove_unused_layers yes)
		(keep_end_layers yes)
		(zone_layer_connections "In1.Cu" "In4.Cu" "In6.Cu")
		(teardrops
			(best_length_ratio 0.4)
			(max_length 1)
			(best_width_ratio 0.9)
			(max_width 2)
			(curved_edges yes)
			(filter_ratio 0.9)
			(enabled yes)
			(allow_two_segments yes)
			(prefer_zone_connections yes)
		)
		(net 1)
	)
	(via
		(at 250.95 88.31)
		(size 0.45)
		(drill 0.1)
		(layers "F.Cu" "B.Cu")
		(remove_unused_layers yes)
		(keep_end_layers yes)
		(zone_layer_connections "In1.Cu" "In4.Cu" "In6.Cu")
		(teardrops
			(best_length_ratio 0.4)
			(max_length 1)
			(best_width_ratio 0.9)
			(max_width 2)
			(curved_edges yes)
			(filter_ratio 0.9)
			(enabled yes)
			(allow_two_segments yes)
			(prefer_zone_connections yes)
		)
		(net 1)
	)
	(via
		(at 137.29 137.86)
		(size 0.45)
		(drill 0.1)
		(layers "F.Cu" "B.Cu")
		(remove_unused_layers yes)
		(keep_end_layers yes)
		(zone_layer_connections "In1.Cu" "In4.Cu" "In6.Cu")
		(teardrops
			(best_length_ratio 0.4)
			(max_length 1)
			(best_width_ratio 0.9)
			(max_width 2)
			(curved_edges yes)
			(filter_ratio 0.9)
			(enabled yes)
			(allow_two_segments yes)
			(prefer_zone_connections yes)
		)
		(net 1)
	)
	(via
		(at 192.381997 137.917221)
		(size 0.45)
		(drill 0.1)
		(layers "F.Cu" "B.Cu")
		(remove_unused_layers yes)
		(keep_end_layers yes)
		(zone_layer_connections "In1.Cu" "In4.Cu" "In6.Cu")
		(teardrops
			(best_length_ratio 0.4)
			(max_length 1)
			(best_width_ratio 0.9)
			(max_width 2)
			(curved_edges yes)
			(filter_ratio 0.9)
			(enabled yes)
			(allow_two_segments yes)
			(prefer_zone_connections yes)
		)
		(net 1)
	)
	(via
		(at 135.6 102.48)
		(size 0.45)
		(drill 0.1)
		(layers "F.Cu" "B.Cu")
		(remove_unused_layers yes)
		(keep_end_layers yes)
		(zone_layer_connections "In1.Cu" "In4.Cu" "In6.Cu")
		(teardrops
			(best_length_ratio 0.4)
			(max_length 1)
			(best_width_ratio 0.9)
			(max_width 2)
			(curved_edges yes)
			(filter_ratio 0.9)
			(enabled yes)
			(allow_two_segments yes)
			(prefer_zone_connections yes)
		)
		(net 1)
	)
	(via
		(at 137.29 141.86)
		(size 0.45)
		(drill 0.1)
		(layers "F.Cu" "B.Cu")
		(remove_unused_layers yes)
		(keep_end_layers yes)
		(zone_layer_connections "In1.Cu" "In4.Cu" "In6.Cu")
		(teardrops
			(best_length_ratio 0.4)
			(max_length 1)
			(best_width_ratio 0.9)
			(max_width 2)
			(curved_edges yes)
			(filter_ratio 0.9)
			(enabled yes)
			(allow_two_segments yes)
			(prefer_zone_connections yes)
		)
		(net 1)
	)
	(via
		(at 233.45 148.1)
		(size 0.45)
		(drill 0.1)
		(layers "F.Cu" "B.Cu")
		(teardrops
			(best_length_ratio 0.4)
			(max_length 1)
			(best_width_ratio 0.9)
			(max_width 2)
			(curved_edges yes)
			(filter_ratio 0.9)
			(enabled yes)
			(allow_two_segments yes)
			(prefer_zone_connections yes)
		)
		(net 1)
	)
	(via
		(at 104.45 74.81)
		(size 0.45)
		(drill 0.1)
		(layers "F.Cu" "B.Cu")
		(remove_unused_layers yes)
		(keep_end_layers yes)
		(zone_layer_connections "In1.Cu" "In4.Cu" "In6.Cu")
		(teardrops
			(best_length_ratio 0.4)
			(max_length 1)
			(best_width_ratio 0.9)
			(max_width 2)
			(curved_edges yes)
			(filter_ratio 0.9)
			(enabled yes)
			(allow_two_segments yes)
			(prefer_zone_connections yes)
		)
		(net 1)
	)
	(via
		(at 132.3 74.51)
		(size 0.45)
		(drill 0.1)
		(layers "F.Cu" "B.Cu")
		(remove_unused_layers yes)
		(keep_end_layers yes)
		(zone_layer_connections "In1.Cu" "In4.Cu" "In6.Cu")
		(teardrops
			(best_length_ratio 0.4)
			(max_length 1)
			(best_width_ratio 0.9)
			(max_width 2)
			(curved_edges yes)
			(filter_ratio 0.9)
			(enabled yes)
			(allow_two_segments yes)
			(prefer_zone_connections yes)
		)
		(net 1)
	)
	(via
		(at 282.45 128.31)
		(size 0.45)
		(drill 0.1)
		(layers "F.Cu" "B.Cu")
		(remove_unused_layers yes)
		(keep_end_layers yes)
		(zone_layer_connections "In1.Cu" "In4.Cu" "In6.Cu")
		(teardrops
			(best_length_ratio 0.4)
			(max_length 1)
			(best_width_ratio 0.9)
			(max_width 2)
			(curved_edges yes)
			(filter_ratio 0.9)
			(enabled yes)
			(allow_two_segments yes)
			(prefer_zone_connections yes)
		)
		(net 1)
	)
	(via
		(at 127.45 165.81)
		(size 0.45)
		(drill 0.1)
		(layers "F.Cu" "B.Cu")
		(remove_unused_layers yes)
		(keep_end_layers yes)
		(zone_layer_connections "In1.Cu" "In4.Cu" "In6.Cu")
		(teardrops
			(best_length_ratio 0.4)
			(max_length 1)
			(best_width_ratio 0.9)
			(max_width 2)
			(curved_edges yes)
			(filter_ratio 0.9)
			(enabled yes)
			(allow_two_segments yes)
			(prefer_zone_connections yes)
		)
		(net 1)
	)
	(via
		(at 130.29 135.86)
		(size 0.45)
		(drill 0.1)
		(layers "F.Cu" "B.Cu")
		(remove_unused_layers yes)
		(keep_end_layers yes)
		(zone_layer_connections "In1.Cu" "In4.Cu" "In6.Cu")
		(teardrops
			(best_length_ratio 0.4)
			(max_length 1)
			(best_width_ratio 0.9)
			(max_width 2)
			(curved_edges yes)
			(filter_ratio 0.9)
			(enabled yes)
			(allow_two_segments yes)
			(prefer_zone_connections yes)
		)
		(net 1)
	)
	(via
		(at 105.45 114.81)
		(size 0.45)
		(drill 0.1)
		(layers "F.Cu" "B.Cu")
		(remove_unused_layers yes)
		(keep_end_layers yes)
		(zone_layer_connections "In1.Cu" "In4.Cu" "In6.Cu")
		(teardrops
			(best_length_ratio 0.4)
			(max_length 1)
			(best_width_ratio 0.9)
			(max_width 2)
			(curved_edges yes)
			(filter_ratio 0.9)
			(enabled yes)
			(allow_two_segments yes)
			(prefer_zone_connections yes)
		)
		(net 1)
	)
	(via
		(at 137.29 134.86)
		(size 0.45)
		(drill 0.1)
		(layers "F.Cu" "B.Cu")
		(remove_unused_layers yes)
		(keep_end_layers yes)
		(zone_layer_connections "In1.Cu" "In4.Cu" "In6.Cu")
		(teardrops
			(best_length_ratio 0.4)
			(max_length 1)
			(best_width_ratio 0.9)
			(max_width 2)
			(curved_edges yes)
			(filter_ratio 0.9)
			(enabled yes)
			(allow_two_segments yes)
			(prefer_zone_connections yes)
		)
		(net 1)
	)
	(via
		(at 133.29 143.86)
		(size 0.45)
		(drill 0.1)
		(layers "F.Cu" "B.Cu")
		(remove_unused_layers yes)
		(keep_end_layers yes)
		(zone_layer_connections "In1.Cu" "In4.Cu" "In6.Cu")
		(teardrops
			(best_length_ratio 0.4)
			(max_length 1)
			(best_width_ratio 0.9)
			(max_width 2)
			(curved_edges yes)
			(filter_ratio 0.9)
			(enabled yes)
			(allow_two_segments yes)
			(prefer_zone_connections yes)
		)
		(net 1)
	)
	(via
		(at 195.55 159.85)
		(size 0.45)
		(drill 0.1)
		(layers "F.Cu" "B.Cu")
		(teardrops
			(best_length_ratio 0.4)
			(max_length 1)
			(best_width_ratio 0.9)
			(max_width 2)
			(curved_edges yes)
			(filter_ratio 0.9)
			(enabled yes)
			(allow_two_segments yes)
			(prefer_zone_connections yes)
		)
		(net 1)
	)
	(via
		(at 136.26 111.89)
		(size 0.45)
		(drill 0.1)
		(layers "F.Cu" "B.Cu")
		(remove_unused_layers yes)
		(keep_end_layers yes)
		(zone_layer_connections "In1.Cu" "In4.Cu" "In6.Cu")
		(teardrops
			(best_length_ratio 0.4)
			(max_length 1)
			(best_width_ratio 0.9)
			(max_width 2)
			(curved_edges yes)
			(filter_ratio 0.9)
			(enabled yes)
			(allow_two_segments yes)
			(prefer_zone_connections yes)
		)
		(net 1)
	)
	(via
		(at 284.45 80.31)
		(size 0.45)
		(drill 0.1)
		(layers "F.Cu" "B.Cu")
		(remove_unused_layers yes)
		(keep_end_layers yes)
		(zone_layer_connections "In1.Cu" "In4.Cu" "In6.Cu")
		(teardrops
			(best_length_ratio 0.4)
			(max_length 1)
			(best_width_ratio 0.9)
			(max_width 2)
			(curved_edges yes)
			(filter_ratio 0.9)
			(enabled yes)
			(allow_two_segments yes)
			(prefer_zone_connections yes)
		)
		(net 1)
	)
	(via
		(at 177.18 103.86)
		(size 0.45)
		(drill 0.1)
		(layers "F.Cu" "B.Cu")
		(remove_unused_layers yes)
		(keep_end_layers yes)
		(zone_layer_connections "In1.Cu" "In4.Cu" "In6.Cu")
		(teardrops
			(best_length_ratio 0.4)
			(max_length 1)
			(best_width_ratio 0.9)
			(max_width 2)
			(curved_edges yes)
			(filter_ratio 0.9)
			(enabled yes)
			(allow_two_segments yes)
			(prefer_zone_connections yes)
		)
		(net 1)
	)
	(via
		(at 302.45 112.31)
		(size 0.45)
		(drill 0.1)
		(layers "F.Cu" "B.Cu")
		(remove_unused_layers yes)
		(keep_end_layers yes)
		(zone_layer_connections "In1.Cu" "In4.Cu" "In6.Cu")
		(teardrops
			(best_length_ratio 0.4)
			(max_length 1)
			(best_width_ratio 0.9)
			(max_width 2)
			(curved_edges yes)
			(filter_ratio 0.9)
			(enabled yes)
			(allow_two_segments yes)
			(prefer_zone_connections yes)
		)
		(net 1)
	)
	(via
		(at 139.95 91.81)
		(size 0.45)
		(drill 0.1)
		(layers "F.Cu" "B.Cu")
		(remove_unused_layers yes)
		(keep_end_layers yes)
		(zone_layer_connections "In1.Cu" "In4.Cu" "In6.Cu")
		(teardrops
			(best_length_ratio 0.4)
			(max_length 1)
			(best_width_ratio 0.9)
			(max_width 2)
			(curved_edges yes)
			(filter_ratio 0.9)
			(enabled yes)
			(allow_two_segments yes)
			(prefer_zone_connections yes)
		)
		(net 1)
	)
	(via
		(at 122.05 152.82)
		(size 0.45)
		(drill 0.1)
		(layers "F.Cu" "B.Cu")
		(remove_unused_layers yes)
		(keep_end_layers yes)
		(zone_layer_connections "In1.Cu" "In4.Cu" "In6.Cu")
		(teardrops
			(best_length_ratio 0.4)
			(max_length 1)
			(best_width_ratio 0.9)
			(max_width 2)
			(curved_edges yes)
			(filter_ratio 0.9)
			(enabled yes)
			(allow_two_segments yes)
			(prefer_zone_connections yes)
		)
		(net 1)
	)
	(via
		(at 282.45 166.41)
		(size 0.45)
		(drill 0.1)
		(layers "F.Cu" "B.Cu")
		(remove_unused_layers yes)
		(keep_end_layers yes)
		(zone_layer_connections "In1.Cu" "In4.Cu" "In6.Cu")
		(teardrops
			(best_length_ratio 0.4)
			(max_length 1)
			(best_width_ratio 0.9)
			(max_width 2)
			(curved_edges yes)
			(filter_ratio 0.9)
			(enabled yes)
			(allow_two_segments yes)
			(prefer_zone_connections yes)
		)
		(net 1)
	)
	(via
		(at 138.3 74.51)
		(size 0.45)
		(drill 0.1)
		(layers "F.Cu" "B.Cu")
		(remove_unused_layers yes)
		(keep_end_layers yes)
		(zone_layer_connections "In1.Cu" "In4.Cu" "In6.Cu")
		(teardrops
			(best_length_ratio 0.4)
			(max_length 1)
			(best_width_ratio 0.9)
			(max_width 2)
			(curved_edges yes)
			(filter_ratio 0.9)
			(enabled yes)
			(allow_two_segments yes)
			(prefer_zone_connections yes)
		)
		(net 1)
	)
	(via
		(at 116.65 146.801)
		(size 0.45)
		(drill 0.1)
		(layers "F.Cu" "B.Cu")
		(remove_unused_layers yes)
		(keep_end_layers yes)
		(zone_layer_connections "In1.Cu" "In4.Cu" "In6.Cu")
		(teardrops
			(best_length_ratio 0.4)
			(max_length 1)
			(best_width_ratio 0.9)
			(max_width 2)
			(curved_edges yes)
			(filter_ratio 0.9)
			(enabled yes)
			(allow_two_segments yes)
			(prefer_zone_connections yes)
		)
		(net 1)
	)
	(via
		(at 312.95 83.31)
		(size 0.45)
		(drill 0.1)
		(layers "F.Cu" "B.Cu")
		(remove_unused_layers yes)
		(keep_end_layers yes)
		(zone_layer_connections "In1.Cu" "In4.Cu" "In6.Cu")
		(teardrops
			(best_length_ratio 0.4)
			(max_length 1)
			(best_width_ratio 0.9)
			(max_width 2)
			(curved_edges yes)
			(filter_ratio 0.9)
			(enabled yes)
			(allow_two_segments yes)
			(prefer_zone_connections yes)
		)
		(net 1)
	)
	(via
		(at 138.29 132.86)
		(size 0.45)
		(drill 0.1)
		(layers "F.Cu" "B.Cu")
		(remove_unused_layers yes)
		(keep_end_layers yes)
		(zone_layer_connections "In1.Cu" "In4.Cu" "In6.Cu")
		(teardrops
			(best_length_ratio 0.4)
			(max_length 1)
			(best_width_ratio 0.9)
			(max_width 2)
			(curved_edges yes)
			(filter_ratio 0.9)
			(enabled yes)
			(allow_two_segments yes)
			(prefer_zone_connections yes)
		)
		(net 1)
	)
	(via
		(at 310.7395 134.21)
		(size 0.45)
		(drill 0.1)
		(layers "F.Cu" "B.Cu")
		(remove_unused_layers yes)
		(keep_end_layers yes)
		(zone_layer_connections "In1.Cu" "In4.Cu" "In6.Cu")
		(teardrops
			(best_length_ratio 0.4)
			(max_length 1)
			(best_width_ratio 0.9)
			(max_width 2)
			(curved_edges yes)
			(filter_ratio 0.9)
			(enabled yes)
			(allow_two_segments yes)
			(prefer_zone_connections yes)
		)
		(net 1)
	)
	(via
		(at 198.45 68.81)
		(size 0.45)
		(drill 0.1)
		(layers "F.Cu" "B.Cu")
		(remove_unused_layers yes)
		(keep_end_layers yes)
		(free yes)
		(zone_layer_connections "In1.Cu" "In4.Cu" "In6.Cu")
		(teardrops
			(best_length_ratio 0.4)
			(max_length 1)
			(best_width_ratio 0.9)
			(max_width 2)
			(curved_edges yes)
			(filter_ratio 0.9)
			(enabled yes)
			(allow_two_segments yes)
			(prefer_zone_connections yes)
		)
		(net 1)
	)
	(via
		(at 105.1 86.084)
		(size 0.45)
		(drill 0.1)
		(layers "F.Cu" "B.Cu")
		(remove_unused_layers yes)
		(keep_end_layers yes)
		(zone_layer_connections "In1.Cu" "In4.Cu" "In6.Cu")
		(teardrops
			(best_length_ratio 0.4)
			(max_length 1)
			(best_width_ratio 0.9)
			(max_width 2)
			(curved_edges yes)
			(filter_ratio 0.9)
			(enabled yes)
			(allow_two_segments yes)
			(prefer_zone_connections yes)
		)
		(net 1)
	)
	(via
		(at 127.45 161.81)
		(size 0.45)
		(drill 0.1)
		(layers "F.Cu" "B.Cu")
		(remove_unused_layers yes)
		(keep_end_layers yes)
		(zone_layer_connections "In1.Cu" "In4.Cu" "In6.Cu")
		(teardrops
			(best_length_ratio 0.4)
			(max_length 1)
			(best_width_ratio 0.9)
			(max_width 2)
			(curved_edges yes)
			(filter_ratio 0.9)
			(enabled yes)
			(allow_two_segments yes)
			(prefer_zone_connections yes)
		)
		(net 1)
	)
	(via
		(at 118.45 162.81)
		(size 0.45)
		(drill 0.1)
		(layers "F.Cu" "B.Cu")
		(remove_unused_layers yes)
		(keep_end_layers yes)
		(zone_layer_connections "In1.Cu" "In4.Cu" "In6.Cu")
		(teardrops
			(best_length_ratio 0.4)
			(max_length 1)
			(best_width_ratio 0.9)
			(max_width 2)
			(curved_edges yes)
			(filter_ratio 0.9)
			(enabled yes)
			(allow_two_segments yes)
			(prefer_zone_connections yes)
		)
		(net 1)
	)
	(via
		(at 131.45 163.81)
		(size 0.45)
		(drill 0.1)
		(layers "F.Cu" "B.Cu")
		(remove_unused_layers yes)
		(keep_end_layers yes)
		(zone_layer_connections "In1.Cu" "In4.Cu" "In6.Cu")
		(teardrops
			(best_length_ratio 0.4)
			(max_length 1)
			(best_width_ratio 0.9)
			(max_width 2)
			(curved_edges yes)
			(filter_ratio 0.9)
			(enabled yes)
			(allow_two_segments yes)
			(prefer_zone_connections yes)
		)
		(net 1)
	)
	(via
		(at 152.5685 89.5585)
		(size 0.45)
		(drill 0.1)
		(layers "F.Cu" "B.Cu")
		(remove_unused_layers yes)
		(keep_end_layers yes)
		(zone_layer_connections "In1.Cu" "In4.Cu" "In6.Cu")
		(teardrops
			(best_length_ratio 0.4)
			(max_length 1)
			(best_width_ratio 0.9)
			(max_width 2)
			(curved_edges yes)
			(filter_ratio 0.9)
			(enabled yes)
			(allow_two_segments yes)
			(prefer_zone_connections yes)
		)
		(net 1)
	)
	(via
		(at 306.95 69.81)
		(size 0.45)
		(drill 0.1)
		(layers "F.Cu" "B.Cu")
		(remove_unused_layers yes)
		(keep_end_layers yes)
		(zone_layer_connections "In1.Cu" "In4.Cu" "In6.Cu")
		(teardrops
			(best_length_ratio 0.4)
			(max_length 1)
			(best_width_ratio 0.9)
			(max_width 2)
			(curved_edges yes)
			(filter_ratio 0.9)
			(enabled yes)
			(allow_two_segments yes)
			(prefer_zone_connections yes)
		)
		(net 1)
	)
	(via
		(at 217.95 86.31)
		(size 0.45)
		(drill 0.1)
		(layers "F.Cu" "B.Cu")
		(remove_unused_layers yes)
		(keep_end_layers yes)
		(zone_layer_connections "In1.Cu" "In4.Cu" "In6.Cu")
		(teardrops
			(best_length_ratio 0.4)
			(max_length 1)
			(best_width_ratio 0.9)
			(max_width 2)
			(curved_edges yes)
			(filter_ratio 0.9)
			(enabled yes)
			(allow_two_segments yes)
			(prefer_zone_connections yes)
		)
		(net 1)
	)
	(via
		(at 223.95 89.31)
		(size 0.45)
		(drill 0.1)
		(layers "F.Cu" "B.Cu")
		(remove_unused_layers yes)
		(keep_end_layers yes)
		(zone_layer_connections "In1.Cu" "In4.Cu" "In6.Cu")
		(teardrops
			(best_length_ratio 0.4)
			(max_length 1)
			(best_width_ratio 0.9)
			(max_width 2)
			(curved_edges yes)
			(filter_ratio 0.9)
			(enabled yes)
			(allow_two_segments yes)
			(prefer_zone_connections yes)
		)
		(net 1)
	)
	(via
		(at 167.95 86.81)
		(size 0.45)
		(drill 0.1)
		(layers "F.Cu" "B.Cu")
		(remove_unused_layers yes)
		(keep_end_layers yes)
		(zone_layer_connections "In1.Cu" "In4.Cu" "In6.Cu")
		(teardrops
			(best_length_ratio 0.4)
			(max_length 1)
			(best_width_ratio 0.9)
			(max_width 2)
			(curved_edges yes)
			(filter_ratio 0.9)
			(enabled yes)
			(allow_two_segments yes)
			(prefer_zone_connections yes)
		)
		(net 1)
	)
	(via
		(at 101.31 158.12)
		(size 0.45)
		(drill 0.1)
		(layers "F.Cu" "B.Cu")
		(remove_unused_layers yes)
		(keep_end_layers yes)
		(zone_layer_connections "In1.Cu" "In4.Cu" "In6.Cu")
		(teardrops
			(best_length_ratio 0.4)
			(max_length 1)
			(best_width_ratio 0.9)
			(max_width 2)
			(curved_edges yes)
			(filter_ratio 0.9)
			(enabled yes)
			(allow_two_segments yes)
			(prefer_zone_connections yes)
		)
		(net 1)
	)
	(via
		(at 250.95 170.81)
		(size 0.45)
		(drill 0.1)
		(layers "F.Cu" "B.Cu")
		(remove_unused_layers yes)
		(keep_end_layers yes)
		(zone_layer_connections "In1.Cu" "In4.Cu" "In6.Cu")
		(teardrops
			(best_length_ratio 0.4)
			(max_length 1)
			(best_width_ratio 0.9)
			(max_width 2)
			(curved_edges yes)
			(filter_ratio 0.9)
			(enabled yes)
			(allow_two_segments yes)
			(prefer_zone_connections yes)
		)
		(net 1)
	)
	(via
		(at 222.45 87.81)
		(size 0.45)
		(drill 0.1)
		(layers "F.Cu" "B.Cu")
		(remove_unused_layers yes)
		(keep_end_layers yes)
		(free yes)
		(zone_layer_connections "In1.Cu" "In4.Cu" "In6.Cu")
		(teardrops
			(best_length_ratio 0.4)
			(max_length 1)
			(best_width_ratio 0.9)
			(max_width 2)
			(curved_edges yes)
			(filter_ratio 0.9)
			(enabled yes)
			(allow_two_segments yes)
			(prefer_zone_connections yes)
		)
		(net 1)
	)
	(via
		(at 202.95 87.31)
		(size 0.45)
		(drill 0.1)
		(layers "F.Cu" "B.Cu")
		(remove_unused_layers yes)
		(keep_end_layers yes)
		(zone_layer_connections "In1.Cu" "In4.Cu" "In6.Cu")
		(teardrops
			(best_length_ratio 0.4)
			(max_length 1)
			(best_width_ratio 0.9)
			(max_width 2)
			(curved_edges yes)
			(filter_ratio 0.9)
			(enabled yes)
			(allow_two_segments yes)
			(prefer_zone_connections yes)
		)
		(net 1)
	)
	(via
		(at 149.45 141.86)
		(size 0.45)
		(drill 0.1)
		(layers "F.Cu" "B.Cu")
		(remove_unused_layers yes)
		(keep_end_layers yes)
		(zone_layer_connections "In1.Cu" "In4.Cu" "In6.Cu")
		(teardrops
			(best_length_ratio 0.4)
			(max_length 1)
			(best_width_ratio 0.9)
			(max_width 2)
			(curved_edges yes)
			(filter_ratio 0.9)
			(enabled yes)
			(allow_two_segments yes)
			(prefer_zone_connections yes)
		)
		(net 1)
	)
	(via
		(at 201 161.9)
		(size 0.45)
		(drill 0.1)
		(layers "F.Cu" "B.Cu")
		(teardrops
			(best_length_ratio 0.4)
			(max_length 1)
			(best_width_ratio 0.9)
			(max_width 2)
			(curved_edges yes)
			(filter_ratio 0.9)
			(enabled yes)
			(allow_two_segments yes)
			(prefer_zone_connections yes)
		)
		(net 1)
	)
	(via
		(at 311.45 81.81)
		(size 0.45)
		(drill 0.1)
		(layers "F.Cu" "B.Cu")
		(remove_unused_layers yes)
		(keep_end_layers yes)
		(zone_layer_connections "In1.Cu" "In4.Cu" "In6.Cu")
		(teardrops
			(best_length_ratio 0.4)
			(max_length 1)
			(best_width_ratio 0.9)
			(max_width 2)
			(curved_edges yes)
			(filter_ratio 0.9)
			(enabled yes)
			(allow_two_segments yes)
			(prefer_zone_connections yes)
		)
		(net 1)
	)
	(via
		(at 295.45 142.81)
		(size 0.45)
		(drill 0.1)
		(layers "F.Cu" "B.Cu")
		(remove_unused_layers yes)
		(keep_end_layers yes)
		(zone_layer_connections "In1.Cu" "In4.Cu" "In6.Cu")
		(teardrops
			(best_length_ratio 0.4)
			(max_length 1)
			(best_width_ratio 0.9)
			(max_width 2)
			(curved_edges yes)
			(filter_ratio 0.9)
			(enabled yes)
			(allow_two_segments yes)
			(prefer_zone_connections yes)
		)
		(net 1)
	)
	(via
		(at 259.6 136.65)
		(size 0.45)
		(drill 0.1)
		(layers "F.Cu" "B.Cu")
		(remove_unused_layers yes)
		(keep_end_layers yes)
		(zone_layer_connections "In1.Cu" "In4.Cu" "In6.Cu")
		(teardrops
			(best_length_ratio 0.4)
			(max_length 1)
			(best_width_ratio 0.9)
			(max_width 2)
			(curved_edges yes)
			(filter_ratio 0.9)
			(enabled yes)
			(allow_two_segments yes)
			(prefer_zone_connections yes)
		)
		(net 1)
	)
	(via
		(at 132.95 158.81)
		(size 0.45)
		(drill 0.1)
		(layers "F.Cu" "B.Cu")
		(remove_unused_layers yes)
		(keep_end_layers yes)
		(zone_layer_connections "In1.Cu" "In4.Cu" "In6.Cu")
		(teardrops
			(best_length_ratio 0.4)
			(max_length 1)
			(best_width_ratio 0.9)
			(max_width 2)
			(curved_edges yes)
			(filter_ratio 0.9)
			(enabled yes)
			(allow_two_segments yes)
			(prefer_zone_connections yes)
		)
		(net 1)
	)
	(via
		(at 96.95 95.81)
		(size 0.45)
		(drill 0.1)
		(layers "F.Cu" "B.Cu")
		(remove_unused_layers yes)
		(keep_end_layers yes)
		(zone_layer_connections "In1.Cu" "In4.Cu" "In6.Cu")
		(teardrops
			(best_length_ratio 0.4)
			(max_length 1)
			(best_width_ratio 0.9)
			(max_width 2)
			(curved_edges yes)
			(filter_ratio 0.9)
			(enabled yes)
			(allow_two_segments yes)
			(prefer_zone_connections yes)
		)
		(net 1)
	)
	(via
		(at 112.875 103.825)
		(size 0.45)
		(drill 0.1)
		(layers "F.Cu" "B.Cu")
		(remove_unused_layers yes)
		(keep_end_layers yes)
		(zone_layer_connections "In1.Cu" "In4.Cu" "In6.Cu")
		(teardrops
			(best_length_ratio 0.4)
			(max_length 1)
			(best_width_ratio 0.9)
			(max_width 2)
			(curved_edges yes)
			(filter_ratio 0.9)
			(enabled yes)
			(allow_two_segments yes)
			(prefer_zone_connections yes)
		)
		(net 1)
	)
	(via
		(at 131.29 132.86)
		(size 0.45)
		(drill 0.1)
		(layers "F.Cu" "B.Cu")
		(remove_unused_layers yes)
		(keep_end_layers yes)
		(zone_layer_connections "In1.Cu" "In4.Cu" "In6.Cu")
		(teardrops
			(best_length_ratio 0.4)
			(max_length 1)
			(best_width_ratio 0.9)
			(max_width 2)
			(curved_edges yes)
			(filter_ratio 0.9)
			(enabled yes)
			(allow_two_segments yes)
			(prefer_zone_connections yes)
		)
		(net 1)
	)
	(via
		(at 102.275 105.365)
		(size 0.45)
		(drill 0.1)
		(layers "F.Cu" "B.Cu")
		(remove_unused_layers yes)
		(keep_end_layers yes)
		(zone_layer_connections "In1.Cu" "In4.Cu" "In6.Cu")
		(teardrops
			(best_length_ratio 0.4)
			(max_length 1)
			(best_width_ratio 0.9)
			(max_width 2)
			(curved_edges yes)
			(filter_ratio 0.9)
			(enabled yes)
			(allow_two_segments yes)
			(prefer_zone_connections yes)
		)
		(net 1)
	)
	(via
		(at 120.45 95.31)
		(size 0.45)
		(drill 0.1)
		(layers "F.Cu" "B.Cu")
		(remove_unused_layers yes)
		(keep_end_layers yes)
		(zone_layer_connections "In1.Cu" "In4.Cu" "In6.Cu")
		(teardrops
			(best_length_ratio 0.4)
			(max_length 1)
			(best_width_ratio 0.9)
			(max_width 2)
			(curved_edges yes)
			(filter_ratio 0.9)
			(enabled yes)
			(allow_two_segments yes)
			(prefer_zone_connections yes)
		)
		(net 1)
	)
	(via
		(at 190.5 165.75)
		(size 0.45)
		(drill 0.1)
		(layers "F.Cu" "B.Cu")
		(teardrops
			(best_length_ratio 0.4)
			(max_length 1)
			(best_width_ratio 0.9)
			(max_width 2)
			(curved_edges yes)
			(filter_ratio 0.9)
			(enabled yes)
			(allow_two_segments yes)
			(prefer_zone_connections yes)
		)
		(net 1)
	)
	(via
		(at 210.8 127.09)
		(size 0.45)
		(drill 0.1)
		(layers "F.Cu" "B.Cu")
		(remove_unused_layers yes)
		(keep_end_layers yes)
		(zone_layer_connections "In1.Cu" "In4.Cu" "In6.Cu")
		(teardrops
			(best_length_ratio 0.4)
			(max_length 1)
			(best_width_ratio 0.9)
			(max_width 2)
			(curved_edges yes)
			(filter_ratio 0.9)
			(enabled yes)
			(allow_two_segments yes)
			(prefer_zone_connections yes)
		)
		(net 1)
	)
	(via
		(at 196.55 154.075)
		(size 0.45)
		(drill 0.1)
		(layers "F.Cu" "B.Cu")
		(teardrops
			(best_length_ratio 0.4)
			(max_length 1)
			(best_width_ratio 0.9)
			(max_width 2)
			(curved_edges yes)
			(filter_ratio 0.9)
			(enabled yes)
			(allow_two_segments yes)
			(prefer_zone_connections yes)
		)
		(net 1)
	)
	(via
		(at 210.5 167.5)
		(size 0.45)
		(drill 0.1)
		(layers "F.Cu" "B.Cu")
		(teardrops
			(best_length_ratio 0.4)
			(max_length 1)
			(best_width_ratio 0.9)
			(max_width 2)
			(curved_edges yes)
			(filter_ratio 0.9)
			(enabled yes)
			(allow_two_segments yes)
			(prefer_zone_connections yes)
		)
		(net 1)
	)
	(via
		(at 164.95 162.025)
		(size 0.45)
		(drill 0.1)
		(layers "F.Cu" "B.Cu")
		(teardrops
			(best_length_ratio 0.4)
			(max_length 1)
			(best_width_ratio 0.9)
			(max_width 2)
			(curved_edges yes)
			(filter_ratio 0.9)
			(enabled yes)
			(allow_two_segments yes)
			(prefer_zone_connections yes)
		)
		(net 1)
	)
	(via
		(at 115.45 170.81)
		(size 0.45)
		(drill 0.1)
		(layers "F.Cu" "B.Cu")
		(remove_unused_layers yes)
		(keep_end_layers yes)
		(zone_layer_connections "In1.Cu" "In4.Cu" "In6.Cu")
		(teardrops
			(best_length_ratio 0.4)
			(max_length 1)
			(best_width_ratio 0.9)
			(max_width 2)
			(curved_edges yes)
			(filter_ratio 0.9)
			(enabled yes)
			(allow_two_segments yes)
			(prefer_zone_connections yes)
		)
		(net 1)
	)
	(via
		(at 281.95 135.31)
		(size 0.45)
		(drill 0.1)
		(layers "F.Cu" "B.Cu")
		(remove_unused_layers yes)
		(keep_end_layers yes)
		(zone_layer_connections "In1.Cu" "In4.Cu" "In6.Cu")
		(teardrops
			(best_length_ratio 0.4)
			(max_length 1)
			(best_width_ratio 0.9)
			(max_width 2)
			(curved_edges yes)
			(filter_ratio 0.9)
			(enabled yes)
			(allow_two_segments yes)
			(prefer_zone_connections yes)
		)
		(net 1)
	)
	(via
		(at 244.45 118.81)
		(size 0.45)
		(drill 0.1)
		(layers "F.Cu" "B.Cu")
		(remove_unused_layers yes)
		(keep_end_layers yes)
		(zone_layer_connections "In1.Cu" "In4.Cu" "In6.Cu")
		(teardrops
			(best_length_ratio 0.4)
			(max_length 1)
			(best_width_ratio 0.9)
			(max_width 2)
			(curved_edges yes)
			(filter_ratio 0.9)
			(enabled yes)
			(allow_two_segments yes)
			(prefer_zone_connections yes)
		)
		(net 1)
	)
	(via
		(at 132.719999 147.63)
		(size 0.45)
		(drill 0.1)
		(layers "F.Cu" "B.Cu")
		(remove_unused_layers yes)
		(keep_end_layers yes)
		(zone_layer_connections "In1.Cu" "In4.Cu" "In6.Cu")
		(teardrops
			(best_length_ratio 0.4)
			(max_length 1)
			(best_width_ratio 0.9)
			(max_width 2)
			(curved_edges yes)
			(filter_ratio 0.9)
			(enabled yes)
			(allow_two_segments yes)
			(prefer_zone_connections yes)
		)
		(net 1)
	)
	(via
		(at 295.95 133.31)
		(size 0.45)
		(drill 0.1)
		(layers "F.Cu" "B.Cu")
		(remove_unused_layers yes)
		(keep_end_layers yes)
		(zone_layer_connections "In1.Cu" "In4.Cu" "In6.Cu")
		(teardrops
			(best_length_ratio 0.4)
			(max_length 1)
			(best_width_ratio 0.9)
			(max_width 2)
			(curved_edges yes)
			(filter_ratio 0.9)
			(enabled yes)
			(allow_two_segments yes)
			(prefer_zone_connections yes)
		)
		(net 1)
	)
	(via
		(at 265.45 111.31)
		(size 0.45)
		(drill 0.1)
		(layers "F.Cu" "B.Cu")
		(remove_unused_layers yes)
		(keep_end_layers yes)
		(zone_layer_connections "In1.Cu" "In4.Cu" "In6.Cu")
		(teardrops
			(best_length_ratio 0.4)
			(max_length 1)
			(best_width_ratio 0.9)
			(max_width 2)
			(curved_edges yes)
			(filter_ratio 0.9)
			(enabled yes)
			(allow_two_segments yes)
			(prefer_zone_connections yes)
		)
		(net 1)
	)
	(via
		(at 285.45 128.31)
		(size 0.45)
		(drill 0.1)
		(layers "F.Cu" "B.Cu")
		(remove_unused_layers yes)
		(keep_end_layers yes)
		(zone_layer_connections "In1.Cu" "In4.Cu" "In6.Cu")
		(teardrops
			(best_length_ratio 0.4)
			(max_length 1)
			(best_width_ratio 0.9)
			(max_width 2)
			(curved_edges yes)
			(filter_ratio 0.9)
			(enabled yes)
			(allow_two_segments yes)
			(prefer_zone_connections yes)
		)
		(net 1)
	)
	(via
		(at 98.45 94.81)
		(size 0.45)
		(drill 0.1)
		(layers "F.Cu" "B.Cu")
		(remove_unused_layers yes)
		(keep_end_layers yes)
		(zone_layer_connections "In1.Cu" "In4.Cu" "In6.Cu")
		(teardrops
			(best_length_ratio 0.4)
			(max_length 1)
			(best_width_ratio 0.9)
			(max_width 2)
			(curved_edges yes)
			(filter_ratio 0.9)
			(enabled yes)
			(allow_two_segments yes)
			(prefer_zone_connections yes)
		)
		(net 1)
	)
	(via
		(at 239.95 117.31)
		(size 0.45)
		(drill 0.1)
		(layers "F.Cu" "B.Cu")
		(remove_unused_layers yes)
		(keep_end_layers yes)
		(zone_layer_connections "In1.Cu" "In4.Cu" "In6.Cu")
		(teardrops
			(best_length_ratio 0.4)
			(max_length 1)
			(best_width_ratio 0.9)
			(max_width 2)
			(curved_edges yes)
			(filter_ratio 0.9)
			(enabled yes)
			(allow_two_segments yes)
			(prefer_zone_connections yes)
		)
		(net 1)
	)
	(via
		(at 265.45 105.31)
		(size 0.45)
		(drill 0.1)
		(layers "F.Cu" "B.Cu")
		(remove_unused_layers yes)
		(keep_end_layers yes)
		(zone_layer_connections "In1.Cu" "In4.Cu" "In6.Cu")
		(teardrops
			(best_length_ratio 0.4)
			(max_length 1)
			(best_width_ratio 0.9)
			(max_width 2)
			(curved_edges yes)
			(filter_ratio 0.9)
			(enabled yes)
			(allow_two_segments yes)
			(prefer_zone_connections yes)
		)
		(net 1)
	)
	(via
		(at 280.95 126.81)
		(size 0.45)
		(drill 0.1)
		(layers "F.Cu" "B.Cu")
		(remove_unused_layers yes)
		(keep_end_layers yes)
		(zone_layer_connections "In1.Cu" "In4.Cu" "In6.Cu")
		(teardrops
			(best_length_ratio 0.4)
			(max_length 1)
			(best_width_ratio 0.9)
			(max_width 2)
			(curved_edges yes)
			(filter_ratio 0.9)
			(enabled yes)
			(allow_two_segments yes)
			(prefer_zone_connections yes)
		)
		(net 1)
	)
	(via
		(at 132.626346 114.688106)
		(size 0.45)
		(drill 0.1)
		(layers "F.Cu" "B.Cu")
		(remove_unused_layers yes)
		(keep_end_layers yes)
		(zone_layer_connections "In1.Cu" "In4.Cu" "In6.Cu")
		(teardrops
			(best_length_ratio 0.4)
			(max_length 1)
			(best_width_ratio 0.9)
			(max_width 2)
			(curved_edges yes)
			(filter_ratio 0.9)
			(enabled yes)
			(allow_two_segments yes)
			(prefer_zone_connections yes)
		)
		(net 1)
	)
	(via
		(at 95.45 86.81)
		(size 0.45)
		(drill 0.1)
		(layers "F.Cu" "B.Cu")
		(remove_unused_layers yes)
		(keep_end_layers yes)
		(zone_layer_connections "In1.Cu" "In4.Cu" "In6.Cu")
		(teardrops
			(best_length_ratio 0.4)
			(max_length 1)
			(best_width_ratio 0.9)
			(max_width 2)
			(curved_edges yes)
			(filter_ratio 0.9)
			(enabled yes)
			(allow_two_segments yes)
			(prefer_zone_connections yes)
		)
		(net 1)
	)
	(via
		(at 95.45 96.81)
		(size 0.45)
		(drill 0.1)
		(layers "F.Cu" "B.Cu")
		(remove_unused_layers yes)
		(keep_end_layers yes)
		(zone_layer_connections "In1.Cu" "In4.Cu" "In6.Cu")
		(teardrops
			(best_length_ratio 0.4)
			(max_length 1)
			(best_width_ratio 0.9)
			(max_width 2)
			(curved_edges yes)
			(filter_ratio 0.9)
			(enabled yes)
			(allow_two_segments yes)
			(prefer_zone_connections yes)
		)
		(net 1)
	)
	(via
		(at 118.15 146.801)
		(size 0.45)
		(drill 0.1)
		(layers "F.Cu" "B.Cu")
		(remove_unused_layers yes)
		(keep_end_layers yes)
		(zone_layer_connections "In1.Cu" "In4.Cu" "In6.Cu")
		(teardrops
			(best_length_ratio 0.4)
			(max_length 1)
			(best_width_ratio 0.9)
			(max_width 2)
			(curved_edges yes)
			(filter_ratio 0.9)
			(enabled yes)
			(allow_two_segments yes)
			(prefer_zone_connections yes)
		)
		(net 1)
	)
	(via
		(at 172.2 155.2)
		(size 0.45)
		(drill 0.1)
		(layers "F.Cu" "B.Cu")
		(teardrops
			(best_length_ratio 0.4)
			(max_length 1)
			(best_width_ratio 0.9)
			(max_width 2)
			(curved_edges yes)
			(filter_ratio 0.9)
			(enabled yes)
			(allow_two_segments yes)
			(prefer_zone_connections yes)
		)
		(net 1)
	)
	(via
		(at 115.95 156.81)
		(size 0.45)
		(drill 0.1)
		(layers "F.Cu" "B.Cu")
		(remove_unused_layers yes)
		(keep_end_layers yes)
		(zone_layer_connections "In1.Cu" "In4.Cu" "In6.Cu")
		(teardrops
			(best_length_ratio 0.4)
			(max_length 1)
			(best_width_ratio 0.9)
			(max_width 2)
			(curved_edges yes)
			(filter_ratio 0.9)
			(enabled yes)
			(allow_two_segments yes)
			(prefer_zone_connections yes)
		)
		(net 1)
	)
	(via
		(at 266.950001 170.81)
		(size 0.45)
		(drill 0.1)
		(layers "F.Cu" "B.Cu")
		(remove_unused_layers yes)
		(keep_end_layers yes)
		(zone_layer_connections "In1.Cu" "In4.Cu" "In6.Cu")
		(teardrops
			(best_length_ratio 0.4)
			(max_length 1)
			(best_width_ratio 0.9)
			(max_width 2)
			(curved_edges yes)
			(filter_ratio 0.9)
			(enabled yes)
			(allow_two_segments yes)
			(prefer_zone_connections yes)
		)
		(net 1)
	)
	(via
		(at 220.95 89.31)
		(size 0.45)
		(drill 0.1)
		(layers "F.Cu" "B.Cu")
		(remove_unused_layers yes)
		(keep_end_layers yes)
		(zone_layer_connections "In1.Cu" "In4.Cu" "In6.Cu")
		(teardrops
			(best_length_ratio 0.4)
			(max_length 1)
			(best_width_ratio 0.9)
			(max_width 2)
			(curved_edges yes)
			(filter_ratio 0.9)
			(enabled yes)
			(allow_two_segments yes)
			(prefer_zone_connections yes)
		)
		(net 1)
	)
	(via
		(at 128.29 134.86)
		(size 0.45)
		(drill 0.1)
		(layers "F.Cu" "B.Cu")
		(remove_unused_layers yes)
		(keep_end_layers yes)
		(zone_layer_connections "In1.Cu" "In4.Cu" "In6.Cu")
		(teardrops
			(best_length_ratio 0.4)
			(max_length 1)
			(best_width_ratio 0.9)
			(max_width 2)
			(curved_edges yes)
			(filter_ratio 0.9)
			(enabled yes)
			(allow_two_segments yes)
			(prefer_zone_connections yes)
		)
		(net 1)
	)
	(via
		(at 136.29 136.86)
		(size 0.45)
		(drill 0.1)
		(layers "F.Cu" "B.Cu")
		(remove_unused_layers yes)
		(keep_end_layers yes)
		(zone_layer_connections "In1.Cu" "In4.Cu" "In6.Cu")
		(teardrops
			(best_length_ratio 0.4)
			(max_length 1)
			(best_width_ratio 0.9)
			(max_width 2)
			(curved_edges yes)
			(filter_ratio 0.9)
			(enabled yes)
			(allow_two_segments yes)
			(prefer_zone_connections yes)
		)
		(net 1)
	)
	(via
		(at 311.474999 104.4)
		(size 0.45)
		(drill 0.1)
		(layers "F.Cu" "B.Cu")
		(remove_unused_layers yes)
		(keep_end_layers yes)
		(zone_layer_connections "In1.Cu" "In4.Cu" "In6.Cu")
		(teardrops
			(best_length_ratio 0.4)
			(max_length 1)
			(best_width_ratio 0.9)
			(max_width 2)
			(curved_edges yes)
			(filter_ratio 0.9)
			(enabled yes)
			(allow_two_segments yes)
			(prefer_zone_connections yes)
		)
		(net 1)
	)
	(via
		(at 318.464501 95.6365)
		(size 0.45)
		(drill 0.1)
		(layers "F.Cu" "B.Cu")
		(remove_unused_layers yes)
		(keep_end_layers yes)
		(zone_layer_connections "In1.Cu" "In4.Cu" "In6.Cu")
		(teardrops
			(best_length_ratio 0.4)
			(max_length 1)
			(best_width_ratio 0.9)
			(max_width 2)
			(curved_edges yes)
			(filter_ratio 0.9)
			(enabled yes)
			(allow_two_segments yes)
			(prefer_zone_connections yes)
		)
		(net 1)
	)
	(via
		(at 124.841744 142.510263)
		(size 0.45)
		(drill 0.1)
		(layers "F.Cu" "B.Cu")
		(remove_unused_layers yes)
		(keep_end_layers yes)
		(zone_layer_connections "In1.Cu" "In4.Cu" "In6.Cu")
		(teardrops
			(best_length_ratio 0.4)
			(max_length 1)
			(best_width_ratio 0.9)
			(max_width 2)
			(curved_edges yes)
			(filter_ratio 0.9)
			(enabled yes)
			(allow_two_segments yes)
			(prefer_zone_connections yes)
		)
		(net 1)
	)
	(via
		(at 196.05 155.425)
		(size 0.45)
		(drill 0.1)
		(layers "F.Cu" "B.Cu")
		(teardrops
			(best_length_ratio 0.4)
			(max_length 1)
			(best_width_ratio 0.9)
			(max_width 2)
			(curved_edges yes)
			(filter_ratio 0.9)
			(enabled yes)
			(allow_two_segments yes)
			(prefer_zone_connections yes)
		)
		(net 1)
	)
	(via
		(at 155.85 122.6)
		(size 0.45)
		(drill 0.1)
		(layers "F.Cu" "B.Cu")
		(remove_unused_layers yes)
		(keep_end_layers yes)
		(zone_layer_connections "In1.Cu" "In4.Cu" "In6.Cu")
		(teardrops
			(best_length_ratio 0.4)
			(max_length 1)
			(best_width_ratio 0.9)
			(max_width 2)
			(curved_edges yes)
			(filter_ratio 0.9)
			(enabled yes)
			(allow_two_segments yes)
			(prefer_zone_connections yes)
		)
		(net 1)
	)
	(via
		(at 225.5 164.3)
		(size 0.45)
		(drill 0.1)
		(layers "F.Cu" "B.Cu")
		(teardrops
			(best_length_ratio 0.4)
			(max_length 1)
			(best_width_ratio 0.9)
			(max_width 2)
			(curved_edges yes)
			(filter_ratio 0.9)
			(enabled yes)
			(allow_two_segments yes)
			(prefer_zone_connections yes)
		)
		(net 1)
	)
	(via
		(at 188.70861 78.102163)
		(size 0.45)
		(drill 0.1)
		(layers "F.Cu" "B.Cu")
		(remove_unused_layers yes)
		(keep_end_layers yes)
		(zone_layer_connections "In1.Cu" "In4.Cu" "In6.Cu")
		(teardrops
			(best_length_ratio 0.4)
			(max_length 1)
			(best_width_ratio 0.9)
			(max_width 2)
			(curved_edges yes)
			(filter_ratio 0.9)
			(enabled yes)
			(allow_two_segments yes)
			(prefer_zone_connections yes)
		)
		(net 1)
	)
	(via
		(at 286.95 170.81)
		(size 0.45)
		(drill 0.1)
		(layers "F.Cu" "B.Cu")
		(remove_unused_layers yes)
		(keep_end_layers yes)
		(zone_layer_connections "In1.Cu" "In4.Cu" "In6.Cu")
		(teardrops
			(best_length_ratio 0.4)
			(max_length 1)
			(best_width_ratio 0.9)
			(max_width 2)
			(curved_edges yes)
			(filter_ratio 0.9)
			(enabled yes)
			(allow_two_segments yes)
			(prefer_zone_connections yes)
		)
		(net 1)
	)
	(via
		(at 166.8 161.35)
		(size 0.45)
		(drill 0.1)
		(layers "F.Cu" "B.Cu")
		(teardrops
			(best_length_ratio 0.4)
			(max_length 1)
			(best_width_ratio 0.9)
			(max_width 2)
			(curved_edges yes)
			(filter_ratio 0.9)
			(enabled yes)
			(allow_two_segments yes)
			(prefer_zone_connections yes)
		)
		(net 1)
	)
	(via
		(at 193.70861 78.102163)
		(size 0.45)
		(drill 0.1)
		(layers "F.Cu" "B.Cu")
		(remove_unused_layers yes)
		(keep_end_layers yes)
		(zone_layer_connections "In1.Cu" "In4.Cu" "In6.Cu")
		(teardrops
			(best_length_ratio 0.4)
			(max_length 1)
			(best_width_ratio 0.9)
			(max_width 2)
			(curved_edges yes)
			(filter_ratio 0.9)
			(enabled yes)
			(allow_two_segments yes)
			(prefer_zone_connections yes)
		)
		(net 1)
	)
	(via
		(at 149.45 74.31)
		(size 0.45)
		(drill 0.1)
		(layers "F.Cu" "B.Cu")
		(remove_unused_layers yes)
		(keep_end_layers yes)
		(zone_layer_connections "In1.Cu" "In4.Cu" "In6.Cu")
		(teardrops
			(best_length_ratio 0.4)
			(max_length 1)
			(best_width_ratio 0.9)
			(max_width 2)
			(curved_edges yes)
			(filter_ratio 0.9)
			(enabled yes)
			(allow_two_segments yes)
			(prefer_zone_connections yes)
		)
		(net 1)
	)
	(via
		(at 253.4 165.53)
		(size 0.45)
		(drill 0.1)
		(layers "F.Cu" "B.Cu")
		(remove_unused_layers yes)
		(keep_end_layers yes)
		(zone_layer_connections "In1.Cu" "In4.Cu" "In6.Cu")
		(teardrops
			(best_length_ratio 0.4)
			(max_length 1)
			(best_width_ratio 0.9)
			(max_width 2)
			(curved_edges yes)
			(filter_ratio 0.9)
			(enabled yes)
			(allow_two_segments yes)
			(prefer_zone_connections yes)
		)
		(net 1)
	)
	(via
		(at 140.84 137.38)
		(size 0.45)
		(drill 0.1)
		(layers "F.Cu" "B.Cu")
		(remove_unused_layers yes)
		(keep_end_layers yes)
		(zone_layer_connections "In1.Cu" "In4.Cu" "In6.Cu")
		(teardrops
			(best_length_ratio 0.4)
			(max_length 1)
			(best_width_ratio 0.9)
			(max_width 2)
			(curved_edges yes)
			(filter_ratio 0.9)
			(enabled yes)
			(allow_two_segments yes)
			(prefer_zone_connections yes)
		)
		(net 1)
	)
	(via
		(at 130.8 73.01)
		(size 0.45)
		(drill 0.1)
		(layers "F.Cu" "B.Cu")
		(remove_unused_layers yes)
		(keep_end_layers yes)
		(zone_layer_connections "In1.Cu" "In4.Cu" "In6.Cu")
		(teardrops
			(best_length_ratio 0.4)
			(max_length 1)
			(best_width_ratio 0.9)
			(max_width 2)
			(curved_edges yes)
			(filter_ratio 0.9)
			(enabled yes)
			(allow_two_segments yes)
			(prefer_zone_connections yes)
		)
		(net 1)
	)
	(via
		(at 259.45 108.31)
		(size 0.45)
		(drill 0.1)
		(layers "F.Cu" "B.Cu")
		(remove_unused_layers yes)
		(keep_end_layers yes)
		(free yes)
		(zone_layer_connections "In1.Cu" "In4.Cu" "In6.Cu")
		(teardrops
			(best_length_ratio 0.4)
			(max_length 1)
			(best_width_ratio 0.9)
			(max_width 2)
			(curved_edges yes)
			(filter_ratio 0.9)
			(enabled yes)
			(allow_two_segments yes)
			(prefer_zone_connections yes)
		)
		(net 1)
	)
	(via
		(at 123.45 160.56)
		(size 0.45)
		(drill 0.1)
		(layers "F.Cu" "B.Cu")
		(remove_unused_layers yes)
		(keep_end_layers yes)
		(zone_layer_connections "In1.Cu" "In4.Cu" "In6.Cu")
		(teardrops
			(best_length_ratio 0.4)
			(max_length 1)
			(best_width_ratio 0.9)
			(max_width 2)
			(curved_edges yes)
			(filter_ratio 0.9)
			(enabled yes)
			(allow_two_segments yes)
			(prefer_zone_connections yes)
		)
		(net 1)
	)
	(via
		(at 233.4 149.45)
		(size 0.45)
		(drill 0.1)
		(layers "F.Cu" "B.Cu")
		(teardrops
			(best_length_ratio 0.4)
			(max_length 1)
			(best_width_ratio 0.9)
			(max_width 2)
			(curved_edges yes)
			(filter_ratio 0.9)
			(enabled yes)
			(allow_two_segments yes)
			(prefer_zone_connections yes)
		)
		(net 1)
	)
	(via
		(at 247.45 90.81)
		(size 0.45)
		(drill 0.1)
		(layers "F.Cu" "B.Cu")
		(remove_unused_layers yes)
		(keep_end_layers yes)
		(zone_layer_connections "In1.Cu" "In4.Cu" "In6.Cu")
		(teardrops
			(best_length_ratio 0.4)
			(max_length 1)
			(best_width_ratio 0.9)
			(max_width 2)
			(curved_edges yes)
			(filter_ratio 0.9)
			(enabled yes)
			(allow_two_segments yes)
			(prefer_zone_connections yes)
		)
		(net 1)
	)
	(via
		(at 309.15 150.11)
		(size 0.45)
		(drill 0.1)
		(layers "F.Cu" "B.Cu")
		(remove_unused_layers yes)
		(keep_end_layers yes)
		(zone_layer_connections "In1.Cu" "In4.Cu" "In6.Cu")
		(teardrops
			(best_length_ratio 0.4)
			(max_length 1)
			(best_width_ratio 0.9)
			(max_width 2)
			(curved_edges yes)
			(filter_ratio 0.9)
			(enabled yes)
			(allow_two_segments yes)
			(prefer_zone_connections yes)
		)
		(net 1)
	)
	(via
		(at 130.02 169.435)
		(size 0.45)
		(drill 0.1)
		(layers "F.Cu" "B.Cu")
		(remove_unused_layers yes)
		(keep_end_layers yes)
		(zone_layer_connections "In1.Cu" "In4.Cu" "In6.Cu")
		(teardrops
			(best_length_ratio 0.4)
			(max_length 1)
			(best_width_ratio 0.9)
			(max_width 2)
			(curved_edges yes)
			(filter_ratio 0.9)
			(enabled yes)
			(allow_two_segments yes)
			(prefer_zone_connections yes)
		)
		(net 1)
	)
	(via
		(at 118.95 71.81)
		(size 0.45)
		(drill 0.1)
		(layers "F.Cu" "B.Cu")
		(remove_unused_layers yes)
		(keep_end_layers yes)
		(zone_layer_connections "In1.Cu" "In4.Cu" "In6.Cu")
		(teardrops
			(best_length_ratio 0.4)
			(max_length 1)
			(best_width_ratio 0.9)
			(max_width 2)
			(curved_edges yes)
			(filter_ratio 0.9)
			(enabled yes)
			(allow_two_segments yes)
			(prefer_zone_connections yes)
		)
		(net 1)
	)
	(via
		(at 262.45 121.81)
		(size 0.45)
		(drill 0.1)
		(layers "F.Cu" "B.Cu")
		(remove_unused_layers yes)
		(keep_end_layers yes)
		(zone_layer_connections "In1.Cu" "In4.Cu" "In6.Cu")
		(teardrops
			(best_length_ratio 0.4)
			(max_length 1)
			(best_width_ratio 0.9)
			(max_width 2)
			(curved_edges yes)
			(filter_ratio 0.9)
			(enabled yes)
			(allow_two_segments yes)
			(prefer_zone_connections yes)
		)
		(net 1)
	)
	(via
		(at 281.95 138.31)
		(size 0.45)
		(drill 0.1)
		(layers "F.Cu" "B.Cu")
		(remove_unused_layers yes)
		(keep_end_layers yes)
		(zone_layer_connections "In1.Cu" "In4.Cu" "In6.Cu")
		(teardrops
			(best_length_ratio 0.4)
			(max_length 1)
			(best_width_ratio 0.9)
			(max_width 2)
			(curved_edges yes)
			(filter_ratio 0.9)
			(enabled yes)
			(allow_two_segments yes)
			(prefer_zone_connections yes)
		)
		(net 1)
	)
	(via
		(at 219.85 154)
		(size 0.45)
		(drill 0.1)
		(layers "F.Cu" "B.Cu")
		(teardrops
			(best_length_ratio 0.4)
			(max_length 1)
			(best_width_ratio 0.9)
			(max_width 2)
			(curved_edges yes)
			(filter_ratio 0.9)
			(enabled yes)
			(allow_two_segments yes)
			(prefer_zone_connections yes)
		)
		(net 1)
	)
	(via
		(at 315.95 83.31)
		(size 0.45)
		(drill 0.1)
		(layers "F.Cu" "B.Cu")
		(remove_unused_layers yes)
		(keep_end_layers yes)
		(zone_layer_connections "In1.Cu" "In4.Cu" "In6.Cu")
		(teardrops
			(best_length_ratio 0.4)
			(max_length 1)
			(best_width_ratio 0.9)
			(max_width 2)
			(curved_edges yes)
			(filter_ratio 0.9)
			(enabled yes)
			(allow_two_segments yes)
			(prefer_zone_connections yes)
		)
		(net 1)
	)
	(via
		(at 236.95 117.31)
		(size 0.45)
		(drill 0.1)
		(layers "F.Cu" "B.Cu")
		(remove_unused_layers yes)
		(keep_end_layers yes)
		(free yes)
		(zone_layer_connections "In1.Cu" "In4.Cu" "In6.Cu")
		(teardrops
			(best_length_ratio 0.4)
			(max_length 1)
			(best_width_ratio 0.9)
			(max_width 2)
			(curved_edges yes)
			(filter_ratio 0.9)
			(enabled yes)
			(allow_two_segments yes)
			(prefer_zone_connections yes)
		)
		(net 1)
	)
	(via
		(at 172.7 165.8)
		(size 0.45)
		(drill 0.1)
		(layers "F.Cu" "B.Cu")
		(teardrops
			(best_length_ratio 0.4)
			(max_length 1)
			(best_width_ratio 0.9)
			(max_width 2)
			(curved_edges yes)
			(filter_ratio 0.9)
			(enabled yes)
			(allow_two_segments yes)
			(prefer_zone_connections yes)
		)
		(net 1)
	)
	(via
		(at 244.45 115.81)
		(size 0.45)
		(drill 0.1)
		(layers "F.Cu" "B.Cu")
		(remove_unused_layers yes)
		(keep_end_layers yes)
		(zone_layer_connections "In1.Cu" "In4.Cu" "In6.Cu")
		(teardrops
			(best_length_ratio 0.4)
			(max_length 1)
			(best_width_ratio 0.9)
			(max_width 2)
			(curved_edges yes)
			(filter_ratio 0.9)
			(enabled yes)
			(allow_two_segments yes)
			(prefer_zone_connections yes)
		)
		(net 1)
	)
	(via
		(at 134.95 160.31)
		(size 0.45)
		(drill 0.1)
		(layers "F.Cu" "B.Cu")
		(remove_unused_layers yes)
		(keep_end_layers yes)
		(zone_layer_connections "In1.Cu" "In4.Cu" "In6.Cu")
		(teardrops
			(best_length_ratio 0.4)
			(max_length 1)
			(best_width_ratio 0.9)
			(max_width 2)
			(curved_edges yes)
			(filter_ratio 0.9)
			(enabled yes)
			(allow_two_segments yes)
			(prefer_zone_connections yes)
		)
		(net 1)
	)
	(via
		(at 316.35 165.71)
		(size 0.45)
		(drill 0.1)
		(layers "F.Cu" "B.Cu")
		(remove_unused_layers yes)
		(keep_end_layers yes)
		(zone_layer_connections "In1.Cu" "In4.Cu" "In6.Cu")
		(teardrops
			(best_length_ratio 0.4)
			(max_length 1)
			(best_width_ratio 0.9)
			(max_width 2)
			(curved_edges yes)
			(filter_ratio 0.9)
			(enabled yes)
			(allow_two_segments yes)
			(prefer_zone_connections yes)
		)
		(net 1)
	)
	(via
		(at 318.95 89.31)
		(size 0.45)
		(drill 0.1)
		(layers "F.Cu" "B.Cu")
		(remove_unused_layers yes)
		(keep_end_layers yes)
		(zone_layer_connections "In1.Cu" "In4.Cu" "In6.Cu")
		(teardrops
			(best_length_ratio 0.4)
			(max_length 1)
			(best_width_ratio 0.9)
			(max_width 2)
			(curved_edges yes)
			(filter_ratio 0.9)
			(enabled yes)
			(allow_two_segments yes)
			(prefer_zone_connections yes)
		)
		(net 1)
	)
	(via
		(at 95.45 161.31)
		(size 0.45)
		(drill 0.1)
		(layers "F.Cu" "B.Cu")
		(remove_unused_layers yes)
		(keep_end_layers yes)
		(zone_layer_connections "In1.Cu" "In4.Cu" "In6.Cu")
		(teardrops
			(best_length_ratio 0.4)
			(max_length 1)
			(best_width_ratio 0.9)
			(max_width 2)
			(curved_edges yes)
			(filter_ratio 0.9)
			(enabled yes)
			(allow_two_segments yes)
			(prefer_zone_connections yes)
		)
		(net 1)
	)
	(via
		(at 295.95 134.81)
		(size 0.45)
		(drill 0.1)
		(layers "F.Cu" "B.Cu")
		(remove_unused_layers yes)
		(keep_end_layers yes)
		(zone_layer_connections "In1.Cu" "In4.Cu" "In6.Cu")
		(teardrops
			(best_length_ratio 0.4)
			(max_length 1)
			(best_width_ratio 0.9)
			(max_width 2)
			(curved_edges yes)
			(filter_ratio 0.9)
			(enabled yes)
			(allow_two_segments yes)
			(prefer_zone_connections yes)
		)
		(net 1)
	)
	(via
		(at 271.3 158.9)
		(size 0.45)
		(drill 0.1)
		(layers "F.Cu" "B.Cu")
		(remove_unused_layers yes)
		(keep_end_layers yes)
		(zone_layer_connections "In1.Cu" "In4.Cu" "In6.Cu")
		(teardrops
			(best_length_ratio 0.4)
			(max_length 1)
			(best_width_ratio 0.9)
			(max_width 2)
			(curved_edges yes)
			(filter_ratio 0.9)
			(enabled yes)
			(allow_two_segments yes)
			(prefer_zone_connections yes)
		)
		(net 1)
	)
	(via
		(at 138.722 147.62)
		(size 0.45)
		(drill 0.1)
		(layers "F.Cu" "B.Cu")
		(remove_unused_layers yes)
		(keep_end_layers yes)
		(zone_layer_connections "In1.Cu" "In4.Cu" "In6.Cu")
		(teardrops
			(best_length_ratio 0.4)
			(max_length 1)
			(best_width_ratio 0.9)
			(max_width 2)
			(curved_edges yes)
			(filter_ratio 0.9)
			(enabled yes)
			(allow_two_segments yes)
			(prefer_zone_connections yes)
		)
		(net 1)
	)
	(via
		(at 223.95 86.31)
		(size 0.45)
		(drill 0.1)
		(layers "F.Cu" "B.Cu")
		(remove_unused_layers yes)
		(keep_end_layers yes)
		(zone_layer_connections "In1.Cu" "In4.Cu" "In6.Cu")
		(teardrops
			(best_length_ratio 0.4)
			(max_length 1)
			(best_width_ratio 0.9)
			(max_width 2)
			(curved_edges yes)
			(filter_ratio 0.9)
			(enabled yes)
			(allow_two_segments yes)
			(prefer_zone_connections yes)
		)
		(net 1)
	)
	(via
		(at 99.77 95.51)
		(size 0.45)
		(drill 0.1)
		(layers "F.Cu" "B.Cu")
		(remove_unused_layers yes)
		(keep_end_layers yes)
		(zone_layer_connections "In1.Cu" "In4.Cu" "In6.Cu")
		(teardrops
			(best_length_ratio 0.4)
			(max_length 1)
			(best_width_ratio 0.9)
			(max_width 2)
			(curved_edges yes)
			(filter_ratio 0.9)
			(enabled yes)
			(allow_two_segments yes)
			(prefer_zone_connections yes)
		)
		(net 1)
	)
	(via
		(at 121.95 156.81)
		(size 0.45)
		(drill 0.1)
		(layers "F.Cu" "B.Cu")
		(remove_unused_layers yes)
		(keep_end_layers yes)
		(zone_layer_connections "In1.Cu" "In4.Cu" "In6.Cu")
		(teardrops
			(best_length_ratio 0.4)
			(max_length 1)
			(best_width_ratio 0.9)
			(max_width 2)
			(curved_edges yes)
			(filter_ratio 0.9)
			(enabled yes)
			(allow_two_segments yes)
			(prefer_zone_connections yes)
		)
		(net 1)
	)
	(via
		(at 142.377 149.738)
		(size 0.45)
		(drill 0.1)
		(layers "F.Cu" "B.Cu")
		(remove_unused_layers yes)
		(keep_end_layers yes)
		(zone_layer_connections "In1.Cu" "In4.Cu" "In6.Cu")
		(teardrops
			(best_length_ratio 0.4)
			(max_length 1)
			(best_width_ratio 0.9)
			(max_width 2)
			(curved_edges yes)
			(filter_ratio 0.9)
			(enabled yes)
			(allow_two_segments yes)
			(prefer_zone_connections yes)
		)
		(net 1)
	)
	(via
		(at 234.4 164.4)
		(size 0.45)
		(drill 0.1)
		(layers "F.Cu" "B.Cu")
		(teardrops
			(best_length_ratio 0.4)
			(max_length 1)
			(best_width_ratio 0.9)
			(max_width 2)
			(curved_edges yes)
			(filter_ratio 0.9)
			(enabled yes)
			(allow_two_segments yes)
			(prefer_zone_connections yes)
		)
		(net 1)
	)
	(via
		(at 279.45 119.81)
		(size 0.45)
		(drill 0.1)
		(layers "F.Cu" "B.Cu")
		(remove_unused_layers yes)
		(keep_end_layers yes)
		(zone_layer_connections "In1.Cu" "In4.Cu" "In6.Cu")
		(teardrops
			(best_length_ratio 0.4)
			(max_length 1)
			(best_width_ratio 0.9)
			(max_width 2)
			(curved_edges yes)
			(filter_ratio 0.9)
			(enabled yes)
			(allow_two_segments yes)
			(prefer_zone_connections yes)
		)
		(net 1)
	)
	(via
		(at 262.95 166.41)
		(size 0.45)
		(drill 0.1)
		(layers "F.Cu" "B.Cu")
		(remove_unused_layers yes)
		(keep_end_layers yes)
		(zone_layer_connections "In1.Cu" "In4.Cu" "In6.Cu")
		(teardrops
			(best_length_ratio 0.4)
			(max_length 1)
			(best_width_ratio 0.9)
			(max_width 2)
			(curved_edges yes)
			(filter_ratio 0.9)
			(enabled yes)
			(allow_two_segments yes)
			(prefer_zone_connections yes)
		)
		(net 1)
	)
	(via
		(at 165.005 158.75)
		(size 0.45)
		(drill 0.1)
		(layers "F.Cu" "B.Cu")
		(teardrops
			(best_length_ratio 0.4)
			(max_length 1)
			(best_width_ratio 0.9)
			(max_width 2)
			(curved_edges yes)
			(filter_ratio 0.9)
			(enabled yes)
			(allow_two_segments yes)
			(prefer_zone_connections yes)
		)
		(net 1)
	)
	(via
		(at 177.18 97.86)
		(size 0.45)
		(drill 0.1)
		(layers "F.Cu" "B.Cu")
		(remove_unused_layers yes)
		(keep_end_layers yes)
		(zone_layer_connections "In1.Cu" "In4.Cu" "In6.Cu")
		(teardrops
			(best_length_ratio 0.4)
			(max_length 1)
			(best_width_ratio 0.9)
			(max_width 2)
			(curved_edges yes)
			(filter_ratio 0.9)
			(enabled yes)
			(allow_two_segments yes)
			(prefer_zone_connections yes)
		)
		(net 1)
	)
	(via
		(at 176 170)
		(size 0.45)
		(drill 0.1)
		(layers "F.Cu" "B.Cu")
		(teardrops
			(best_length_ratio 0.4)
			(max_length 1)
			(best_width_ratio 0.9)
			(max_width 2)
			(curved_edges yes)
			(filter_ratio 0.9)
			(enabled yes)
			(allow_two_segments yes)
			(prefer_zone_connections yes)
		)
		(net 1)
	)
	(via
		(at 102.45 129.81)
		(size 0.45)
		(drill 0.1)
		(layers "F.Cu" "B.Cu")
		(remove_unused_layers yes)
		(keep_end_layers yes)
		(zone_layer_connections "In1.Cu" "In4.Cu" "In6.Cu")
		(teardrops
			(best_length_ratio 0.4)
			(max_length 1)
			(best_width_ratio 0.9)
			(max_width 2)
			(curved_edges yes)
			(filter_ratio 0.9)
			(enabled yes)
			(allow_two_segments yes)
			(prefer_zone_connections yes)
		)
		(net 1)
	)
	(via
		(at 123.45 165.81)
		(size 0.45)
		(drill 0.1)
		(layers "F.Cu" "B.Cu")
		(remove_unused_layers yes)
		(keep_end_layers yes)
		(zone_layer_connections "In1.Cu" "In4.Cu" "In6.Cu")
		(teardrops
			(best_length_ratio 0.4)
			(max_length 1)
			(best_width_ratio 0.9)
			(max_width 2)
			(curved_edges yes)
			(filter_ratio 0.9)
			(enabled yes)
			(allow_two_segments yes)
			(prefer_zone_connections yes)
		)
		(net 1)
	)
	(via
		(at 182.72 90.695)
		(size 0.45)
		(drill 0.1)
		(layers "F.Cu" "B.Cu")
		(remove_unused_layers yes)
		(keep_end_layers yes)
		(zone_layer_connections "In1.Cu" "In4.Cu" "In6.Cu")
		(teardrops
			(best_length_ratio 0.4)
			(max_length 1)
			(best_width_ratio 0.9)
			(max_width 2)
			(curved_edges yes)
			(filter_ratio 0.9)
			(enabled yes)
			(allow_two_segments yes)
			(prefer_zone_connections yes)
		)
		(net 1)
	)
	(via
		(at 281.95 147.31)
		(size 0.45)
		(drill 0.1)
		(layers "F.Cu" "B.Cu")
		(remove_unused_layers yes)
		(keep_end_layers yes)
		(zone_layer_connections "In1.Cu" "In4.Cu" "In6.Cu")
		(teardrops
			(best_length_ratio 0.4)
			(max_length 1)
			(best_width_ratio 0.9)
			(max_width 2)
			(curved_edges yes)
			(filter_ratio 0.9)
			(enabled yes)
			(allow_two_segments yes)
			(prefer_zone_connections yes)
		)
		(net 1)
	)
	(via
		(at 120.95 159.31)
		(size 0.45)
		(drill 0.1)
		(layers "F.Cu" "B.Cu")
		(remove_unused_layers yes)
		(keep_end_layers yes)
		(zone_layer_connections "In1.Cu" "In4.Cu" "In6.Cu")
		(teardrops
			(best_length_ratio 0.4)
			(max_length 1)
			(best_width_ratio 0.9)
			(max_width 2)
			(curved_edges yes)
			(filter_ratio 0.9)
			(enabled yes)
			(allow_two_segments yes)
			(prefer_zone_connections yes)
		)
		(net 1)
	)
	(via
		(at 277.95 121.31)
		(size 0.45)
		(drill 0.1)
		(layers "F.Cu" "B.Cu")
		(remove_unused_layers yes)
		(keep_end_layers yes)
		(zone_layer_connections "In1.Cu" "In4.Cu" "In6.Cu")
		(teardrops
			(best_length_ratio 0.4)
			(max_length 1)
			(best_width_ratio 0.9)
			(max_width 2)
			(curved_edges yes)
			(filter_ratio 0.9)
			(enabled yes)
			(allow_two_segments yes)
			(prefer_zone_connections yes)
		)
		(net 1)
	)
	(via
		(at 172.2 167.2)
		(size 0.45)
		(drill 0.1)
		(layers "F.Cu" "B.Cu")
		(teardrops
			(best_length_ratio 0.4)
			(max_length 1)
			(best_width_ratio 0.9)
			(max_width 2)
			(curved_edges yes)
			(filter_ratio 0.9)
			(enabled yes)
			(allow_two_segments yes)
			(prefer_zone_connections yes)
		)
		(net 1)
	)
	(via
		(at 129.3 71.51)
		(size 0.45)
		(drill 0.1)
		(layers "F.Cu" "B.Cu")
		(remove_unused_layers yes)
		(keep_end_layers yes)
		(zone_layer_connections "In1.Cu" "In4.Cu" "In6.Cu")
		(teardrops
			(best_length_ratio 0.4)
			(max_length 1)
			(best_width_ratio 0.9)
			(max_width 2)
			(curved_edges yes)
			(filter_ratio 0.9)
			(enabled yes)
			(allow_two_segments yes)
			(prefer_zone_connections yes)
		)
		(net 1)
	)
	(via
		(at 318.4895 134.71)
		(size 0.45)
		(drill 0.1)
		(layers "F.Cu" "B.Cu")
		(remove_unused_layers yes)
		(keep_end_layers yes)
		(zone_layer_connections "In1.Cu" "In4.Cu" "In6.Cu")
		(teardrops
			(best_length_ratio 0.4)
			(max_length 1)
			(best_width_ratio 0.9)
			(max_width 2)
			(curved_edges yes)
			(filter_ratio 0.9)
			(enabled yes)
			(allow_two_segments yes)
			(prefer_zone_connections yes)
		)
		(net 1)
	)
	(via
		(at 143.95 71.31)
		(size 0.45)
		(drill 0.1)
		(layers "F.Cu" "B.Cu")
		(remove_unused_layers yes)
		(keep_end_layers yes)
		(zone_layer_connections "In1.Cu" "In4.Cu" "In6.Cu")
		(teardrops
			(best_length_ratio 0.4)
			(max_length 1)
			(best_width_ratio 0.9)
			(max_width 2)
			(curved_edges yes)
			(filter_ratio 0.9)
			(enabled yes)
			(allow_two_segments yes)
			(prefer_zone_connections yes)
		)
		(net 1)
	)
	(via
		(at 197.45 103.31)
		(size 0.45)
		(drill 0.1)
		(layers "F.Cu" "B.Cu")
		(remove_unused_layers yes)
		(keep_end_layers yes)
		(zone_layer_connections "In1.Cu" "In4.Cu" "In6.Cu")
		(teardrops
			(best_length_ratio 0.4)
			(max_length 1)
			(best_width_ratio 0.9)
			(max_width 2)
			(curved_edges yes)
			(filter_ratio 0.9)
			(enabled yes)
			(allow_two_segments yes)
			(prefer_zone_connections yes)
		)
		(net 1)
	)
	(via
		(at 248.950001 170.81)
		(size 0.45)
		(drill 0.1)
		(layers "F.Cu" "B.Cu")
		(remove_unused_layers yes)
		(keep_end_layers yes)
		(zone_layer_connections "In1.Cu" "In4.Cu" "In6.Cu")
		(teardrops
			(best_length_ratio 0.4)
			(max_length 1)
			(best_width_ratio 0.9)
			(max_width 2)
			(curved_edges yes)
			(filter_ratio 0.9)
			(enabled yes)
			(allow_two_segments yes)
			(prefer_zone_connections yes)
		)
		(net 1)
	)
	(via
		(at 260.95 120.31)
		(size 0.45)
		(drill 0.1)
		(layers "F.Cu" "B.Cu")
		(remove_unused_layers yes)
		(keep_end_layers yes)
		(zone_layer_connections "In1.Cu" "In4.Cu" "In6.Cu")
		(teardrops
			(best_length_ratio 0.4)
			(max_length 1)
			(best_width_ratio 0.9)
			(max_width 2)
			(curved_edges yes)
			(filter_ratio 0.9)
			(enabled yes)
			(allow_two_segments yes)
			(prefer_zone_connections yes)
		)
		(net 1)
	)
	(via
		(at 280.95 112.31)
		(size 0.45)
		(drill 0.1)
		(layers "F.Cu" "B.Cu")
		(remove_unused_layers yes)
		(keep_end_layers yes)
		(zone_layer_connections "In1.Cu" "In4.Cu" "In6.Cu")
		(teardrops
			(best_length_ratio 0.4)
			(max_length 1)
			(best_width_ratio 0.9)
			(max_width 2)
			(curved_edges yes)
			(filter_ratio 0.9)
			(enabled yes)
			(allow_two_segments yes)
			(prefer_zone_connections yes)
		)
		(net 1)
	)
	(via
		(at 195.95 152.25)
		(size 0.45)
		(drill 0.1)
		(layers "F.Cu" "B.Cu")
		(teardrops
			(best_length_ratio 0.4)
			(max_length 1)
			(best_width_ratio 0.9)
			(max_width 2)
			(curved_edges yes)
			(filter_ratio 0.9)
			(enabled yes)
			(allow_two_segments yes)
			(prefer_zone_connections yes)
		)
		(net 1)
	)
	(via
		(at 171.6 160.8)
		(size 0.45)
		(drill 0.1)
		(layers "F.Cu" "B.Cu")
		(teardrops
			(best_length_ratio 0.4)
			(max_length 1)
			(best_width_ratio 0.9)
			(max_width 2)
			(curved_edges yes)
			(filter_ratio 0.9)
			(enabled yes)
			(allow_two_segments yes)
			(prefer_zone_connections yes)
		)
		(net 1)
	)
	(via
		(at 135.29 133.86)
		(size 0.45)
		(drill 0.1)
		(layers "F.Cu" "B.Cu")
		(remove_unused_layers yes)
		(keep_end_layers yes)
		(zone_layer_connections "In1.Cu" "In4.Cu" "In6.Cu")
		(teardrops
			(best_length_ratio 0.4)
			(max_length 1)
			(best_width_ratio 0.9)
			(max_width 2)
			(curved_edges yes)
			(filter_ratio 0.9)
			(enabled yes)
			(allow_two_segments yes)
			(prefer_zone_connections yes)
		)
		(net 1)
	)
	(via
		(at 206.643792 131.888027)
		(size 0.45)
		(drill 0.1)
		(layers "F.Cu" "B.Cu")
		(remove_unused_layers yes)
		(keep_end_layers yes)
		(zone_layer_connections "In1.Cu" "In4.Cu" "In6.Cu")
		(teardrops
			(best_length_ratio 0.4)
			(max_length 1)
			(best_width_ratio 0.9)
			(max_width 2)
			(curved_edges yes)
			(filter_ratio 0.9)
			(enabled yes)
			(allow_two_segments yes)
			(prefer_zone_connections yes)
		)
		(net 1)
	)
	(via
		(at 201.95 101.81)
		(size 0.45)
		(drill 0.1)
		(layers "F.Cu" "B.Cu")
		(remove_unused_layers yes)
		(keep_end_layers yes)
		(zone_layer_connections "In1.Cu" "In4.Cu" "In6.Cu")
		(teardrops
			(best_length_ratio 0.4)
			(max_length 1)
			(best_width_ratio 0.9)
			(max_width 2)
			(curved_edges yes)
			(filter_ratio 0.9)
			(enabled yes)
			(allow_two_segments yes)
			(prefer_zone_connections yes)
		)
		(net 1)
	)
	(via
		(at 110.975 157.725)
		(size 0.45)
		(drill 0.1)
		(layers "F.Cu" "B.Cu")
		(remove_unused_layers yes)
		(keep_end_layers yes)
		(free yes)
		(zone_layer_connections "In1.Cu" "In4.Cu" "In6.Cu")
		(teardrops
			(best_length_ratio 0.4)
			(max_length 1)
			(best_width_ratio 0.9)
			(max_width 2)
			(curved_edges yes)
			(filter_ratio 0.9)
			(enabled yes)
			(allow_two_segments yes)
			(prefer_zone_connections yes)
		)
		(net 1)
	)
	(via
		(at 306.95 86.31)
		(size 0.45)
		(drill 0.1)
		(layers "F.Cu" "B.Cu")
		(remove_unused_layers yes)
		(keep_end_layers yes)
		(zone_layer_connections "In1.Cu" "In4.Cu" "In6.Cu")
		(teardrops
			(best_length_ratio 0.4)
			(max_length 1)
			(best_width_ratio 0.9)
			(max_width 2)
			(curved_edges yes)
			(filter_ratio 0.9)
			(enabled yes)
			(allow_two_segments yes)
			(prefer_zone_connections yes)
		)
		(net 1)
	)
	(via
		(at 195.774695 130.772614)
		(size 0.45)
		(drill 0.1)
		(layers "F.Cu" "B.Cu")
		(remove_unused_layers yes)
		(keep_end_layers yes)
		(zone_layer_connections "In1.Cu" "In4.Cu" "In6.Cu")
		(teardrops
			(best_length_ratio 0.4)
			(max_length 1)
			(best_width_ratio 0.9)
			(max_width 2)
			(curved_edges yes)
			(filter_ratio 0.9)
			(enabled yes)
			(allow_two_segments yes)
			(prefer_zone_connections yes)
		)
		(net 1)
	)
	(via
		(at 179.5 166.9)
		(size 0.45)
		(drill 0.1)
		(layers "F.Cu" "B.Cu")
		(teardrops
			(best_length_ratio 0.4)
			(max_length 1)
			(best_width_ratio 0.9)
			(max_width 2)
			(curved_edges yes)
			(filter_ratio 0.9)
			(enabled yes)
			(allow_two_segments yes)
			(prefer_zone_connections yes)
		)
		(net 1)
	)
	(via
		(at 174.45 68.81)
		(size 0.45)
		(drill 0.1)
		(layers "F.Cu" "B.Cu")
		(remove_unused_layers yes)
		(keep_end_layers yes)
		(zone_layer_connections "In1.Cu" "In4.Cu" "In6.Cu")
		(teardrops
			(best_length_ratio 0.4)
			(max_length 1)
			(best_width_ratio 0.9)
			(max_width 2)
			(curved_edges yes)
			(filter_ratio 0.9)
			(enabled yes)
			(allow_two_segments yes)
			(prefer_zone_connections yes)
		)
		(net 1)
	)
	(via
		(at 177.18 96.36)
		(size 0.45)
		(drill 0.1)
		(layers "F.Cu" "B.Cu")
		(remove_unused_layers yes)
		(keep_end_layers yes)
		(zone_layer_connections "In1.Cu" "In4.Cu" "In6.Cu")
		(teardrops
			(best_length_ratio 0.4)
			(max_length 1)
			(best_width_ratio 0.9)
			(max_width 2)
			(curved_edges yes)
			(filter_ratio 0.9)
			(enabled yes)
			(allow_two_segments yes)
			(prefer_zone_connections yes)
		)
		(net 1)
	)
	(via
		(at 165.925 163.55)
		(size 0.45)
		(drill 0.1)
		(layers "F.Cu" "B.Cu")
		(teardrops
			(best_length_ratio 0.4)
			(max_length 1)
			(best_width_ratio 0.9)
			(max_width 2)
			(curved_edges yes)
			(filter_ratio 0.9)
			(enabled yes)
			(allow_two_segments yes)
			(prefer_zone_connections yes)
		)
		(net 1)
	)
	(via
		(at 120.45 169.81)
		(size 0.45)
		(drill 0.1)
		(layers "F.Cu" "B.Cu")
		(remove_unused_layers yes)
		(keep_end_layers yes)
		(zone_layer_connections "In1.Cu" "In4.Cu" "In6.Cu")
		(teardrops
			(best_length_ratio 0.4)
			(max_length 1)
			(best_width_ratio 0.9)
			(max_width 2)
			(curved_edges yes)
			(filter_ratio 0.9)
			(enabled yes)
			(allow_two_segments yes)
			(prefer_zone_connections yes)
		)
		(net 1)
	)
	(via
		(at 132.45 164.81)
		(size 0.45)
		(drill 0.1)
		(layers "F.Cu" "B.Cu")
		(remove_unused_layers yes)
		(keep_end_layers yes)
		(zone_layer_connections "In1.Cu" "In4.Cu" "In6.Cu")
		(teardrops
			(best_length_ratio 0.4)
			(max_length 1)
			(best_width_ratio 0.9)
			(max_width 2)
			(curved_edges yes)
			(filter_ratio 0.9)
			(enabled yes)
			(allow_two_segments yes)
			(prefer_zone_connections yes)
		)
		(net 1)
	)
	(via
		(at 116.65 147.901)
		(size 0.45)
		(drill 0.1)
		(layers "F.Cu" "B.Cu")
		(remove_unused_layers yes)
		(keep_end_layers yes)
		(zone_layer_connections "In1.Cu" "In4.Cu" "In6.Cu")
		(teardrops
			(best_length_ratio 0.4)
			(max_length 1)
			(best_width_ratio 0.9)
			(max_width 2)
			(curved_edges yes)
			(filter_ratio 0.9)
			(enabled yes)
			(allow_two_segments yes)
			(prefer_zone_connections yes)
		)
		(net 1)
	)
	(via
		(at 285.45 110.81)
		(size 0.45)
		(drill 0.1)
		(layers "F.Cu" "B.Cu")
		(remove_unused_layers yes)
		(keep_end_layers yes)
		(zone_layer_connections "In1.Cu" "In4.Cu" "In6.Cu")
		(teardrops
			(best_length_ratio 0.4)
			(max_length 1)
			(best_width_ratio 0.9)
			(max_width 2)
			(curved_edges yes)
			(filter_ratio 0.9)
			(enabled yes)
			(allow_two_segments yes)
			(prefer_zone_connections yes)
		)
		(net 1)
	)
	(via
		(at 217.95 89.31)
		(size 0.45)
		(drill 0.1)
		(layers "F.Cu" "B.Cu")
		(remove_unused_layers yes)
		(keep_end_layers yes)
		(zone_layer_connections "In1.Cu" "In4.Cu" "In6.Cu")
		(teardrops
			(best_length_ratio 0.4)
			(max_length 1)
			(best_width_ratio 0.9)
			(max_width 2)
			(curved_edges yes)
			(filter_ratio 0.9)
			(enabled yes)
			(allow_two_segments yes)
			(prefer_zone_connections yes)
		)
		(net 1)
	)
	(via
		(at 169.45 82.31)
		(size 0.45)
		(drill 0.1)
		(layers "F.Cu" "B.Cu")
		(remove_unused_layers yes)
		(keep_end_layers yes)
		(free yes)
		(zone_layer_connections "In1.Cu" "In4.Cu" "In6.Cu")
		(teardrops
			(best_length_ratio 0.4)
			(max_length 1)
			(best_width_ratio 0.9)
			(max_width 2)
			(curved_edges yes)
			(filter_ratio 0.9)
			(enabled yes)
			(allow_two_segments yes)
			(prefer_zone_connections yes)
		)
		(net 1)
	)
	(via
		(at 208.45 167.5)
		(size 0.45)
		(drill 0.1)
		(layers "F.Cu" "B.Cu")
		(teardrops
			(best_length_ratio 0.4)
			(max_length 1)
			(best_width_ratio 0.9)
			(max_width 2)
			(curved_edges yes)
			(filter_ratio 0.9)
			(enabled yes)
			(allow_two_segments yes)
			(prefer_zone_connections yes)
		)
		(net 1)
	)
	(via
		(at 136.29 143.81)
		(size 0.45)
		(drill 0.1)
		(layers "F.Cu" "B.Cu")
		(remove_unused_layers yes)
		(keep_end_layers yes)
		(zone_layer_connections "In1.Cu" "In4.Cu" "In6.Cu")
		(teardrops
			(best_length_ratio 0.4)
			(max_length 1)
			(best_width_ratio 0.9)
			(max_width 2)
			(curved_edges yes)
			(filter_ratio 0.9)
			(enabled yes)
			(allow_two_segments yes)
			(prefer_zone_connections yes)
		)
		(net 1)
	)
	(via
		(at 318.95 83.31)
		(size 0.45)
		(drill 0.1)
		(layers "F.Cu" "B.Cu")
		(remove_unused_layers yes)
		(keep_end_layers yes)
		(zone_layer_connections "In1.Cu" "In4.Cu" "In6.Cu")
		(teardrops
			(best_length_ratio 0.4)
			(max_length 1)
			(best_width_ratio 0.9)
			(max_width 2)
			(curved_edges yes)
			(filter_ratio 0.9)
			(enabled yes)
			(allow_two_segments yes)
			(prefer_zone_connections yes)
		)
		(net 1)
	)
	(via
		(at 127.29 146.81)
		(size 0.45)
		(drill 0.1)
		(layers "F.Cu" "B.Cu")
		(remove_unused_layers yes)
		(keep_end_layers yes)
		(zone_layer_connections "In1.Cu" "In4.Cu" "In6.Cu")
		(teardrops
			(best_length_ratio 0.4)
			(max_length 1)
			(best_width_ratio 0.9)
			(max_width 2)
			(curved_edges yes)
			(filter_ratio 0.9)
			(enabled yes)
			(allow_two_segments yes)
			(prefer_zone_connections yes)
		)
		(net 1)
	)
	(via
		(at 134.45 85.81)
		(size 0.45)
		(drill 0.1)
		(layers "F.Cu" "B.Cu")
		(remove_unused_layers yes)
		(keep_end_layers yes)
		(zone_layer_connections "In1.Cu" "In4.Cu" "In6.Cu")
		(teardrops
			(best_length_ratio 0.4)
			(max_length 1)
			(best_width_ratio 0.9)
			(max_width 2)
			(curved_edges yes)
			(filter_ratio 0.9)
			(enabled yes)
			(allow_two_segments yes)
			(prefer_zone_connections yes)
		)
		(net 1)
	)
	(via
		(at 311.464499 101.6365)
		(size 0.45)
		(drill 0.1)
		(layers "F.Cu" "B.Cu")
		(remove_unused_layers yes)
		(keep_end_layers yes)
		(free yes)
		(zone_layer_connections "In1.Cu" "In4.Cu" "In6.Cu")
		(teardrops
			(best_length_ratio 0.4)
			(max_length 1)
			(best_width_ratio 0.9)
			(max_width 2)
			(curved_edges yes)
			(filter_ratio 0.9)
			(enabled yes)
			(allow_two_segments yes)
			(prefer_zone_connections yes)
		)
		(net 1)
	)
	(via
		(at 129.45 161.81)
		(size 0.45)
		(drill 0.1)
		(layers "F.Cu" "B.Cu")
		(remove_unused_layers yes)
		(keep_end_layers yes)
		(zone_layer_connections "In1.Cu" "In4.Cu" "In6.Cu")
		(teardrops
			(best_length_ratio 0.4)
			(max_length 1)
			(best_width_ratio 0.9)
			(max_width 2)
			(curved_edges yes)
			(filter_ratio 0.9)
			(enabled yes)
			(allow_two_segments yes)
			(prefer_zone_connections yes)
		)
		(net 1)
	)
	(via
		(at 99.45 132.81)
		(size 0.45)
		(drill 0.1)
		(layers "F.Cu" "B.Cu")
		(remove_unused_layers yes)
		(keep_end_layers yes)
		(zone_layer_connections "In1.Cu" "In4.Cu" "In6.Cu")
		(teardrops
			(best_length_ratio 0.4)
			(max_length 1)
			(best_width_ratio 0.9)
			(max_width 2)
			(curved_edges yes)
			(filter_ratio 0.9)
			(enabled yes)
			(allow_two_segments yes)
			(prefer_zone_connections yes)
		)
		(net 1)
	)
	(via
		(at 228.45 87.81)
		(size 0.45)
		(drill 0.1)
		(layers "F.Cu" "B.Cu")
		(remove_unused_layers yes)
		(keep_end_layers yes)
		(zone_layer_connections "In1.Cu" "In4.Cu" "In6.Cu")
		(teardrops
			(best_length_ratio 0.4)
			(max_length 1)
			(best_width_ratio 0.9)
			(max_width 2)
			(curved_edges yes)
			(filter_ratio 0.9)
			(enabled yes)
			(allow_two_segments yes)
			(prefer_zone_connections yes)
		)
		(net 1)
	)
	(via
		(at 219 157.8)
		(size 0.45)
		(drill 0.1)
		(layers "F.Cu" "B.Cu")
		(teardrops
			(best_length_ratio 0.4)
			(max_length 1)
			(best_width_ratio 0.9)
			(max_width 2)
			(curved_edges yes)
			(filter_ratio 0.9)
			(enabled yes)
			(allow_two_segments yes)
			(prefer_zone_connections yes)
		)
		(net 1)
	)
	(via
		(at 136.45 167.31)
		(size 0.45)
		(drill 0.1)
		(layers "F.Cu" "B.Cu")
		(remove_unused_layers yes)
		(keep_end_layers yes)
		(zone_layer_connections "In1.Cu" "In4.Cu" "In6.Cu")
		(teardrops
			(best_length_ratio 0.4)
			(max_length 1)
			(best_width_ratio 0.9)
			(max_width 2)
			(curved_edges yes)
			(filter_ratio 0.9)
			(enabled yes)
			(allow_two_segments yes)
			(prefer_zone_connections yes)
		)
		(net 1)
	)
	(via
		(at 291.95 124.81)
		(size 0.45)
		(drill 0.1)
		(layers "F.Cu" "B.Cu")
		(remove_unused_layers yes)
		(keep_end_layers yes)
		(zone_layer_connections "In1.Cu" "In4.Cu" "In6.Cu")
		(teardrops
			(best_length_ratio 0.4)
			(max_length 1)
			(best_width_ratio 0.9)
			(max_width 2)
			(curved_edges yes)
			(filter_ratio 0.9)
			(enabled yes)
			(allow_two_segments yes)
			(prefer_zone_connections yes)
		)
		(net 1)
	)
	(via
		(at 114.51 75.175)
		(size 0.45)
		(drill 0.1)
		(layers "F.Cu" "B.Cu")
		(remove_unused_layers yes)
		(keep_end_layers yes)
		(zone_layer_connections "In1.Cu" "In4.Cu" "In6.Cu")
		(teardrops
			(best_length_ratio 0.4)
			(max_length 1)
			(best_width_ratio 0.9)
			(max_width 2)
			(curved_edges yes)
			(filter_ratio 0.9)
			(enabled yes)
			(allow_two_segments yes)
			(prefer_zone_connections yes)
		)
		(net 1)
	)
	(via
		(at 155.249 156.797)
		(size 0.45)
		(drill 0.1)
		(layers "F.Cu" "B.Cu")
		(remove_unused_layers yes)
		(keep_end_layers yes)
		(zone_layer_connections "In1.Cu" "In4.Cu" "In6.Cu")
		(teardrops
			(best_length_ratio 0.4)
			(max_length 1)
			(best_width_ratio 0.9)
			(max_width 2)
			(curved_edges yes)
			(filter_ratio 0.9)
			(enabled yes)
			(allow_two_segments yes)
			(prefer_zone_connections yes)
		)
		(net 1)
	)
	(via
		(at 292.45 137.81)
		(size 0.45)
		(drill 0.1)
		(layers "F.Cu" "B.Cu")
		(remove_unused_layers yes)
		(keep_end_layers yes)
		(zone_layer_connections "In1.Cu" "In4.Cu" "In6.Cu")
		(teardrops
			(best_length_ratio 0.4)
			(max_length 1)
			(best_width_ratio 0.9)
			(max_width 2)
			(curved_edges yes)
			(filter_ratio 0.9)
			(enabled yes)
			(allow_two_segments yes)
			(prefer_zone_connections yes)
		)
		(net 1)
	)
	(via
		(at 294.95 106.81)
		(size 0.45)
		(drill 0.1)
		(layers "F.Cu" "B.Cu")
		(remove_unused_layers yes)
		(keep_end_layers yes)
		(zone_layer_connections "In1.Cu" "In4.Cu" "In6.Cu")
		(teardrops
			(best_length_ratio 0.4)
			(max_length 1)
			(best_width_ratio 0.9)
			(max_width 2)
			(curved_edges yes)
			(filter_ratio 0.9)
			(enabled yes)
			(allow_two_segments yes)
			(prefer_zone_connections yes)
		)
		(net 1)
	)
	(via
		(at 142.45 78.31)
		(size 0.45)
		(drill 0.1)
		(layers "F.Cu" "B.Cu")
		(remove_unused_layers yes)
		(keep_end_layers yes)
		(zone_layer_connections "In1.Cu" "In4.Cu" "In6.Cu")
		(teardrops
			(best_length_ratio 0.4)
			(max_length 1)
			(best_width_ratio 0.9)
			(max_width 2)
			(curved_edges yes)
			(filter_ratio 0.9)
			(enabled yes)
			(allow_two_segments yes)
			(prefer_zone_connections yes)
		)
		(net 1)
	)
	(via
		(at 239.95 123.31)
		(size 0.45)
		(drill 0.1)
		(layers "F.Cu" "B.Cu")
		(remove_unused_layers yes)
		(keep_end_layers yes)
		(zone_layer_connections "In1.Cu" "In4.Cu" "In6.Cu")
		(teardrops
			(best_length_ratio 0.4)
			(max_length 1)
			(best_width_ratio 0.9)
			(max_width 2)
			(curved_edges yes)
			(filter_ratio 0.9)
			(enabled yes)
			(allow_two_segments yes)
			(prefer_zone_connections yes)
		)
		(net 1)
	)
	(via
		(at 174.703893 99.409175)
		(size 0.45)
		(drill 0.1)
		(layers "F.Cu" "B.Cu")
		(remove_unused_layers yes)
		(keep_end_layers yes)
		(zone_layer_connections "In1.Cu" "In4.Cu" "In6.Cu")
		(teardrops
			(best_length_ratio 0.4)
			(max_length 1)
			(best_width_ratio 0.9)
			(max_width 2)
			(curved_edges yes)
			(filter_ratio 0.9)
			(enabled yes)
			(allow_two_segments yes)
			(prefer_zone_connections yes)
		)
		(net 1)
	)
	(via
		(at 256.95 166.41)
		(size 0.45)
		(drill 0.1)
		(layers "F.Cu" "B.Cu")
		(remove_unused_layers yes)
		(keep_end_layers yes)
		(free yes)
		(zone_layer_connections "In1.Cu" "In4.Cu" "In6.Cu")
		(teardrops
			(best_length_ratio 0.4)
			(max_length 1)
			(best_width_ratio 0.9)
			(max_width 2)
			(curved_edges yes)
			(filter_ratio 0.9)
			(enabled yes)
			(allow_two_segments yes)
			(prefer_zone_connections yes)
		)
		(net 1)
	)
	(via
		(at 287.45 130.31)
		(size 0.45)
		(drill 0.1)
		(layers "F.Cu" "B.Cu")
		(remove_unused_layers yes)
		(keep_end_layers yes)
		(zone_layer_connections "In1.Cu" "In4.Cu" "In6.Cu")
		(teardrops
			(best_length_ratio 0.4)
			(max_length 1)
			(best_width_ratio 0.9)
			(max_width 2)
			(curved_edges yes)
			(filter_ratio 0.9)
			(enabled yes)
			(allow_two_segments yes)
			(prefer_zone_connections yes)
		)
		(net 1)
	)
	(via
		(at 191.604179 137.139403)
		(size 0.45)
		(drill 0.1)
		(layers "F.Cu" "B.Cu")
		(remove_unused_layers yes)
		(keep_end_layers yes)
		(zone_layer_connections "In1.Cu" "In4.Cu" "In6.Cu")
		(teardrops
			(best_length_ratio 0.4)
			(max_length 1)
			(best_width_ratio 0.9)
			(max_width 2)
			(curved_edges yes)
			(filter_ratio 0.9)
			(enabled yes)
			(allow_two_segments yes)
			(prefer_zone_connections yes)
		)
		(net 1)
	)
	(via
		(at 129.45 91.81)
		(size 0.45)
		(drill 0.1)
		(layers "F.Cu" "B.Cu")
		(remove_unused_layers yes)
		(keep_end_layers yes)
		(zone_layer_connections "In1.Cu" "In4.Cu" "In6.Cu")
		(teardrops
			(best_length_ratio 0.4)
			(max_length 1)
			(best_width_ratio 0.9)
			(max_width 2)
			(curved_edges yes)
			(filter_ratio 0.9)
			(enabled yes)
			(allow_two_segments yes)
			(prefer_zone_connections yes)
		)
		(net 1)
	)
	(via
		(at 316.489499 134.71)
		(size 0.45)
		(drill 0.1)
		(layers "F.Cu" "B.Cu")
		(remove_unused_layers yes)
		(keep_end_layers yes)
		(zone_layer_connections "In1.Cu" "In4.Cu" "In6.Cu")
		(teardrops
			(best_length_ratio 0.4)
			(max_length 1)
			(best_width_ratio 0.9)
			(max_width 2)
			(curved_edges yes)
			(filter_ratio 0.9)
			(enabled yes)
			(allow_two_segments yes)
			(prefer_zone_connections yes)
		)
		(net 1)
	)
	(via
		(at 123.9 153.81)
		(size 0.45)
		(drill 0.1)
		(layers "F.Cu" "B.Cu")
		(remove_unused_layers yes)
		(keep_end_layers yes)
		(zone_layer_connections "In1.Cu" "In4.Cu" "In6.Cu")
		(teardrops
			(best_length_ratio 0.4)
			(max_length 1)
			(best_width_ratio 0.9)
			(max_width 2)
			(curved_edges yes)
			(filter_ratio 0.9)
			(enabled yes)
			(allow_two_segments yes)
			(prefer_zone_connections yes)
		)
		(net 1)
	)
	(via
		(at 216.45 90.81)
		(size 0.45)
		(drill 0.1)
		(layers "F.Cu" "B.Cu")
		(remove_unused_layers yes)
		(keep_end_layers yes)
		(zone_layer_connections "In1.Cu" "In4.Cu" "In6.Cu")
		(teardrops
			(best_length_ratio 0.4)
			(max_length 1)
			(best_width_ratio 0.9)
			(max_width 2)
			(curved_edges yes)
			(filter_ratio 0.9)
			(enabled yes)
			(allow_two_segments yes)
			(prefer_zone_connections yes)
		)
		(net 1)
	)
	(via
		(at 263.95 109.81)
		(size 0.45)
		(drill 0.1)
		(layers "F.Cu" "B.Cu")
		(remove_unused_layers yes)
		(keep_end_layers yes)
		(zone_layer_connections "In1.Cu" "In4.Cu" "In6.Cu")
		(teardrops
			(best_length_ratio 0.4)
			(max_length 1)
			(best_width_ratio 0.9)
			(max_width 2)
			(curved_edges yes)
			(filter_ratio 0.9)
			(enabled yes)
			(allow_two_segments yes)
			(prefer_zone_connections yes)
		)
		(net 1)
	)
	(via
		(at 261.56 137.51)
		(size 0.45)
		(drill 0.1)
		(layers "F.Cu" "B.Cu")
		(remove_unused_layers yes)
		(keep_end_layers yes)
		(zone_layer_connections "In1.Cu" "In4.Cu" "In6.Cu")
		(teardrops
			(best_length_ratio 0.4)
			(max_length 1)
			(best_width_ratio 0.9)
			(max_width 2)
			(curved_edges yes)
			(filter_ratio 0.9)
			(enabled yes)
			(allow_two_segments yes)
			(prefer_zone_connections yes)
		)
		(net 1)
	)
	(via
		(at 113.45 96.31)
		(size 0.45)
		(drill 0.1)
		(layers "F.Cu" "B.Cu")
		(remove_unused_layers yes)
		(keep_end_layers yes)
		(zone_layer_connections "In1.Cu" "In4.Cu" "In6.Cu")
		(teardrops
			(best_length_ratio 0.4)
			(max_length 1)
			(best_width_ratio 0.9)
			(max_width 2)
			(curved_edges yes)
			(filter_ratio 0.9)
			(enabled yes)
			(allow_two_segments yes)
			(prefer_zone_connections yes)
		)
		(net 1)
	)
	(via
		(at 178 149.925)
		(size 0.45)
		(drill 0.1)
		(layers "F.Cu" "B.Cu")
		(teardrops
			(best_length_ratio 0.4)
			(max_length 1)
			(best_width_ratio 0.9)
			(max_width 2)
			(curved_edges yes)
			(filter_ratio 0.9)
			(enabled yes)
			(allow_two_segments yes)
			(prefer_zone_connections yes)
		)
		(net 1)
	)
	(via
		(at 177.18 94.86)
		(size 0.45)
		(drill 0.1)
		(layers "F.Cu" "B.Cu")
		(remove_unused_layers yes)
		(keep_end_layers yes)
		(zone_layer_connections "In1.Cu" "In4.Cu" "In6.Cu")
		(teardrops
			(best_length_ratio 0.4)
			(max_length 1)
			(best_width_ratio 0.9)
			(max_width 2)
			(curved_edges yes)
			(filter_ratio 0.9)
			(enabled yes)
			(allow_two_segments yes)
			(prefer_zone_connections yes)
		)
		(net 1)
	)
	(via
		(at 242.6 160.8)
		(size 0.45)
		(drill 0.1)
		(layers "F.Cu" "B.Cu")
		(teardrops
			(best_length_ratio 0.4)
			(max_length 1)
			(best_width_ratio 0.9)
			(max_width 2)
			(curved_edges yes)
			(filter_ratio 0.9)
			(enabled yes)
			(allow_two_segments yes)
			(prefer_zone_connections yes)
		)
		(net 1)
	)
	(via
		(at 302.98 90.06)
		(size 0.45)
		(drill 0.1)
		(layers "F.Cu" "B.Cu")
		(remove_unused_layers yes)
		(keep_end_layers yes)
		(zone_layer_connections "In1.Cu" "In4.Cu" "In6.Cu")
		(teardrops
			(best_length_ratio 0.4)
			(max_length 1)
			(best_width_ratio 0.9)
			(max_width 2)
			(curved_edges yes)
			(filter_ratio 0.9)
			(enabled yes)
			(allow_two_segments yes)
			(prefer_zone_connections yes)
		)
		(net 1)
	)
	(via
		(at 154.5 80.56)
		(size 0.45)
		(drill 0.1)
		(layers "F.Cu" "B.Cu")
		(remove_unused_layers yes)
		(keep_end_layers yes)
		(zone_layer_connections "In1.Cu" "In4.Cu" "In6.Cu")
		(teardrops
			(best_length_ratio 0.4)
			(max_length 1)
			(best_width_ratio 0.9)
			(max_width 2)
			(curved_edges yes)
			(filter_ratio 0.9)
			(enabled yes)
			(allow_two_segments yes)
			(prefer_zone_connections yes)
		)
		(net 1)
	)
	(via
		(at 292.45 142.81)
		(size 0.45)
		(drill 0.1)
		(layers "F.Cu" "B.Cu")
		(remove_unused_layers yes)
		(keep_end_layers yes)
		(zone_layer_connections "In1.Cu" "In4.Cu" "In6.Cu")
		(teardrops
			(best_length_ratio 0.4)
			(max_length 1)
			(best_width_ratio 0.9)
			(max_width 2)
			(curved_edges yes)
			(filter_ratio 0.9)
			(enabled yes)
			(allow_two_segments yes)
			(prefer_zone_connections yes)
		)
		(net 1)
	)
	(via
		(at 210.5 155.5)
		(size 0.45)
		(drill 0.1)
		(layers "F.Cu" "B.Cu")
		(teardrops
			(best_length_ratio 0.4)
			(max_length 1)
			(best_width_ratio 0.9)
			(max_width 2)
			(curved_edges yes)
			(filter_ratio 0.9)
			(enabled yes)
			(allow_two_segments yes)
			(prefer_zone_connections yes)
		)
		(net 1)
	)
	(via
		(at 193.7255 135.018083)
		(size 0.45)
		(drill 0.1)
		(layers "F.Cu" "B.Cu")
		(remove_unused_layers yes)
		(keep_end_layers yes)
		(zone_layer_connections "In1.Cu" "In4.Cu" "In6.Cu")
		(teardrops
			(best_length_ratio 0.4)
			(max_length 1)
			(best_width_ratio 0.9)
			(max_width 2)
			(curved_edges yes)
			(filter_ratio 0.9)
			(enabled yes)
			(allow_two_segments yes)
			(prefer_zone_connections yes)
		)
		(net 1)
	)
	(via
		(at 151.45 131.86)
		(size 0.45)
		(drill 0.1)
		(layers "F.Cu" "B.Cu")
		(remove_unused_layers yes)
		(keep_end_layers yes)
		(zone_layer_connections "In1.Cu" "In4.Cu" "In6.Cu")
		(teardrops
			(best_length_ratio 0.4)
			(max_length 1)
			(best_width_ratio 0.9)
			(max_width 2)
			(curved_edges yes)
			(filter_ratio 0.9)
			(enabled yes)
			(allow_two_segments yes)
			(prefer_zone_connections yes)
		)
		(net 1)
	)
	(via
		(at 239.95 114.31)
		(size 0.45)
		(drill 0.1)
		(layers "F.Cu" "B.Cu")
		(remove_unused_layers yes)
		(keep_end_layers yes)
		(zone_layer_connections "In1.Cu" "In4.Cu" "In6.Cu")
		(teardrops
			(best_length_ratio 0.4)
			(max_length 1)
			(best_width_ratio 0.9)
			(max_width 2)
			(curved_edges yes)
			(filter_ratio 0.9)
			(enabled yes)
			(allow_two_segments yes)
			(prefer_zone_connections yes)
		)
		(net 1)
	)
	(via
		(at 101.45 132.81)
		(size 0.45)
		(drill 0.1)
		(layers "F.Cu" "B.Cu")
		(remove_unused_layers yes)
		(keep_end_layers yes)
		(zone_layer_connections "In1.Cu" "In4.Cu" "In6.Cu")
		(teardrops
			(best_length_ratio 0.4)
			(max_length 1)
			(best_width_ratio 0.9)
			(max_width 2)
			(curved_edges yes)
			(filter_ratio 0.9)
			(enabled yes)
			(allow_two_segments yes)
			(prefer_zone_connections yes)
		)
		(net 1)
	)
	(via
		(at 310.15 72.06)
		(size 0.45)
		(drill 0.1)
		(layers "F.Cu" "B.Cu")
		(remove_unused_layers yes)
		(keep_end_layers yes)
		(zone_layer_connections "In1.Cu" "In4.Cu" "In6.Cu")
		(teardrops
			(best_length_ratio 0.4)
			(max_length 1)
			(best_width_ratio 0.9)
			(max_width 2)
			(curved_edges yes)
			(filter_ratio 0.9)
			(enabled yes)
			(allow_two_segments yes)
			(prefer_zone_connections yes)
		)
		(net 1)
	)
	(via
		(at 136.3 161.56)
		(size 0.45)
		(drill 0.1)
		(layers "F.Cu" "B.Cu")
		(remove_unused_layers yes)
		(keep_end_layers yes)
		(zone_layer_connections "In1.Cu" "In4.Cu" "In6.Cu")
		(teardrops
			(best_length_ratio 0.4)
			(max_length 1)
			(best_width_ratio 0.9)
			(max_width 2)
			(curved_edges yes)
			(filter_ratio 0.9)
			(enabled yes)
			(allow_two_segments yes)
			(prefer_zone_connections yes)
		)
		(net 1)
	)
	(via
		(at 135.29 141.86)
		(size 0.45)
		(drill 0.1)
		(layers "F.Cu" "B.Cu")
		(remove_unused_layers yes)
		(keep_end_layers yes)
		(zone_layer_connections "In1.Cu" "In4.Cu" "In6.Cu")
		(teardrops
			(best_length_ratio 0.4)
			(max_length 1)
			(best_width_ratio 0.9)
			(max_width 2)
			(curved_edges yes)
			(filter_ratio 0.9)
			(enabled yes)
			(allow_two_segments yes)
			(prefer_zone_connections yes)
		)
		(net 1)
	)
	(via
		(at 151.45 142.86)
		(size 0.45)
		(drill 0.1)
		(layers "F.Cu" "B.Cu")
		(remove_unused_layers yes)
		(keep_end_layers yes)
		(zone_layer_connections "In1.Cu" "In4.Cu" "In6.Cu")
		(teardrops
			(best_length_ratio 0.4)
			(max_length 1)
			(best_width_ratio 0.9)
			(max_width 2)
			(curved_edges yes)
			(filter_ratio 0.9)
			(enabled yes)
			(allow_two_segments yes)
			(prefer_zone_connections yes)
		)
		(net 1)
	)
	(via
		(at 220.7 169.9)
		(size 0.45)
		(drill 0.1)
		(layers "F.Cu" "B.Cu")
		(teardrops
			(best_length_ratio 0.4)
			(max_length 1)
			(best_width_ratio 0.9)
			(max_width 2)
			(curved_edges yes)
			(filter_ratio 0.9)
			(enabled yes)
			(allow_two_segments yes)
			(prefer_zone_connections yes)
		)
		(net 1)
	)
	(via
		(at 284.95 90.31)
		(size 0.45)
		(drill 0.1)
		(layers "F.Cu" "B.Cu")
		(remove_unused_layers yes)
		(keep_end_layers yes)
		(zone_layer_connections "In1.Cu" "In4.Cu" "In6.Cu")
		(teardrops
			(best_length_ratio 0.4)
			(max_length 1)
			(best_width_ratio 0.9)
			(max_width 2)
			(curved_edges yes)
			(filter_ratio 0.9)
			(enabled yes)
			(allow_two_segments yes)
			(prefer_zone_connections yes)
		)
		(net 1)
	)
	(via
		(at 284.95 144.31)
		(size 0.45)
		(drill 0.1)
		(layers "F.Cu" "B.Cu")
		(remove_unused_layers yes)
		(keep_end_layers yes)
		(zone_layer_connections "In1.Cu" "In4.Cu" "In6.Cu")
		(teardrops
			(best_length_ratio 0.4)
			(max_length 1)
			(best_width_ratio 0.9)
			(max_width 2)
			(curved_edges yes)
			(filter_ratio 0.9)
			(enabled yes)
			(allow_two_segments yes)
			(prefer_zone_connections yes)
		)
		(net 1)
	)
	(via
		(at 131.3 84.91)
		(size 0.45)
		(drill 0.1)
		(layers "F.Cu" "B.Cu")
		(remove_unused_layers yes)
		(keep_end_layers yes)
		(zone_layer_connections "In1.Cu" "In4.Cu" "In6.Cu")
		(teardrops
			(best_length_ratio 0.4)
			(max_length 1)
			(best_width_ratio 0.9)
			(max_width 2)
			(curved_edges yes)
			(filter_ratio 0.9)
			(enabled yes)
			(allow_two_segments yes)
			(prefer_zone_connections yes)
		)
		(net 1)
	)
	(via
		(at 284.950001 170.81)
		(size 0.45)
		(drill 0.1)
		(layers "F.Cu" "B.Cu")
		(remove_unused_layers yes)
		(keep_end_layers yes)
		(zone_layer_connections "In1.Cu" "In4.Cu" "In6.Cu")
		(teardrops
			(best_length_ratio 0.4)
			(max_length 1)
			(best_width_ratio 0.9)
			(max_width 2)
			(curved_edges yes)
			(filter_ratio 0.9)
			(enabled yes)
			(allow_two_segments yes)
			(prefer_zone_connections yes)
		)
		(net 1)
	)
	(via
		(at 142.52 133.38)
		(size 0.45)
		(drill 0.1)
		(layers "F.Cu" "B.Cu")
		(remove_unused_layers yes)
		(keep_end_layers yes)
		(zone_layer_connections "In1.Cu" "In4.Cu" "In6.Cu")
		(teardrops
			(best_length_ratio 0.4)
			(max_length 1)
			(best_width_ratio 0.9)
			(max_width 2)
			(curved_edges yes)
			(filter_ratio 0.9)
			(enabled yes)
			(allow_two_segments yes)
			(prefer_zone_connections yes)
		)
		(net 1)
	)
	(via
		(at 112.63 134.56)
		(size 0.45)
		(drill 0.1)
		(layers "F.Cu" "B.Cu")
		(remove_unused_layers yes)
		(keep_end_layers yes)
		(zone_layer_connections "In1.Cu" "In4.Cu" "In6.Cu")
		(teardrops
			(best_length_ratio 0.4)
			(max_length 1)
			(best_width_ratio 0.9)
			(max_width 2)
			(curved_edges yes)
			(filter_ratio 0.9)
			(enabled yes)
			(allow_two_segments yes)
			(prefer_zone_connections yes)
		)
		(net 1)
	)
	(via
		(at 196.95 86.81)
		(size 0.45)
		(drill 0.1)
		(layers "F.Cu" "B.Cu")
		(remove_unused_layers yes)
		(keep_end_layers yes)
		(zone_layer_connections "In1.Cu" "In4.Cu" "In6.Cu")
		(teardrops
			(best_length_ratio 0.4)
			(max_length 1)
			(best_width_ratio 0.9)
			(max_width 2)
			(curved_edges yes)
			(filter_ratio 0.9)
			(enabled yes)
			(allow_two_segments yes)
			(prefer_zone_connections yes)
		)
		(net 1)
	)
	(via
		(at 283.45 142.81)
		(size 0.45)
		(drill 0.1)
		(layers "F.Cu" "B.Cu")
		(remove_unused_layers yes)
		(keep_end_layers yes)
		(zone_layer_connections "In1.Cu" "In4.Cu" "In6.Cu")
		(teardrops
			(best_length_ratio 0.4)
			(max_length 1)
			(best_width_ratio 0.9)
			(max_width 2)
			(curved_edges yes)
			(filter_ratio 0.9)
			(enabled yes)
			(allow_two_segments yes)
			(prefer_zone_connections yes)
		)
		(net 1)
	)
	(via
		(at 158.649 161.297)
		(size 0.45)
		(drill 0.1)
		(layers "F.Cu" "B.Cu")
		(remove_unused_layers yes)
		(keep_end_layers yes)
		(zone_layer_connections "In1.Cu" "In4.Cu" "In6.Cu")
		(teardrops
			(best_length_ratio 0.4)
			(max_length 1)
			(best_width_ratio 0.9)
			(max_width 2)
			(curved_edges yes)
			(filter_ratio 0.9)
			(enabled yes)
			(allow_two_segments yes)
			(prefer_zone_connections yes)
		)
		(net 1)
	)
	(via
		(at 226.3 144.35)
		(size 0.45)
		(drill 0.1)
		(layers "F.Cu" "B.Cu")
		(teardrops
			(best_length_ratio 0.4)
			(max_length 1)
			(best_width_ratio 0.9)
			(max_width 2)
			(curved_edges yes)
			(filter_ratio 0.9)
			(enabled yes)
			(allow_two_segments yes)
			(prefer_zone_connections yes)
		)
		(net 1)
	)
	(via
		(at 317.4645 98.6365)
		(size 0.45)
		(drill 0.1)
		(layers "F.Cu" "B.Cu")
		(remove_unused_layers yes)
		(keep_end_layers yes)
		(free yes)
		(zone_layer_connections "In1.Cu" "In4.Cu" "In6.Cu")
		(teardrops
			(best_length_ratio 0.4)
			(max_length 1)
			(best_width_ratio 0.9)
			(max_width 2)
			(curved_edges yes)
			(filter_ratio 0.9)
			(enabled yes)
			(allow_two_segments yes)
			(prefer_zone_connections yes)
		)
		(net 1)
	)
	(via
		(at 139.8 73.01)
		(size 0.45)
		(drill 0.1)
		(layers "F.Cu" "B.Cu")
		(remove_unused_layers yes)
		(keep_end_layers yes)
		(zone_layer_connections "In1.Cu" "In4.Cu" "In6.Cu")
		(teardrops
			(best_length_ratio 0.4)
			(max_length 1)
			(best_width_ratio 0.9)
			(max_width 2)
			(curved_edges yes)
			(filter_ratio 0.9)
			(enabled yes)
			(allow_two_segments yes)
			(prefer_zone_connections yes)
		)
		(net 1)
	)
	(via
		(at 215.45 164.4)
		(size 0.45)
		(drill 0.1)
		(layers "F.Cu" "B.Cu")
		(teardrops
			(best_length_ratio 0.4)
			(max_length 1)
			(best_width_ratio 0.9)
			(max_width 2)
			(curved_edges yes)
			(filter_ratio 0.9)
			(enabled yes)
			(allow_two_segments yes)
			(prefer_zone_connections yes)
		)
		(net 1)
	)
	(via
		(at 159.45 153.81)
		(size 0.45)
		(drill 0.1)
		(layers "F.Cu" "B.Cu")
		(remove_unused_layers yes)
		(keep_end_layers yes)
		(zone_layer_connections "In1.Cu" "In4.Cu" "In6.Cu")
		(teardrops
			(best_length_ratio 0.4)
			(max_length 1)
			(best_width_ratio 0.9)
			(max_width 2)
			(curved_edges yes)
			(filter_ratio 0.9)
			(enabled yes)
			(allow_two_segments yes)
			(prefer_zone_connections yes)
		)
		(net 1)
	)
	(via
		(at 177.9 157.9)
		(size 0.45)
		(drill 0.1)
		(layers "F.Cu" "B.Cu")
		(teardrops
			(best_length_ratio 0.4)
			(max_length 1)
			(best_width_ratio 0.9)
			(max_width 2)
			(curved_edges yes)
			(filter_ratio 0.9)
			(enabled yes)
			(allow_two_segments yes)
			(prefer_zone_connections yes)
		)
		(net 1)
	)
	(via
		(at 285.95 100.81)
		(size 0.45)
		(drill 0.1)
		(layers "F.Cu" "B.Cu")
		(remove_unused_layers yes)
		(keep_end_layers yes)
		(zone_layer_connections "In1.Cu" "In4.Cu" "In6.Cu")
		(teardrops
			(best_length_ratio 0.4)
			(max_length 1)
			(best_width_ratio 0.9)
			(max_width 2)
			(curved_edges yes)
			(filter_ratio 0.9)
			(enabled yes)
			(allow_two_segments yes)
			(prefer_zone_connections yes)
		)
		(net 1)
	)
	(via
		(at 262.45 117.31)
		(size 0.45)
		(drill 0.1)
		(layers "F.Cu" "B.Cu")
		(remove_unused_layers yes)
		(keep_end_layers yes)
		(zone_layer_connections "In1.Cu" "In4.Cu" "In6.Cu")
		(teardrops
			(best_length_ratio 0.4)
			(max_length 1)
			(best_width_ratio 0.9)
			(max_width 2)
			(curved_edges yes)
			(filter_ratio 0.9)
			(enabled yes)
			(allow_two_segments yes)
			(prefer_zone_connections yes)
		)
		(net 1)
	)
	(via
		(at 233.55 127.29)
		(size 0.45)
		(drill 0.1)
		(layers "F.Cu" "B.Cu")
		(remove_unused_layers yes)
		(keep_end_layers yes)
		(zone_layer_connections "In1.Cu" "In4.Cu" "In6.Cu")
		(teardrops
			(best_length_ratio 0.4)
			(max_length 1)
			(best_width_ratio 0.9)
			(max_width 2)
			(curved_edges yes)
			(filter_ratio 0.9)
			(enabled yes)
			(allow_two_segments yes)
			(prefer_zone_connections yes)
		)
		(net 1)
	)
	(via
		(at 196.95 70.31)
		(size 0.45)
		(drill 0.1)
		(layers "F.Cu" "B.Cu")
		(remove_unused_layers yes)
		(keep_end_layers yes)
		(free yes)
		(zone_layer_connections "In1.Cu" "In4.Cu" "In6.Cu")
		(teardrops
			(best_length_ratio 0.4)
			(max_length 1)
			(best_width_ratio 0.9)
			(max_width 2)
			(curved_edges yes)
			(filter_ratio 0.9)
			(enabled yes)
			(allow_two_segments yes)
			(prefer_zone_connections yes)
		)
		(net 1)
	)
	(via
		(at 99.95 89.81)
		(size 0.45)
		(drill 0.1)
		(layers "F.Cu" "B.Cu")
		(remove_unused_layers yes)
		(keep_end_layers yes)
		(zone_layer_connections "In1.Cu" "In4.Cu" "In6.Cu")
		(teardrops
			(best_length_ratio 0.4)
			(max_length 1)
			(best_width_ratio 0.9)
			(max_width 2)
			(curved_edges yes)
			(filter_ratio 0.9)
			(enabled yes)
			(allow_two_segments yes)
			(prefer_zone_connections yes)
		)
		(net 1)
	)
	(via
		(at 152.02 147.63)
		(size 0.45)
		(drill 0.1)
		(layers "F.Cu" "B.Cu")
		(remove_unused_layers yes)
		(keep_end_layers yes)
		(zone_layer_connections "In1.Cu" "In4.Cu" "In6.Cu")
		(teardrops
			(best_length_ratio 0.4)
			(max_length 1)
			(best_width_ratio 0.9)
			(max_width 2)
			(curved_edges yes)
			(filter_ratio 0.9)
			(enabled yes)
			(allow_two_segments yes)
			(prefer_zone_connections yes)
		)
		(net 1)
	)
	(via
		(at 311.425499 135.11)
		(size 0.45)
		(drill 0.1)
		(layers "F.Cu" "B.Cu")
		(remove_unused_layers yes)
		(keep_end_layers yes)
		(zone_layer_connections "In1.Cu" "In4.Cu" "In6.Cu")
		(teardrops
			(best_length_ratio 0.4)
			(max_length 1)
			(best_width_ratio 0.9)
			(max_width 2)
			(curved_edges yes)
			(filter_ratio 0.9)
			(enabled yes)
			(allow_two_segments yes)
			(prefer_zone_connections yes)
		)
		(net 1)
	)
	(via
		(at 186 161.7)
		(size 0.45)
		(drill 0.1)
		(layers "F.Cu" "B.Cu")
		(teardrops
			(best_length_ratio 0.4)
			(max_length 1)
			(best_width_ratio 0.9)
			(max_width 2)
			(curved_edges yes)
			(filter_ratio 0.9)
			(enabled yes)
			(allow_two_segments yes)
			(prefer_zone_connections yes)
		)
		(net 1)
	)
	(via
		(at 210.45 90.81)
		(size 0.45)
		(drill 0.1)
		(layers "F.Cu" "B.Cu")
		(remove_unused_layers yes)
		(keep_end_layers yes)
		(free yes)
		(zone_layer_connections "In1.Cu" "In4.Cu" "In6.Cu")
		(teardrops
			(best_length_ratio 0.4)
			(max_length 1)
			(best_width_ratio 0.9)
			(max_width 2)
			(curved_edges yes)
			(filter_ratio 0.9)
			(enabled yes)
			(allow_two_segments yes)
			(prefer_zone_connections yes)
		)
		(net 1)
	)
	(via
		(at 130 86.210002)
		(size 0.45)
		(drill 0.1)
		(layers "F.Cu" "B.Cu")
		(remove_unused_layers yes)
		(keep_end_layers yes)
		(zone_layer_connections "In1.Cu" "In4.Cu" "In6.Cu")
		(teardrops
			(best_length_ratio 0.4)
			(max_length 1)
			(best_width_ratio 0.9)
			(max_width 2)
			(curved_edges yes)
			(filter_ratio 0.9)
			(enabled yes)
			(allow_two_segments yes)
			(prefer_zone_connections yes)
		)
		(net 1)
	)
	(via
		(at 127.29 143.86)
		(size 0.45)
		(drill 0.1)
		(layers "F.Cu" "B.Cu")
		(remove_unused_layers yes)
		(keep_end_layers yes)
		(zone_layer_connections "In1.Cu" "In4.Cu" "In6.Cu")
		(teardrops
			(best_length_ratio 0.4)
			(max_length 1)
			(best_width_ratio 0.9)
			(max_width 2)
			(curved_edges yes)
			(filter_ratio 0.9)
			(enabled yes)
			(allow_two_segments yes)
			(prefer_zone_connections yes)
		)
		(net 1)
	)
	(via
		(at 112.95 88.61)
		(size 0.45)
		(drill 0.1)
		(layers "F.Cu" "B.Cu")
		(remove_unused_layers yes)
		(keep_end_layers yes)
		(zone_layer_connections "In1.Cu" "In4.Cu" "In6.Cu")
		(teardrops
			(best_length_ratio 0.4)
			(max_length 1)
			(best_width_ratio 0.9)
			(max_width 2)
			(curved_edges yes)
			(filter_ratio 0.9)
			(enabled yes)
			(allow_two_segments yes)
			(prefer_zone_connections yes)
		)
		(net 1)
	)
	(via
		(at 287.95 144.31)
		(size 0.45)
		(drill 0.1)
		(layers "F.Cu" "B.Cu")
		(remove_unused_layers yes)
		(keep_end_layers yes)
		(zone_layer_connections "In1.Cu" "In4.Cu" "In6.Cu")
		(teardrops
			(best_length_ratio 0.4)
			(max_length 1)
			(best_width_ratio 0.9)
			(max_width 2)
			(curved_edges yes)
			(filter_ratio 0.9)
			(enabled yes)
			(allow_two_segments yes)
			(prefer_zone_connections yes)
		)
		(net 1)
	)
	(via
		(at 283.95 106.31)
		(size 0.45)
		(drill 0.1)
		(layers "F.Cu" "B.Cu")
		(remove_unused_layers yes)
		(keep_end_layers yes)
		(zone_layer_connections "In1.Cu" "In4.Cu" "In6.Cu")
		(teardrops
			(best_length_ratio 0.4)
			(max_length 1)
			(best_width_ratio 0.9)
			(max_width 2)
			(curved_edges yes)
			(filter_ratio 0.9)
			(enabled yes)
			(allow_two_segments yes)
			(prefer_zone_connections yes)
		)
		(net 1)
	)
	(via
		(at 127.25 102.869848)
		(size 0.45)
		(drill 0.1)
		(layers "F.Cu" "B.Cu")
		(remove_unused_layers yes)
		(keep_end_layers yes)
		(zone_layer_connections "In1.Cu" "In4.Cu" "In6.Cu")
		(teardrops
			(best_length_ratio 0.4)
			(max_length 1)
			(best_width_ratio 0.9)
			(max_width 2)
			(curved_edges yes)
			(filter_ratio 0.9)
			(enabled yes)
			(allow_two_segments yes)
			(prefer_zone_connections yes)
		)
		(net 1)
	)
	(via
		(at 258.730708 77.605)
		(size 0.45)
		(drill 0.1)
		(layers "F.Cu" "B.Cu")
		(remove_unused_layers yes)
		(keep_end_layers yes)
		(zone_layer_connections "In1.Cu" "In4.Cu" "In6.Cu")
		(teardrops
			(best_length_ratio 0.4)
			(max_length 1)
			(best_width_ratio 0.9)
			(max_width 2)
			(curved_edges yes)
			(filter_ratio 0.9)
			(enabled yes)
			(allow_two_segments yes)
			(prefer_zone_connections yes)
		)
		(net 1)
	)
	(via
		(at 280.95 118.31)
		(size 0.45)
		(drill 0.1)
		(layers "F.Cu" "B.Cu")
		(remove_unused_layers yes)
		(keep_end_layers yes)
		(zone_layer_connections "In1.Cu" "In4.Cu" "In6.Cu")
		(teardrops
			(best_length_ratio 0.4)
			(max_length 1)
			(best_width_ratio 0.9)
			(max_width 2)
			(curved_edges yes)
			(filter_ratio 0.9)
			(enabled yes)
			(allow_two_segments yes)
			(prefer_zone_connections yes)
		)
		(net 1)
	)
	(via
		(at 238.45 118.81)
		(size 0.45)
		(drill 0.1)
		(layers "F.Cu" "B.Cu")
		(remove_unused_layers yes)
		(keep_end_layers yes)
		(zone_layer_connections "In1.Cu" "In4.Cu" "In6.Cu")
		(teardrops
			(best_length_ratio 0.4)
			(max_length 1)
			(best_width_ratio 0.9)
			(max_width 2)
			(curved_edges yes)
			(filter_ratio 0.9)
			(enabled yes)
			(allow_two_segments yes)
			(prefer_zone_connections yes)
		)
		(net 1)
	)
	(via
		(at 101.95 111.81)
		(size 0.45)
		(drill 0.1)
		(layers "F.Cu" "B.Cu")
		(remove_unused_layers yes)
		(keep_end_layers yes)
		(zone_layer_connections "In1.Cu" "In4.Cu" "In6.Cu")
		(teardrops
			(best_length_ratio 0.4)
			(max_length 1)
			(best_width_ratio 0.9)
			(max_width 2)
			(curved_edges yes)
			(filter_ratio 0.9)
			(enabled yes)
			(allow_two_segments yes)
			(prefer_zone_connections yes)
		)
		(net 1)
	)
	(via
		(at 173.2 152.4)
		(size 0.45)
		(drill 0.1)
		(layers "F.Cu" "B.Cu")
		(teardrops
			(best_length_ratio 0.4)
			(max_length 1)
			(best_width_ratio 0.9)
			(max_width 2)
			(curved_edges yes)
			(filter_ratio 0.9)
			(enabled yes)
			(allow_two_segments yes)
			(prefer_zone_connections yes)
		)
		(net 1)
	)
	(via
		(at 125.95 154.81)
		(size 0.45)
		(drill 0.1)
		(layers "F.Cu" "B.Cu")
		(remove_unused_layers yes)
		(keep_end_layers yes)
		(zone_layer_connections "In1.Cu" "In4.Cu" "In6.Cu")
		(teardrops
			(best_length_ratio 0.4)
			(max_length 1)
			(best_width_ratio 0.9)
			(max_width 2)
			(curved_edges yes)
			(filter_ratio 0.9)
			(enabled yes)
			(allow_two_segments yes)
			(prefer_zone_connections yes)
		)
		(net 1)
	)
	(via
		(at 96.45 139.81)
		(size 0.45)
		(drill 0.1)
		(layers "F.Cu" "B.Cu")
		(remove_unused_layers yes)
		(keep_end_layers yes)
		(zone_layer_connections "In1.Cu" "In4.Cu" "In6.Cu")
		(teardrops
			(best_length_ratio 0.4)
			(max_length 1)
			(best_width_ratio 0.9)
			(max_width 2)
			(curved_edges yes)
			(filter_ratio 0.9)
			(enabled yes)
			(allow_two_segments yes)
			(prefer_zone_connections yes)
		)
		(net 1)
	)
	(via
		(at 104.37 101.86)
		(size 0.45)
		(drill 0.1)
		(layers "F.Cu" "B.Cu")
		(remove_unused_layers yes)
		(keep_end_layers yes)
		(zone_layer_connections "In1.Cu" "In4.Cu" "In6.Cu")
		(teardrops
			(best_length_ratio 0.4)
			(max_length 1)
			(best_width_ratio 0.9)
			(max_width 2)
			(curved_edges yes)
			(filter_ratio 0.9)
			(enabled yes)
			(allow_two_segments yes)
			(prefer_zone_connections yes)
		)
		(net 1)
	)
	(via
		(at 290.95 136.31)
		(size 0.45)
		(drill 0.1)
		(layers "F.Cu" "B.Cu")
		(remove_unused_layers yes)
		(keep_end_layers yes)
		(zone_layer_connections "In1.Cu" "In4.Cu" "In6.Cu")
		(teardrops
			(best_length_ratio 0.4)
			(max_length 1)
			(best_width_ratio 0.9)
			(max_width 2)
			(curved_edges yes)
			(filter_ratio 0.9)
			(enabled yes)
			(allow_two_segments yes)
			(prefer_zone_connections yes)
		)
		(net 1)
	)
	(via
		(at 285.45 119.81)
		(size 0.45)
		(drill 0.1)
		(layers "F.Cu" "B.Cu")
		(remove_unused_layers yes)
		(keep_end_layers yes)
		(zone_layer_connections "In1.Cu" "In4.Cu" "In6.Cu")
		(teardrops
			(best_length_ratio 0.4)
			(max_length 1)
			(best_width_ratio 0.9)
			(max_width 2)
			(curved_edges yes)
			(filter_ratio 0.9)
			(enabled yes)
			(allow_two_segments yes)
			(prefer_zone_connections yes)
		)
		(net 1)
	)
	(via
		(at 207.68 131.35)
		(size 0.45)
		(drill 0.1)
		(layers "F.Cu" "B.Cu")
		(remove_unused_layers yes)
		(keep_end_layers yes)
		(zone_layer_connections "In1.Cu" "In4.Cu" "In6.Cu")
		(teardrops
			(best_length_ratio 0.4)
			(max_length 1)
			(best_width_ratio 0.9)
			(max_width 2)
			(curved_edges yes)
			(filter_ratio 0.9)
			(enabled yes)
			(allow_two_segments yes)
			(prefer_zone_connections yes)
		)
		(net 1)
	)
	(via
		(at 316.4645 95.6365)
		(size 0.45)
		(drill 0.1)
		(layers "F.Cu" "B.Cu")
		(remove_unused_layers yes)
		(keep_end_layers yes)
		(zone_layer_connections "In1.Cu" "In4.Cu" "In6.Cu")
		(teardrops
			(best_length_ratio 0.4)
			(max_length 1)
			(best_width_ratio 0.9)
			(max_width 2)
			(curved_edges yes)
			(filter_ratio 0.9)
			(enabled yes)
			(allow_two_segments yes)
			(prefer_zone_connections yes)
		)
		(net 1)
	)
	(via
		(at 213.5 155.5)
		(size 0.45)
		(drill 0.1)
		(layers "F.Cu" "B.Cu")
		(teardrops
			(best_length_ratio 0.4)
			(max_length 1)
			(best_width_ratio 0.9)
			(max_width 2)
			(curved_edges yes)
			(filter_ratio 0.9)
			(enabled yes)
			(allow_two_segments yes)
			(prefer_zone_connections yes)
		)
		(net 1)
	)
	(via
		(at 294.95 120.31)
		(size 0.45)
		(drill 0.1)
		(layers "F.Cu" "B.Cu")
		(remove_unused_layers yes)
		(keep_end_layers yes)
		(zone_layer_connections "In1.Cu" "In4.Cu" "In6.Cu")
		(teardrops
			(best_length_ratio 0.4)
			(max_length 1)
			(best_width_ratio 0.9)
			(max_width 2)
			(curved_edges yes)
			(filter_ratio 0.9)
			(enabled yes)
			(allow_two_segments yes)
			(prefer_zone_connections yes)
		)
		(net 1)
	)
	(via
		(at 286.45 148.81)
		(size 0.45)
		(drill 0.1)
		(layers "F.Cu" "B.Cu")
		(remove_unused_layers yes)
		(keep_end_layers yes)
		(zone_layer_connections "In1.Cu" "In4.Cu" "In6.Cu")
		(teardrops
			(best_length_ratio 0.4)
			(max_length 1)
			(best_width_ratio 0.9)
			(max_width 2)
			(curved_edges yes)
			(filter_ratio 0.9)
			(enabled yes)
			(allow_two_segments yes)
			(prefer_zone_connections yes)
		)
		(net 1)
	)
	(via
		(at 132.290002 137.86)
		(size 0.45)
		(drill 0.1)
		(layers "F.Cu" "B.Cu")
		(remove_unused_layers yes)
		(keep_end_layers yes)
		(zone_layer_connections "In1.Cu" "In4.Cu" "In6.Cu")
		(teardrops
			(best_length_ratio 0.4)
			(max_length 1)
			(best_width_ratio 0.9)
			(max_width 2)
			(curved_edges yes)
			(filter_ratio 0.9)
			(enabled yes)
			(allow_two_segments yes)
			(prefer_zone_connections yes)
		)
		(net 1)
	)
	(via
		(at 220.95 86.31)
		(size 0.45)
		(drill 0.1)
		(layers "F.Cu" "B.Cu")
		(remove_unused_layers yes)
		(keep_end_layers yes)
		(zone_layer_connections "In1.Cu" "In4.Cu" "In6.Cu")
		(teardrops
			(best_length_ratio 0.4)
			(max_length 1)
			(best_width_ratio 0.9)
			(max_width 2)
			(curved_edges yes)
			(filter_ratio 0.9)
			(enabled yes)
			(allow_two_segments yes)
			(prefer_zone_connections yes)
		)
		(net 1)
	)
	(via
		(at 181.86 90.69)
		(size 0.45)
		(drill 0.1)
		(layers "F.Cu" "B.Cu")
		(remove_unused_layers yes)
		(keep_end_layers yes)
		(zone_layer_connections "In1.Cu" "In4.Cu" "In6.Cu")
		(teardrops
			(best_length_ratio 0.4)
			(max_length 1)
			(best_width_ratio 0.9)
			(max_width 2)
			(curved_edges yes)
			(filter_ratio 0.9)
			(enabled yes)
			(allow_two_segments yes)
			(prefer_zone_connections yes)
		)
		(net 1)
	)
	(via
		(at 282.45 82.31)
		(size 0.45)
		(drill 0.1)
		(layers "F.Cu" "B.Cu")
		(remove_unused_layers yes)
		(keep_end_layers yes)
		(zone_layer_connections "In1.Cu" "In4.Cu" "In6.Cu")
		(teardrops
			(best_length_ratio 0.4)
			(max_length 1)
			(best_width_ratio 0.9)
			(max_width 2)
			(curved_edges yes)
			(filter_ratio 0.9)
			(enabled yes)
			(allow_two_segments yes)
			(prefer_zone_connections yes)
		)
		(net 1)
	)
	(via
		(at 304.197 75.04)
		(size 0.45)
		(drill 0.1)
		(layers "F.Cu" "B.Cu")
		(remove_unused_layers yes)
		(keep_end_layers yes)
		(zone_layer_connections "In1.Cu" "In4.Cu" "In6.Cu")
		(teardrops
			(best_length_ratio 0.4)
			(max_length 1)
			(best_width_ratio 0.9)
			(max_width 2)
			(curved_edges yes)
			(filter_ratio 0.9)
			(enabled yes)
			(allow_two_segments yes)
			(prefer_zone_connections yes)
		)
		(net 1)
	)
	(via
		(at 277.95 126.81)
		(size 0.45)
		(drill 0.1)
		(layers "F.Cu" "B.Cu")
		(remove_unused_layers yes)
		(keep_end_layers yes)
		(zone_layer_connections "In1.Cu" "In4.Cu" "In6.Cu")
		(teardrops
			(best_length_ratio 0.4)
			(max_length 1)
			(best_width_ratio 0.9)
			(max_width 2)
			(curved_edges yes)
			(filter_ratio 0.9)
			(enabled yes)
			(allow_two_segments yes)
			(prefer_zone_connections yes)
		)
		(net 1)
	)
	(via
		(at 160.45 154.81)
		(size 0.45)
		(drill 0.1)
		(layers "F.Cu" "B.Cu")
		(remove_unused_layers yes)
		(keep_end_layers yes)
		(zone_layer_connections "In1.Cu" "In4.Cu" "In6.Cu")
		(teardrops
			(best_length_ratio 0.4)
			(max_length 1)
			(best_width_ratio 0.9)
			(max_width 2)
			(curved_edges yes)
			(filter_ratio 0.9)
			(enabled yes)
			(allow_two_segments yes)
			(prefer_zone_connections yes)
		)
		(net 1)
	)
	(via
		(at 186.70861 78.102163)
		(size 0.45)
		(drill 0.1)
		(layers "F.Cu" "B.Cu")
		(remove_unused_layers yes)
		(keep_end_layers yes)
		(zone_layer_connections "In1.Cu" "In4.Cu" "In6.Cu")
		(teardrops
			(best_length_ratio 0.4)
			(max_length 1)
			(best_width_ratio 0.9)
			(max_width 2)
			(curved_edges yes)
			(filter_ratio 0.9)
			(enabled yes)
			(allow_two_segments yes)
			(prefer_zone_connections yes)
		)
		(net 1)
	)
	(via
		(at 285.45 107.81)
		(size 0.45)
		(drill 0.1)
		(layers "F.Cu" "B.Cu")
		(remove_unused_layers yes)
		(keep_end_layers yes)
		(zone_layer_connections "In1.Cu" "In4.Cu" "In6.Cu")
		(teardrops
			(best_length_ratio 0.4)
			(max_length 1)
			(best_width_ratio 0.9)
			(max_width 2)
			(curved_edges yes)
			(filter_ratio 0.9)
			(enabled yes)
			(allow_two_segments yes)
			(prefer_zone_connections yes)
		)
		(net 1)
	)
	(via
		(at 311.425499 133.46)
		(size 0.45)
		(drill 0.1)
		(layers "F.Cu" "B.Cu")
		(remove_unused_layers yes)
		(keep_end_layers yes)
		(zone_layer_connections "In1.Cu" "In4.Cu" "In6.Cu")
		(teardrops
			(best_length_ratio 0.4)
			(max_length 1)
			(best_width_ratio 0.9)
			(max_width 2)
			(curved_edges yes)
			(filter_ratio 0.9)
			(enabled yes)
			(allow_two_segments yes)
			(prefer_zone_connections yes)
		)
		(net 1)
	)
	(via
		(at 247.45 118.81)
		(size 0.45)
		(drill 0.1)
		(layers "F.Cu" "B.Cu")
		(remove_unused_layers yes)
		(keep_end_layers yes)
		(zone_layer_connections "In1.Cu" "In4.Cu" "In6.Cu")
		(teardrops
			(best_length_ratio 0.4)
			(max_length 1)
			(best_width_ratio 0.9)
			(max_width 2)
			(curved_edges yes)
			(filter_ratio 0.9)
			(enabled yes)
			(allow_two_segments yes)
			(prefer_zone_connections yes)
		)
		(net 1)
	)
	(via
		(at 150.25 159.75)
		(size 0.45)
		(drill 0.1)
		(layers "F.Cu" "B.Cu")
		(remove_unused_layers yes)
		(keep_end_layers yes)
		(zone_layer_connections "In1.Cu" "In4.Cu" "In6.Cu")
		(teardrops
			(best_length_ratio 0.4)
			(max_length 1)
			(best_width_ratio 0.9)
			(max_width 2)
			(curved_edges yes)
			(filter_ratio 0.9)
			(enabled yes)
			(allow_two_segments yes)
			(prefer_zone_connections yes)
		)
		(net 1)
	)
	(via
		(at 132.45 78.31)
		(size 0.45)
		(drill 0.1)
		(layers "F.Cu" "B.Cu")
		(remove_unused_layers yes)
		(keep_end_layers yes)
		(zone_layer_connections "In1.Cu" "In4.Cu" "In6.Cu")
		(teardrops
			(best_length_ratio 0.4)
			(max_length 1)
			(best_width_ratio 0.9)
			(max_width 2)
			(curved_edges yes)
			(filter_ratio 0.9)
			(enabled yes)
			(allow_two_segments yes)
			(prefer_zone_connections yes)
		)
		(net 1)
	)
	(via
		(at 286.45 142.81)
		(size 0.45)
		(drill 0.1)
		(layers "F.Cu" "B.Cu")
		(remove_unused_layers yes)
		(keep_end_layers yes)
		(zone_layer_connections "In1.Cu" "In4.Cu" "In6.Cu")
		(teardrops
			(best_length_ratio 0.4)
			(max_length 1)
			(best_width_ratio 0.9)
			(max_width 2)
			(curved_edges yes)
			(filter_ratio 0.9)
			(enabled yes)
			(allow_two_segments yes)
			(prefer_zone_connections yes)
		)
		(net 1)
	)
	(via
		(at 162.45 92.31)
		(size 0.45)
		(drill 0.1)
		(layers "F.Cu" "B.Cu")
		(remove_unused_layers yes)
		(keep_end_layers yes)
		(zone_layer_connections "In1.Cu" "In4.Cu" "In6.Cu")
		(teardrops
			(best_length_ratio 0.4)
			(max_length 1)
			(best_width_ratio 0.9)
			(max_width 2)
			(curved_edges yes)
			(filter_ratio 0.9)
			(enabled yes)
			(allow_two_segments yes)
			(prefer_zone_connections yes)
		)
		(net 1)
	)
	(via
		(at 221.95 122.81)
		(size 0.45)
		(drill 0.1)
		(layers "F.Cu" "B.Cu")
		(remove_unused_layers yes)
		(keep_end_layers yes)
		(zone_layer_connections "In1.Cu" "In4.Cu" "In6.Cu")
		(teardrops
			(best_length_ratio 0.4)
			(max_length 1)
			(best_width_ratio 0.9)
			(max_width 2)
			(curved_edges yes)
			(filter_ratio 0.9)
			(enabled yes)
			(allow_two_segments yes)
			(prefer_zone_connections yes)
		)
		(net 1)
	)
	(via
		(at 216.1 123)
		(size 0.45)
		(drill 0.1)
		(layers "F.Cu" "B.Cu")
		(remove_unused_layers yes)
		(keep_end_layers yes)
		(zone_layer_connections "In1.Cu" "In4.Cu" "In6.Cu")
		(teardrops
			(best_length_ratio 0.4)
			(max_length 1)
			(best_width_ratio 0.9)
			(max_width 2)
			(curved_edges yes)
			(filter_ratio 0.9)
			(enabled yes)
			(allow_two_segments yes)
			(prefer_zone_connections yes)
		)
		(net 1)
	)
	(via
		(at 253.45 115.81)
		(size 0.45)
		(drill 0.1)
		(layers "F.Cu" "B.Cu")
		(remove_unused_layers yes)
		(keep_end_layers yes)
		(zone_layer_connections "In1.Cu" "In4.Cu" "In6.Cu")
		(teardrops
			(best_length_ratio 0.4)
			(max_length 1)
			(best_width_ratio 0.9)
			(max_width 2)
			(curved_edges yes)
			(filter_ratio 0.9)
			(enabled yes)
			(allow_two_segments yes)
			(prefer_zone_connections yes)
		)
		(net 1)
	)
	(via
		(at 222 157.8)
		(size 0.45)
		(drill 0.1)
		(layers "F.Cu" "B.Cu")
		(teardrops
			(best_length_ratio 0.4)
			(max_length 1)
			(best_width_ratio 0.9)
			(max_width 2)
			(curved_edges yes)
			(filter_ratio 0.9)
			(enabled yes)
			(allow_two_segments yes)
			(prefer_zone_connections yes)
		)
		(net 1)
	)
	(via
		(at 156.45 135.86)
		(size 0.45)
		(drill 0.1)
		(layers "F.Cu" "B.Cu")
		(remove_unused_layers yes)
		(keep_end_layers yes)
		(zone_layer_connections "In1.Cu" "In4.Cu" "In6.Cu")
		(teardrops
			(best_length_ratio 0.4)
			(max_length 1)
			(best_width_ratio 0.9)
			(max_width 2)
			(curved_edges yes)
			(filter_ratio 0.9)
			(enabled yes)
			(allow_two_segments yes)
			(prefer_zone_connections yes)
		)
		(net 1)
	)
	(via
		(at 144.323613 143.478366)
		(size 0.45)
		(drill 0.1)
		(layers "F.Cu" "B.Cu")
		(remove_unused_layers yes)
		(keep_end_layers yes)
		(zone_layer_connections "In1.Cu" "In4.Cu" "In6.Cu")
		(teardrops
			(best_length_ratio 0.4)
			(max_length 1)
			(best_width_ratio 0.9)
			(max_width 2)
			(curved_edges yes)
			(filter_ratio 0.9)
			(enabled yes)
			(allow_two_segments yes)
			(prefer_zone_connections yes)
		)
		(net 1)
	)
	(via
		(at 259.45 96.31)
		(size 0.45)
		(drill 0.1)
		(layers "F.Cu" "B.Cu")
		(remove_unused_layers yes)
		(keep_end_layers yes)
		(zone_layer_connections "In1.Cu" "In4.Cu" "In6.Cu")
		(teardrops
			(best_length_ratio 0.4)
			(max_length 1)
			(best_width_ratio 0.9)
			(max_width 2)
			(curved_edges yes)
			(filter_ratio 0.9)
			(enabled yes)
			(allow_two_segments yes)
			(prefer_zone_connections yes)
		)
		(net 1)
	)
	(via
		(at 159.45 154.81)
		(size 0.45)
		(drill 0.1)
		(layers "F.Cu" "B.Cu")
		(remove_unused_layers yes)
		(keep_end_layers yes)
		(zone_layer_connections "In1.Cu" "In4.Cu" "In6.Cu")
		(teardrops
			(best_length_ratio 0.4)
			(max_length 1)
			(best_width_ratio 0.9)
			(max_width 2)
			(curved_edges yes)
			(filter_ratio 0.9)
			(enabled yes)
			(allow_two_segments yes)
			(prefer_zone_connections yes)
		)
		(net 1)
	)
	(via
		(at 277.95 115.31)
		(size 0.45)
		(drill 0.1)
		(layers "F.Cu" "B.Cu")
		(remove_unused_layers yes)
		(keep_end_layers yes)
		(zone_layer_connections "In1.Cu" "In4.Cu" "In6.Cu")
		(teardrops
			(best_length_ratio 0.4)
			(max_length 1)
			(best_width_ratio 0.9)
			(max_width 2)
			(curved_edges yes)
			(filter_ratio 0.9)
			(enabled yes)
			(allow_two_segments yes)
			(prefer_zone_connections yes)
		)
		(net 1)
	)
	(via
		(at 158.55 156.33)
		(size 0.45)
		(drill 0.1)
		(layers "F.Cu" "B.Cu")
		(remove_unused_layers yes)
		(keep_end_layers yes)
		(zone_layer_connections "In1.Cu" "In4.Cu" "In6.Cu")
		(teardrops
			(best_length_ratio 0.4)
			(max_length 1)
			(best_width_ratio 0.9)
			(max_width 2)
			(curved_edges yes)
			(filter_ratio 0.9)
			(enabled yes)
			(allow_two_segments yes)
			(prefer_zone_connections yes)
		)
		(net 1)
	)
	(via
		(at 310.714501 95.1365)
		(size 0.45)
		(drill 0.1)
		(layers "F.Cu" "B.Cu")
		(remove_unused_layers yes)
		(keep_end_layers yes)
		(zone_layer_connections "In1.Cu" "In4.Cu" "In6.Cu")
		(teardrops
			(best_length_ratio 0.4)
			(max_length 1)
			(best_width_ratio 0.9)
			(max_width 2)
			(curved_edges yes)
			(filter_ratio 0.9)
			(enabled yes)
			(allow_two_segments yes)
			(prefer_zone_connections yes)
		)
		(net 1)
	)
	(via
		(at 243.57 126.71)
		(size 0.45)
		(drill 0.1)
		(layers "F.Cu" "B.Cu")
		(remove_unused_layers yes)
		(keep_end_layers yes)
		(zone_layer_connections "In1.Cu" "In4.Cu" "In6.Cu")
		(teardrops
			(best_length_ratio 0.4)
			(max_length 1)
			(best_width_ratio 0.9)
			(max_width 2)
			(curved_edges yes)
			(filter_ratio 0.9)
			(enabled yes)
			(allow_two_segments yes)
			(prefer_zone_connections yes)
		)
		(net 1)
	)
	(via
		(at 197.4 170.2)
		(size 0.45)
		(drill 0.1)
		(layers "F.Cu" "B.Cu")
		(teardrops
			(best_length_ratio 0.4)
			(max_length 1)
			(best_width_ratio 0.9)
			(max_width 2)
			(curved_edges yes)
			(filter_ratio 0.9)
			(enabled yes)
			(allow_two_segments yes)
			(prefer_zone_connections yes)
		)
		(net 1)
	)
	(via
		(at 251.95 114.31)
		(size 0.45)
		(drill 0.1)
		(layers "F.Cu" "B.Cu")
		(remove_unused_layers yes)
		(keep_end_layers yes)
		(zone_layer_connections "In1.Cu" "In4.Cu" "In6.Cu")
		(teardrops
			(best_length_ratio 0.4)
			(max_length 1)
			(best_width_ratio 0.9)
			(max_width 2)
			(curved_edges yes)
			(filter_ratio 0.9)
			(enabled yes)
			(allow_two_segments yes)
			(prefer_zone_connections yes)
		)
		(net 1)
	)
	(via
		(at 257.95 117.31)
		(size 0.45)
		(drill 0.1)
		(layers "F.Cu" "B.Cu")
		(remove_unused_layers yes)
		(keep_end_layers yes)
		(zone_layer_connections "In1.Cu" "In4.Cu" "In6.Cu")
		(teardrops
			(best_length_ratio 0.4)
			(max_length 1)
			(best_width_ratio 0.9)
			(max_width 2)
			(curved_edges yes)
			(filter_ratio 0.9)
			(enabled yes)
			(allow_two_segments yes)
			(prefer_zone_connections yes)
		)
		(net 1)
	)
	(via
		(at 294.95 130.31)
		(size 0.45)
		(drill 0.1)
		(layers "F.Cu" "B.Cu")
		(remove_unused_layers yes)
		(keep_end_layers yes)
		(zone_layer_connections "In1.Cu" "In4.Cu" "In6.Cu")
		(teardrops
			(best_length_ratio 0.4)
			(max_length 1)
			(best_width_ratio 0.9)
			(max_width 2)
			(curved_edges yes)
			(filter_ratio 0.9)
			(enabled yes)
			(allow_two_segments yes)
			(prefer_zone_connections yes)
		)
		(net 1)
	)
	(via
		(at 176 161.7)
		(size 0.45)
		(drill 0.1)
		(layers "F.Cu" "B.Cu")
		(teardrops
			(best_length_ratio 0.4)
			(max_length 1)
			(best_width_ratio 0.9)
			(max_width 2)
			(curved_edges yes)
			(filter_ratio 0.9)
			(enabled yes)
			(allow_two_segments yes)
			(prefer_zone_connections yes)
		)
		(net 1)
	)
	(via
		(at 135.29 140.86)
		(size 0.45)
		(drill 0.1)
		(layers "F.Cu" "B.Cu")
		(remove_unused_layers yes)
		(keep_end_layers yes)
		(zone_layer_connections "In1.Cu" "In4.Cu" "In6.Cu")
		(teardrops
			(best_length_ratio 0.4)
			(max_length 1)
			(best_width_ratio 0.9)
			(max_width 2)
			(curved_edges yes)
			(filter_ratio 0.9)
			(enabled yes)
			(allow_two_segments yes)
			(prefer_zone_connections yes)
		)
		(net 1)
	)
	(via
		(at 193.95 80.81)
		(size 0.45)
		(drill 0.1)
		(layers "F.Cu" "B.Cu")
		(remove_unused_layers yes)
		(keep_end_layers yes)
		(free yes)
		(zone_layer_connections "In1.Cu" "In4.Cu" "In6.Cu")
		(teardrops
			(best_length_ratio 0.4)
			(max_length 1)
			(best_width_ratio 0.9)
			(max_width 2)
			(curved_edges yes)
			(filter_ratio 0.9)
			(enabled yes)
			(allow_two_segments yes)
			(prefer_zone_connections yes)
		)
		(net 1)
	)
	(via
		(at 268.7 141.6)
		(size 0.45)
		(drill 0.1)
		(layers "F.Cu" "B.Cu")
		(remove_unused_layers yes)
		(keep_end_layers yes)
		(zone_layer_connections "In1.Cu" "In4.Cu" "In6.Cu")
		(teardrops
			(best_length_ratio 0.4)
			(max_length 1)
			(best_width_ratio 0.9)
			(max_width 2)
			(curved_edges yes)
			(filter_ratio 0.9)
			(enabled yes)
			(allow_two_segments yes)
			(prefer_zone_connections yes)
		)
		(net 1)
	)
	(via
		(at 133.95 158.81)
		(size 0.45)
		(drill 0.1)
		(layers "F.Cu" "B.Cu")
		(remove_unused_layers yes)
		(keep_end_layers yes)
		(zone_layer_connections "In1.Cu" "In4.Cu" "In6.Cu")
		(teardrops
			(best_length_ratio 0.4)
			(max_length 1)
			(best_width_ratio 0.9)
			(max_width 2)
			(curved_edges yes)
			(filter_ratio 0.9)
			(enabled yes)
			(allow_two_segments yes)
			(prefer_zone_connections yes)
		)
		(net 1)
	)
	(via
		(at 183.64 113.53)
		(size 0.45)
		(drill 0.1)
		(layers "F.Cu" "B.Cu")
		(remove_unused_layers yes)
		(keep_end_layers yes)
		(zone_layer_connections "In1.Cu" "In4.Cu" "In6.Cu")
		(teardrops
			(best_length_ratio 0.4)
			(max_length 1)
			(best_width_ratio 0.9)
			(max_width 2)
			(curved_edges yes)
			(filter_ratio 0.9)
			(enabled yes)
			(allow_two_segments yes)
			(prefer_zone_connections yes)
		)
		(net 1)
	)
	(via
		(at 245.95 114.31)
		(size 0.45)
		(drill 0.1)
		(layers "F.Cu" "B.Cu")
		(remove_unused_layers yes)
		(keep_end_layers yes)
		(free yes)
		(zone_layer_connections "In1.Cu" "In4.Cu" "In6.Cu")
		(teardrops
			(best_length_ratio 0.4)
			(max_length 1)
			(best_width_ratio 0.9)
			(max_width 2)
			(curved_edges yes)
			(filter_ratio 0.9)
			(enabled yes)
			(allow_two_segments yes)
			(prefer_zone_connections yes)
		)
		(net 1)
	)
	(via
		(at 119.45 96.31)
		(size 0.45)
		(drill 0.1)
		(layers "F.Cu" "B.Cu")
		(remove_unused_layers yes)
		(keep_end_layers yes)
		(zone_layer_connections "In1.Cu" "In4.Cu" "In6.Cu")
		(teardrops
			(best_length_ratio 0.4)
			(max_length 1)
			(best_width_ratio 0.9)
			(max_width 2)
			(curved_edges yes)
			(filter_ratio 0.9)
			(enabled yes)
			(allow_two_segments yes)
			(prefer_zone_connections yes)
		)
		(net 1)
	)
	(via
		(at 297.95 106.81)
		(size 0.45)
		(drill 0.1)
		(layers "F.Cu" "B.Cu")
		(remove_unused_layers yes)
		(keep_end_layers yes)
		(zone_layer_connections "In1.Cu" "In4.Cu" "In6.Cu")
		(teardrops
			(best_length_ratio 0.4)
			(max_length 1)
			(best_width_ratio 0.9)
			(max_width 2)
			(curved_edges yes)
			(filter_ratio 0.9)
			(enabled yes)
			(allow_two_segments yes)
			(prefer_zone_connections yes)
		)
		(net 1)
	)
	(via
		(at 191.025 167.5)
		(size 0.45)
		(drill 0.1)
		(layers "F.Cu" "B.Cu")
		(teardrops
			(best_length_ratio 0.4)
			(max_length 1)
			(best_width_ratio 0.9)
			(max_width 2)
			(curved_edges yes)
			(filter_ratio 0.9)
			(enabled yes)
			(allow_two_segments yes)
			(prefer_zone_connections yes)
		)
		(net 1)
	)
	(via
		(at 228.45 90.81)
		(size 0.45)
		(drill 0.1)
		(layers "F.Cu" "B.Cu")
		(remove_unused_layers yes)
		(keep_end_layers yes)
		(zone_layer_connections "In1.Cu" "In4.Cu" "In6.Cu")
		(teardrops
			(best_length_ratio 0.4)
			(max_length 1)
			(best_width_ratio 0.9)
			(max_width 2)
			(curved_edges yes)
			(filter_ratio 0.9)
			(enabled yes)
			(allow_two_segments yes)
			(prefer_zone_connections yes)
		)
		(net 1)
	)
	(via
		(at 233.4 167.2)
		(size 0.45)
		(drill 0.1)
		(layers "F.Cu" "B.Cu")
		(teardrops
			(best_length_ratio 0.4)
			(max_length 1)
			(best_width_ratio 0.9)
			(max_width 2)
			(curved_edges yes)
			(filter_ratio 0.9)
			(enabled yes)
			(allow_two_segments yes)
			(prefer_zone_connections yes)
		)
		(net 1)
	)
	(via
		(at 156.45 141.86)
		(size 0.45)
		(drill 0.1)
		(layers "F.Cu" "B.Cu")
		(remove_unused_layers yes)
		(keep_end_layers yes)
		(zone_layer_connections "In1.Cu" "In4.Cu" "In6.Cu")
		(teardrops
			(best_length_ratio 0.4)
			(max_length 1)
			(best_width_ratio 0.9)
			(max_width 2)
			(curved_edges yes)
			(filter_ratio 0.9)
			(enabled yes)
			(allow_two_segments yes)
			(prefer_zone_connections yes)
		)
		(net 1)
	)
	(via
		(at 126.95 154.81)
		(size 0.45)
		(drill 0.1)
		(layers "F.Cu" "B.Cu")
		(remove_unused_layers yes)
		(keep_end_layers yes)
		(zone_layer_connections "In1.Cu" "In4.Cu" "In6.Cu")
		(teardrops
			(best_length_ratio 0.4)
			(max_length 1)
			(best_width_ratio 0.9)
			(max_width 2)
			(curved_edges yes)
			(filter_ratio 0.9)
			(enabled yes)
			(allow_two_segments yes)
			(prefer_zone_connections yes)
		)
		(net 1)
	)
	(via
		(at 189.75 165.55)
		(size 0.45)
		(drill 0.1)
		(layers "F.Cu" "B.Cu")
		(teardrops
			(best_length_ratio 0.4)
			(max_length 1)
			(best_width_ratio 0.9)
			(max_width 2)
			(curved_edges yes)
			(filter_ratio 0.9)
			(enabled yes)
			(allow_two_segments yes)
			(prefer_zone_connections yes)
		)
		(net 1)
	)
	(via
		(at 296.45 111.31)
		(size 0.45)
		(drill 0.1)
		(layers "F.Cu" "B.Cu")
		(remove_unused_layers yes)
		(keep_end_layers yes)
		(zone_layer_connections "In1.Cu" "In4.Cu" "In6.Cu")
		(teardrops
			(best_length_ratio 0.4)
			(max_length 1)
			(best_width_ratio 0.9)
			(max_width 2)
			(curved_edges yes)
			(filter_ratio 0.9)
			(enabled yes)
			(allow_two_segments yes)
			(prefer_zone_connections yes)
		)
		(net 1)
	)
	(via
		(at 152.5685 83.5595)
		(size 0.45)
		(drill 0.1)
		(layers "F.Cu" "B.Cu")
		(remove_unused_layers yes)
		(keep_end_layers yes)
		(zone_layer_connections "In1.Cu" "In4.Cu" "In6.Cu")
		(teardrops
			(best_length_ratio 0.4)
			(max_length 1)
			(best_width_ratio 0.9)
			(max_width 2)
			(curved_edges yes)
			(filter_ratio 0.9)
			(enabled yes)
			(allow_two_segments yes)
			(prefer_zone_connections yes)
		)
		(net 1)
	)
	(via
		(at 104.111432 106.154827)
		(size 0.45)
		(drill 0.1)
		(layers "F.Cu" "B.Cu")
		(remove_unused_layers yes)
		(keep_end_layers yes)
		(zone_layer_connections "In1.Cu" "In4.Cu" "In6.Cu")
		(teardrops
			(best_length_ratio 0.4)
			(max_length 1)
			(best_width_ratio 0.9)
			(max_width 2)
			(curved_edges yes)
			(filter_ratio 0.9)
			(enabled yes)
			(allow_two_segments yes)
			(prefer_zone_connections yes)
		)
		(net 1)
	)
	(via
		(at 95.45 157.31)
		(size 0.45)
		(drill 0.1)
		(layers "F.Cu" "B.Cu")
		(remove_unused_layers yes)
		(keep_end_layers yes)
		(zone_layer_connections "In1.Cu" "In4.Cu" "In6.Cu")
		(teardrops
			(best_length_ratio 0.4)
			(max_length 1)
			(best_width_ratio 0.9)
			(max_width 2)
			(curved_edges yes)
			(filter_ratio 0.9)
			(enabled yes)
			(allow_two_segments yes)
			(prefer_zone_connections yes)
		)
		(net 1)
	)
	(via
		(at 158.38 138.36)
		(size 0.45)
		(drill 0.1)
		(layers "F.Cu" "B.Cu")
		(remove_unused_layers yes)
		(keep_end_layers yes)
		(zone_layer_connections "In1.Cu" "In4.Cu" "In6.Cu")
		(teardrops
			(best_length_ratio 0.4)
			(max_length 1)
			(best_width_ratio 0.9)
			(max_width 2)
			(curved_edges yes)
			(filter_ratio 0.9)
			(enabled yes)
			(allow_two_segments yes)
			(prefer_zone_connections yes)
		)
		(net 1)
	)
	(via
		(at 233.4 155.2)
		(size 0.45)
		(drill 0.1)
		(layers "F.Cu" "B.Cu")
		(teardrops
			(best_length_ratio 0.4)
			(max_length 1)
			(best_width_ratio 0.9)
			(max_width 2)
			(curved_edges yes)
			(filter_ratio 0.9)
			(enabled yes)
			(allow_two_segments yes)
			(prefer_zone_connections yes)
		)
		(net 1)
	)
	(via
		(at 95.449999 170.81)
		(size 0.45)
		(drill 0.1)
		(layers "F.Cu" "B.Cu")
		(remove_unused_layers yes)
		(keep_end_layers yes)
		(zone_layer_connections "In1.Cu" "In4.Cu" "In6.Cu")
		(teardrops
			(best_length_ratio 0.4)
			(max_length 1)
			(best_width_ratio 0.9)
			(max_width 2)
			(curved_edges yes)
			(filter_ratio 0.9)
			(enabled yes)
			(allow_two_segments yes)
			(prefer_zone_connections yes)
		)
		(net 1)
	)
	(via
		(at 318.95 86.31)
		(size 0.45)
		(drill 0.1)
		(layers "F.Cu" "B.Cu")
		(remove_unused_layers yes)
		(keep_end_layers yes)
		(zone_layer_connections "In1.Cu" "In4.Cu" "In6.Cu")
		(teardrops
			(best_length_ratio 0.4)
			(max_length 1)
			(best_width_ratio 0.9)
			(max_width 2)
			(curved_edges yes)
			(filter_ratio 0.9)
			(enabled yes)
			(allow_two_segments yes)
			(prefer_zone_connections yes)
		)
		(net 1)
	)
	(via
		(at 230.6 144.9)
		(size 0.45)
		(drill 0.1)
		(layers "F.Cu" "B.Cu")
		(teardrops
			(best_length_ratio 0.4)
			(max_length 1)
			(best_width_ratio 0.9)
			(max_width 2)
			(curved_edges yes)
			(filter_ratio 0.9)
			(enabled yes)
			(allow_two_segments yes)
			(prefer_zone_connections yes)
		)
		(net 1)
	)
	(via
		(at 213.45 161.8)
		(size 0.45)
		(drill 0.1)
		(layers "F.Cu" "B.Cu")
		(teardrops
			(best_length_ratio 0.4)
			(max_length 1)
			(best_width_ratio 0.9)
			(max_width 2)
			(curved_edges yes)
			(filter_ratio 0.9)
			(enabled yes)
			(allow_two_segments yes)
			(prefer_zone_connections yes)
		)
		(net 1)
	)
	(via
		(at 215.55 149.921)
		(size 0.45)
		(drill 0.1)
		(layers "F.Cu" "B.Cu")
		(teardrops
			(best_length_ratio 0.4)
			(max_length 1)
			(best_width_ratio 0.9)
			(max_width 2)
			(curved_edges yes)
			(filter_ratio 0.9)
			(enabled yes)
			(allow_two_segments yes)
			(prefer_zone_connections yes)
		)
		(net 1)
	)
	(via
		(at 314.4645 100.6365)
		(size 0.45)
		(drill 0.1)
		(layers "F.Cu" "B.Cu")
		(remove_unused_layers yes)
		(keep_end_layers yes)
		(free yes)
		(zone_layer_connections "In1.Cu" "In4.Cu" "In6.Cu")
		(teardrops
			(best_length_ratio 0.4)
			(max_length 1)
			(best_width_ratio 0.9)
			(max_width 2)
			(curved_edges yes)
			(filter_ratio 0.9)
			(enabled yes)
			(allow_two_segments yes)
			(prefer_zone_connections yes)
		)
		(net 1)
	)
	(via
		(at 190.95 70.31)
		(size 0.45)
		(drill 0.1)
		(layers "F.Cu" "B.Cu")
		(remove_unused_layers yes)
		(keep_end_layers yes)
		(free yes)
		(zone_layer_connections "In1.Cu" "In4.Cu" "In6.Cu")
		(teardrops
			(best_length_ratio 0.4)
			(max_length 1)
			(best_width_ratio 0.9)
			(max_width 2)
			(curved_edges yes)
			(filter_ratio 0.9)
			(enabled yes)
			(allow_two_segments yes)
			(prefer_zone_connections yes)
		)
		(net 1)
	)
	(via
		(at 122.173342 164.23)
		(size 0.45)
		(drill 0.1)
		(layers "F.Cu" "B.Cu")
		(remove_unused_layers yes)
		(keep_end_layers yes)
		(zone_layer_connections "In1.Cu" "In4.Cu" "In6.Cu")
		(teardrops
			(best_length_ratio 0.4)
			(max_length 1)
			(best_width_ratio 0.9)
			(max_width 2)
			(curved_edges yes)
			(filter_ratio 0.9)
			(enabled yes)
			(allow_two_segments yes)
			(prefer_zone_connections yes)
		)
		(net 1)
	)
	(via
		(at 134.45 169.81)
		(size 0.45)
		(drill 0.1)
		(layers "F.Cu" "B.Cu")
		(remove_unused_layers yes)
		(keep_end_layers yes)
		(zone_layer_connections "In1.Cu" "In4.Cu" "In6.Cu")
		(teardrops
			(best_length_ratio 0.4)
			(max_length 1)
			(best_width_ratio 0.9)
			(max_width 2)
			(curved_edges yes)
			(filter_ratio 0.9)
			(enabled yes)
			(allow_two_segments yes)
			(prefer_zone_connections yes)
		)
		(net 1)
	)
	(via
		(at 96.591069 104.996964)
		(size 0.45)
		(drill 0.1)
		(layers "F.Cu" "B.Cu")
		(remove_unused_layers yes)
		(keep_end_layers yes)
		(zone_layer_connections "In1.Cu" "In4.Cu" "In6.Cu")
		(teardrops
			(best_length_ratio 0.4)
			(max_length 1)
			(best_width_ratio 0.9)
			(max_width 2)
			(curved_edges yes)
			(filter_ratio 0.9)
			(enabled yes)
			(allow_two_segments yes)
			(prefer_zone_connections yes)
		)
		(net 1)
	)
	(via
		(at 234.95 114.31)
		(size 0.45)
		(drill 0.1)
		(layers "F.Cu" "B.Cu")
		(remove_unused_layers yes)
		(keep_end_layers yes)
		(zone_layer_connections "In1.Cu" "In4.Cu" "In6.Cu")
		(teardrops
			(best_length_ratio 0.4)
			(max_length 1)
			(best_width_ratio 0.9)
			(max_width 2)
			(curved_edges yes)
			(filter_ratio 0.9)
			(enabled yes)
			(allow_two_segments yes)
			(prefer_zone_connections yes)
		)
		(net 1)
	)
	(via
		(at 239.95 120.31)
		(size 0.45)
		(drill 0.1)
		(layers "F.Cu" "B.Cu")
		(remove_unused_layers yes)
		(keep_end_layers yes)
		(zone_layer_connections "In1.Cu" "In4.Cu" "In6.Cu")
		(teardrops
			(best_length_ratio 0.4)
			(max_length 1)
			(best_width_ratio 0.9)
			(max_width 2)
			(curved_edges yes)
			(filter_ratio 0.9)
			(enabled yes)
			(allow_two_segments yes)
			(prefer_zone_connections yes)
		)
		(net 1)
	)
	(via
		(at 96.8 148.1)
		(size 0.45)
		(drill 0.1)
		(layers "F.Cu" "B.Cu")
		(remove_unused_layers yes)
		(keep_end_layers yes)
		(zone_layer_connections "In1.Cu" "In4.Cu" "In6.Cu")
		(teardrops
			(best_length_ratio 0.4)
			(max_length 1)
			(best_width_ratio 0.9)
			(max_width 2)
			(curved_edges yes)
			(filter_ratio 0.9)
			(enabled yes)
			(allow_two_segments yes)
			(prefer_zone_connections yes)
		)
		(net 1)
	)
	(via
		(at 315.489499 135.71)
		(size 0.45)
		(drill 0.1)
		(layers "F.Cu" "B.Cu")
		(remove_unused_layers yes)
		(keep_end_layers yes)
		(zone_layer_connections "In1.Cu" "In4.Cu" "In6.Cu")
		(teardrops
			(best_length_ratio 0.4)
			(max_length 1)
			(best_width_ratio 0.9)
			(max_width 2)
			(curved_edges yes)
			(filter_ratio 0.9)
			(enabled yes)
			(allow_two_segments yes)
			(prefer_zone_connections yes)
		)
		(net 1)
	)
	(via
		(at 225.45 78.11)
		(size 0.45)
		(drill 0.1)
		(layers "F.Cu" "B.Cu")
		(remove_unused_layers yes)
		(keep_end_layers yes)
		(zone_layer_connections "In1.Cu" "In4.Cu" "In6.Cu")
		(teardrops
			(best_length_ratio 0.4)
			(max_length 1)
			(best_width_ratio 0.9)
			(max_width 2)
			(curved_edges yes)
			(filter_ratio 0.9)
			(enabled yes)
			(allow_two_segments yes)
			(prefer_zone_connections yes)
		)
		(net 1)
	)
	(via
		(at 96.95 101.81)
		(size 0.45)
		(drill 0.1)
		(layers "F.Cu" "B.Cu")
		(remove_unused_layers yes)
		(keep_end_layers yes)
		(zone_layer_connections "In1.Cu" "In4.Cu" "In6.Cu")
		(teardrops
			(best_length_ratio 0.4)
			(max_length 1)
			(best_width_ratio 0.9)
			(max_width 2)
			(curved_edges yes)
			(filter_ratio 0.9)
			(enabled yes)
			(allow_two_segments yes)
			(prefer_zone_connections yes)
		)
		(net 1)
	)
	(via
		(at 229.2 143.5)
		(size 0.45)
		(drill 0.1)
		(layers "F.Cu" "B.Cu")
		(teardrops
			(best_length_ratio 0.4)
			(max_length 1)
			(best_width_ratio 0.9)
			(max_width 2)
			(curved_edges yes)
			(filter_ratio 0.9)
			(enabled yes)
			(allow_two_segments yes)
			(prefer_zone_connections yes)
		)
		(net 1)
	)
	(via
		(at 110.95 74.31)
		(size 0.45)
		(drill 0.1)
		(layers "F.Cu" "B.Cu")
		(remove_unused_layers yes)
		(keep_end_layers yes)
		(zone_layer_connections "In1.Cu" "In4.Cu" "In6.Cu")
		(teardrops
			(best_length_ratio 0.4)
			(max_length 1)
			(best_width_ratio 0.9)
			(max_width 2)
			(curved_edges yes)
			(filter_ratio 0.9)
			(enabled yes)
			(allow_two_segments yes)
			(prefer_zone_connections yes)
		)
		(net 1)
	)
	(via
		(at 117.45 69.16)
		(size 0.45)
		(drill 0.1)
		(layers "F.Cu" "B.Cu")
		(remove_unused_layers yes)
		(keep_end_layers yes)
		(zone_layer_connections "In1.Cu" "In4.Cu" "In6.Cu")
		(teardrops
			(best_length_ratio 0.4)
			(max_length 1)
			(best_width_ratio 0.9)
			(max_width 2)
			(curved_edges yes)
			(filter_ratio 0.9)
			(enabled yes)
			(allow_two_segments yes)
			(prefer_zone_connections yes)
		)
		(net 1)
	)
	(via
		(at 121.95 95.31)
		(size 0.45)
		(drill 0.1)
		(layers "F.Cu" "B.Cu")
		(remove_unused_layers yes)
		(keep_end_layers yes)
		(zone_layer_connections "In1.Cu" "In4.Cu" "In6.Cu")
		(teardrops
			(best_length_ratio 0.4)
			(max_length 1)
			(best_width_ratio 0.9)
			(max_width 2)
			(curved_edges yes)
			(filter_ratio 0.9)
			(enabled yes)
			(allow_two_segments yes)
			(prefer_zone_connections yes)
		)
		(net 1)
	)
	(via
		(at 197.70861 78.102163)
		(size 0.45)
		(drill 0.1)
		(layers "F.Cu" "B.Cu")
		(remove_unused_layers yes)
		(keep_end_layers yes)
		(zone_layer_connections "In1.Cu" "In4.Cu" "In6.Cu")
		(teardrops
			(best_length_ratio 0.4)
			(max_length 1)
			(best_width_ratio 0.9)
			(max_width 2)
			(curved_edges yes)
			(filter_ratio 0.9)
			(enabled yes)
			(allow_two_segments yes)
			(prefer_zone_connections yes)
		)
		(net 1)
	)
	(via
		(at 135.45 170.81)
		(size 0.45)
		(drill 0.1)
		(layers "F.Cu" "B.Cu")
		(remove_unused_layers yes)
		(keep_end_layers yes)
		(zone_layer_connections "In1.Cu" "In4.Cu" "In6.Cu")
		(teardrops
			(best_length_ratio 0.4)
			(max_length 1)
			(best_width_ratio 0.9)
			(max_width 2)
			(curved_edges yes)
			(filter_ratio 0.9)
			(enabled yes)
			(allow_two_segments yes)
			(prefer_zone_connections yes)
		)
		(net 1)
	)
	(via
		(at 95.45 142.81)
		(size 0.45)
		(drill 0.1)
		(layers "F.Cu" "B.Cu")
		(remove_unused_layers yes)
		(keep_end_layers yes)
		(zone_layer_connections "In1.Cu" "In4.Cu" "In6.Cu")
		(teardrops
			(best_length_ratio 0.4)
			(max_length 1)
			(best_width_ratio 0.9)
			(max_width 2)
			(curved_edges yes)
			(filter_ratio 0.9)
			(enabled yes)
			(allow_two_segments yes)
			(prefer_zone_connections yes)
		)
		(net 1)
	)
	(via
		(at 213.5 167.5)
		(size 0.45)
		(drill 0.1)
		(layers "F.Cu" "B.Cu")
		(teardrops
			(best_length_ratio 0.4)
			(max_length 1)
			(best_width_ratio 0.9)
			(max_width 2)
			(curved_edges yes)
			(filter_ratio 0.9)
			(enabled yes)
			(allow_two_segments yes)
			(prefer_zone_connections yes)
		)
		(net 1)
	)
	(via
		(at 281.95 141.31)
		(size 0.45)
		(drill 0.1)
		(layers "F.Cu" "B.Cu")
		(remove_unused_layers yes)
		(keep_end_layers yes)
		(zone_layer_connections "In1.Cu" "In4.Cu" "In6.Cu")
		(teardrops
			(best_length_ratio 0.4)
			(max_length 1)
			(best_width_ratio 0.9)
			(max_width 2)
			(curved_edges yes)
			(filter_ratio 0.9)
			(enabled yes)
			(allow_two_segments yes)
			(prefer_zone_connections yes)
		)
		(net 1)
	)
	(via
		(at 134.29 134.86)
		(size 0.45)
		(drill 0.1)
		(layers "F.Cu" "B.Cu")
		(remove_unused_layers yes)
		(keep_end_layers yes)
		(zone_layer_connections "In1.Cu" "In4.Cu" "In6.Cu")
		(teardrops
			(best_length_ratio 0.4)
			(max_length 1)
			(best_width_ratio 0.9)
			(max_width 2)
			(curved_edges yes)
			(filter_ratio 0.9)
			(enabled yes)
			(allow_two_segments yes)
			(prefer_zone_connections yes)
		)
		(net 1)
	)
	(via
		(at 172.45 82.31)
		(size 0.45)
		(drill 0.1)
		(layers "F.Cu" "B.Cu")
		(remove_unused_layers yes)
		(keep_end_layers yes)
		(zone_layer_connections "In1.Cu" "In4.Cu" "In6.Cu")
		(teardrops
			(best_length_ratio 0.4)
			(max_length 1)
			(best_width_ratio 0.9)
			(max_width 2)
			(curved_edges yes)
			(filter_ratio 0.9)
			(enabled yes)
			(allow_two_segments yes)
			(prefer_zone_connections yes)
		)
		(net 1)
	)
	(via
		(at 312.194641 167.964452)
		(size 0.45)
		(drill 0.1)
		(layers "F.Cu" "B.Cu")
		(remove_unused_layers yes)
		(keep_end_layers yes)
		(zone_layer_connections "In1.Cu" "In4.Cu" "In6.Cu")
		(teardrops
			(best_length_ratio 0.4)
			(max_length 1)
			(best_width_ratio 0.9)
			(max_width 2)
			(curved_edges yes)
			(filter_ratio 0.9)
			(enabled yes)
			(allow_two_segments yes)
			(prefer_zone_connections yes)
		)
		(net 1)
	)
	(via
		(at 138.95 83.81)
		(size 0.45)
		(drill 0.1)
		(layers "F.Cu" "B.Cu")
		(remove_unused_layers yes)
		(keep_end_layers yes)
		(zone_layer_connections "In1.Cu" "In4.Cu" "In6.Cu")
		(teardrops
			(best_length_ratio 0.4)
			(max_length 1)
			(best_width_ratio 0.9)
			(max_width 2)
			(curved_edges yes)
			(filter_ratio 0.9)
			(enabled yes)
			(allow_two_segments yes)
			(prefer_zone_connections yes)
		)
		(net 1)
	)
	(via
		(at 176.6 155.5)
		(size 0.45)
		(drill 0.1)
		(layers "F.Cu" "B.Cu")
		(teardrops
			(best_length_ratio 0.4)
			(max_length 1)
			(best_width_ratio 0.9)
			(max_width 2)
			(curved_edges yes)
			(filter_ratio 0.9)
			(enabled yes)
			(allow_two_segments yes)
			(prefer_zone_connections yes)
		)
		(net 1)
	)
	(via
		(at 241.45 121.81)
		(size 0.45)
		(drill 0.1)
		(layers "F.Cu" "B.Cu")
		(remove_unused_layers yes)
		(keep_end_layers yes)
		(zone_layer_connections "In1.Cu" "In4.Cu" "In6.Cu")
		(teardrops
			(best_length_ratio 0.4)
			(max_length 1)
			(best_width_ratio 0.9)
			(max_width 2)
			(curved_edges yes)
			(filter_ratio 0.9)
			(enabled yes)
			(allow_two_segments yes)
			(prefer_zone_connections yes)
		)
		(net 1)
	)
	(via
		(at 279.45 128.31)
		(size 0.45)
		(drill 0.1)
		(layers "F.Cu" "B.Cu")
		(remove_unused_layers yes)
		(keep_end_layers yes)
		(zone_layer_connections "In1.Cu" "In4.Cu" "In6.Cu")
		(teardrops
			(best_length_ratio 0.4)
			(max_length 1)
			(best_width_ratio 0.9)
			(max_width 2)
			(curved_edges yes)
			(filter_ratio 0.9)
			(enabled yes)
			(allow_two_segments yes)
			(prefer_zone_connections yes)
		)
		(net 1)
	)
	(via
		(at 229.95 89.31)
		(size 0.45)
		(drill 0.1)
		(layers "F.Cu" "B.Cu")
		(remove_unused_layers yes)
		(keep_end_layers yes)
		(zone_layer_connections "In1.Cu" "In4.Cu" "In6.Cu")
		(teardrops
			(best_length_ratio 0.4)
			(max_length 1)
			(best_width_ratio 0.9)
			(max_width 2)
			(curved_edges yes)
			(filter_ratio 0.9)
			(enabled yes)
			(allow_two_segments yes)
			(prefer_zone_connections yes)
		)
		(net 1)
	)
	(via
		(at 317.45 78.81)
		(size 0.45)
		(drill 0.1)
		(layers "F.Cu" "B.Cu")
		(remove_unused_layers yes)
		(keep_end_layers yes)
		(zone_layer_connections "In1.Cu" "In4.Cu" "In6.Cu")
		(teardrops
			(best_length_ratio 0.4)
			(max_length 1)
			(best_width_ratio 0.9)
			(max_width 2)
			(curved_edges yes)
			(filter_ratio 0.9)
			(enabled yes)
			(allow_two_segments yes)
			(prefer_zone_connections yes)
		)
		(net 1)
	)
	(via
		(at 136.86 147.62)
		(size 0.45)
		(drill 0.1)
		(layers "F.Cu" "B.Cu")
		(remove_unused_layers yes)
		(keep_end_layers yes)
		(zone_layer_connections "In1.Cu" "In4.Cu" "In6.Cu")
		(teardrops
			(best_length_ratio 0.4)
			(max_length 1)
			(best_width_ratio 0.9)
			(max_width 2)
			(curved_edges yes)
			(filter_ratio 0.9)
			(enabled yes)
			(allow_two_segments yes)
			(prefer_zone_connections yes)
		)
		(net 1)
	)
	(via
		(at 116.45 164.81)
		(size 0.45)
		(drill 0.1)
		(layers "F.Cu" "B.Cu")
		(remove_unused_layers yes)
		(keep_end_layers yes)
		(zone_layer_connections "In1.Cu" "In4.Cu" "In6.Cu")
		(teardrops
			(best_length_ratio 0.4)
			(max_length 1)
			(best_width_ratio 0.9)
			(max_width 2)
			(curved_edges yes)
			(filter_ratio 0.9)
			(enabled yes)
			(allow_two_segments yes)
			(prefer_zone_connections yes)
		)
		(net 1)
	)
	(via
		(at 317.45 72.31)
		(size 0.45)
		(drill 0.1)
		(layers "F.Cu" "B.Cu")
		(remove_unused_layers yes)
		(keep_end_layers yes)
		(zone_layer_connections "In1.Cu" "In4.Cu" "In6.Cu")
		(teardrops
			(best_length_ratio 0.4)
			(max_length 1)
			(best_width_ratio 0.9)
			(max_width 2)
			(curved_edges yes)
			(filter_ratio 0.9)
			(enabled yes)
			(allow_two_segments yes)
			(prefer_zone_connections yes)
		)
		(net 1)
	)
	(via
		(at 256.45 118.81)
		(size 0.45)
		(drill 0.1)
		(layers "F.Cu" "B.Cu")
		(remove_unused_layers yes)
		(keep_end_layers yes)
		(zone_layer_connections "In1.Cu" "In4.Cu" "In6.Cu")
		(teardrops
			(best_length_ratio 0.4)
			(max_length 1)
			(best_width_ratio 0.9)
			(max_width 2)
			(curved_edges yes)
			(filter_ratio 0.9)
			(enabled yes)
			(allow_two_segments yes)
			(prefer_zone_connections yes)
		)
		(net 1)
	)
	(via
		(at 95.45 138.81)
		(size 0.45)
		(drill 0.1)
		(layers "F.Cu" "B.Cu")
		(remove_unused_layers yes)
		(keep_end_layers yes)
		(zone_layer_connections "In1.Cu" "In4.Cu" "In6.Cu")
		(teardrops
			(best_length_ratio 0.4)
			(max_length 1)
			(best_width_ratio 0.9)
			(max_width 2)
			(curved_edges yes)
			(filter_ratio 0.9)
			(enabled yes)
			(allow_two_segments yes)
			(prefer_zone_connections yes)
		)
		(net 1)
	)
	(via
		(at 248.95 114.31)
		(size 0.45)
		(drill 0.1)
		(layers "F.Cu" "B.Cu")
		(remove_unused_layers yes)
		(keep_end_layers yes)
		(zone_layer_connections "In1.Cu" "In4.Cu" "In6.Cu")
		(teardrops
			(best_length_ratio 0.4)
			(max_length 1)
			(best_width_ratio 0.9)
			(max_width 2)
			(curved_edges yes)
			(filter_ratio 0.9)
			(enabled yes)
			(allow_two_segments yes)
			(prefer_zone_connections yes)
		)
		(net 1)
	)
	(via
		(at 100.45 129.81)
		(size 0.45)
		(drill 0.1)
		(layers "F.Cu" "B.Cu")
		(remove_unused_layers yes)
		(keep_end_layers yes)
		(zone_layer_connections "In1.Cu" "In4.Cu" "In6.Cu")
		(teardrops
			(best_length_ratio 0.4)
			(max_length 1)
			(best_width_ratio 0.9)
			(max_width 2)
			(curved_edges yes)
			(filter_ratio 0.9)
			(enabled yes)
			(allow_two_segments yes)
			(prefer_zone_connections yes)
		)
		(net 1)
	)
	(via
		(at 177.18 100.86)
		(size 0.45)
		(drill 0.1)
		(layers "F.Cu" "B.Cu")
		(remove_unused_layers yes)
		(keep_end_layers yes)
		(zone_layer_connections "In1.Cu" "In4.Cu" "In6.Cu")
		(teardrops
			(best_length_ratio 0.4)
			(max_length 1)
			(best_width_ratio 0.9)
			(max_width 2)
			(curved_edges yes)
			(filter_ratio 0.9)
			(enabled yes)
			(allow_two_segments yes)
			(prefer_zone_connections yes)
		)
		(net 1)
	)
	(via
		(at 158.45 90.81)
		(size 0.45)
		(drill 0.1)
		(layers "F.Cu" "B.Cu")
		(remove_unused_layers yes)
		(keep_end_layers yes)
		(zone_layer_connections "In1.Cu" "In4.Cu" "In6.Cu")
		(teardrops
			(best_length_ratio 0.4)
			(max_length 1)
			(best_width_ratio 0.9)
			(max_width 2)
			(curved_edges yes)
			(filter_ratio 0.9)
			(enabled yes)
			(allow_two_segments yes)
			(prefer_zone_connections yes)
		)
		(net 1)
	)
	(via
		(at 121.95 154.81)
		(size 0.45)
		(drill 0.1)
		(layers "F.Cu" "B.Cu")
		(remove_unused_layers yes)
		(keep_end_layers yes)
		(zone_layer_connections "In1.Cu" "In4.Cu" "In6.Cu")
		(teardrops
			(best_length_ratio 0.4)
			(max_length 1)
			(best_width_ratio 0.9)
			(max_width 2)
			(curved_edges yes)
			(filter_ratio 0.9)
			(enabled yes)
			(allow_two_segments yes)
			(prefer_zone_connections yes)
		)
		(net 1)
	)
	(via
		(at 284.95 138.31)
		(size 0.45)
		(drill 0.1)
		(layers "F.Cu" "B.Cu")
		(remove_unused_layers yes)
		(keep_end_layers yes)
		(zone_layer_connections "In1.Cu" "In4.Cu" "In6.Cu")
		(teardrops
			(best_length_ratio 0.4)
			(max_length 1)
			(best_width_ratio 0.9)
			(max_width 2)
			(curved_edges yes)
			(filter_ratio 0.9)
			(enabled yes)
			(allow_two_segments yes)
			(prefer_zone_connections yes)
		)
		(net 1)
	)
	(via
		(at 190.70861 78.102163)
		(size 0.45)
		(drill 0.1)
		(layers "F.Cu" "B.Cu")
		(remove_unused_layers yes)
		(keep_end_layers yes)
		(zone_layer_connections "In1.Cu" "In4.Cu" "In6.Cu")
		(teardrops
			(best_length_ratio 0.4)
			(max_length 1)
			(best_width_ratio 0.9)
			(max_width 2)
			(curved_edges yes)
			(filter_ratio 0.9)
			(enabled yes)
			(allow_two_segments yes)
			(prefer_zone_connections yes)
		)
		(net 1)
	)
	(via
		(at 181.1 166.9)
		(size 0.45)
		(drill 0.1)
		(layers "F.Cu" "B.Cu")
		(teardrops
			(best_length_ratio 0.4)
			(max_length 1)
			(best_width_ratio 0.9)
			(max_width 2)
			(curved_edges yes)
			(filter_ratio 0.9)
			(enabled yes)
			(allow_two_segments yes)
			(prefer_zone_connections yes)
		)
		(net 1)
	)
	(via
		(at 312.074999 120.21)
		(size 0.45)
		(drill 0.1)
		(layers "F.Cu" "B.Cu")
		(remove_unused_layers yes)
		(keep_end_layers yes)
		(zone_layer_connections "In1.Cu" "In4.Cu" "In6.Cu")
		(teardrops
			(best_length_ratio 0.4)
			(max_length 1)
			(best_width_ratio 0.9)
			(max_width 2)
			(curved_edges yes)
			(filter_ratio 0.9)
			(enabled yes)
			(allow_two_segments yes)
			(prefer_zone_connections yes)
		)
		(net 1)
	)
	(via
		(at 252.950001 170.81)
		(size 0.45)
		(drill 0.1)
		(layers "F.Cu" "B.Cu")
		(remove_unused_layers yes)
		(keep_end_layers yes)
		(zone_layer_connections "In1.Cu" "In4.Cu" "In6.Cu")
		(teardrops
			(best_length_ratio 0.4)
			(max_length 1)
			(best_width_ratio 0.9)
			(max_width 2)
			(curved_edges yes)
			(filter_ratio 0.9)
			(enabled yes)
			(allow_two_segments yes)
			(prefer_zone_connections yes)
		)
		(net 1)
	)
	(via
		(at 106.1 151.2)
		(size 0.45)
		(drill 0.1)
		(layers "F.Cu" "B.Cu")
		(remove_unused_layers yes)
		(keep_end_layers yes)
		(zone_layer_connections "In1.Cu" "In4.Cu" "In6.Cu")
		(teardrops
			(best_length_ratio 0.4)
			(max_length 1)
			(best_width_ratio 0.9)
			(max_width 2)
			(curved_edges yes)
			(filter_ratio 0.9)
			(enabled yes)
			(allow_two_segments yes)
			(prefer_zone_connections yes)
		)
		(net 1)
	)
	(via
		(at 95.45 153.31)
		(size 0.45)
		(drill 0.1)
		(layers "F.Cu" "B.Cu")
		(remove_unused_layers yes)
		(keep_end_layers yes)
		(zone_layer_connections "In1.Cu" "In4.Cu" "In6.Cu")
		(teardrops
			(best_length_ratio 0.4)
			(max_length 1)
			(best_width_ratio 0.9)
			(max_width 2)
			(curved_edges yes)
			(filter_ratio 0.9)
			(enabled yes)
			(allow_two_segments yes)
			(prefer_zone_connections yes)
		)
		(net 1)
	)
	(via
		(at 311.45 75.31)
		(size 0.45)
		(drill 0.1)
		(layers "F.Cu" "B.Cu")
		(remove_unused_layers yes)
		(keep_end_layers yes)
		(zone_layer_connections "In1.Cu" "In4.Cu" "In6.Cu")
		(teardrops
			(best_length_ratio 0.4)
			(max_length 1)
			(best_width_ratio 0.9)
			(max_width 2)
			(curved_edges yes)
			(filter_ratio 0.9)
			(enabled yes)
			(allow_two_segments yes)
			(prefer_zone_connections yes)
		)
		(net 1)
	)
	(via
		(at 195.95 98.81)
		(size 0.45)
		(drill 0.1)
		(layers "F.Cu" "B.Cu")
		(remove_unused_layers yes)
		(keep_end_layers yes)
		(zone_layer_connections "In1.Cu" "In4.Cu" "In6.Cu")
		(teardrops
			(best_length_ratio 0.4)
			(max_length 1)
			(best_width_ratio 0.9)
			(max_width 2)
			(curved_edges yes)
			(filter_ratio 0.9)
			(enabled yes)
			(allow_two_segments yes)
			(prefer_zone_connections yes)
		)
		(net 1)
	)
	(via
		(at 226.95 89.31)
		(size 0.45)
		(drill 0.1)
		(layers "F.Cu" "B.Cu")
		(remove_unused_layers yes)
		(keep_end_layers yes)
		(zone_layer_connections "In1.Cu" "In4.Cu" "In6.Cu")
		(teardrops
			(best_length_ratio 0.4)
			(max_length 1)
			(best_width_ratio 0.9)
			(max_width 2)
			(curved_edges yes)
			(filter_ratio 0.9)
			(enabled yes)
			(allow_two_segments yes)
			(prefer_zone_connections yes)
		)
		(net 1)
	)
	(via
		(at 102.95 99.81)
		(size 0.45)
		(drill 0.1)
		(layers "F.Cu" "B.Cu")
		(remove_unused_layers yes)
		(keep_end_layers yes)
		(zone_layer_connections "In1.Cu" "In4.Cu" "In6.Cu")
		(teardrops
			(best_length_ratio 0.4)
			(max_length 1)
			(best_width_ratio 0.9)
			(max_width 2)
			(curved_edges yes)
			(filter_ratio 0.9)
			(enabled yes)
			(allow_two_segments yes)
			(prefer_zone_connections yes)
		)
		(net 1)
	)
	(via
		(at 192.95 82.31)
		(size 0.45)
		(drill 0.1)
		(layers "F.Cu" "B.Cu")
		(remove_unused_layers yes)
		(keep_end_layers yes)
		(zone_layer_connections "In1.Cu" "In4.Cu" "In6.Cu")
		(teardrops
			(best_length_ratio 0.4)
			(max_length 1)
			(best_width_ratio 0.9)
			(max_width 2)
			(curved_edges yes)
			(filter_ratio 0.9)
			(enabled yes)
			(allow_two_segments yes)
			(prefer_zone_connections yes)
		)
		(net 1)
	)
	(via
		(at 134.905 83.310001)
		(size 0.45)
		(drill 0.1)
		(layers "F.Cu" "B.Cu")
		(remove_unused_layers yes)
		(keep_end_layers yes)
		(zone_layer_connections "In1.Cu" "In4.Cu" "In6.Cu")
		(teardrops
			(best_length_ratio 0.4)
			(max_length 1)
			(best_width_ratio 0.9)
			(max_width 2)
			(curved_edges yes)
			(filter_ratio 0.9)
			(enabled yes)
			(allow_two_segments yes)
			(prefer_zone_connections yes)
		)
		(net 1)
	)
	(via
		(at 292.95 115.31)
		(size 0.45)
		(drill 0.1)
		(layers "F.Cu" "B.Cu")
		(remove_unused_layers yes)
		(keep_end_layers yes)
		(zone_layer_connections "In1.Cu" "In4.Cu" "In6.Cu")
		(teardrops
			(best_length_ratio 0.4)
			(max_length 1)
			(best_width_ratio 0.9)
			(max_width 2)
			(curved_edges yes)
			(filter_ratio 0.9)
			(enabled yes)
			(allow_two_segments yes)
			(prefer_zone_connections yes)
		)
		(net 1)
	)
	(via
		(at 97.45 130.81)
		(size 0.45)
		(drill 0.1)
		(layers "F.Cu" "B.Cu")
		(remove_unused_layers yes)
		(keep_end_layers yes)
		(zone_layer_connections "In1.Cu" "In4.Cu" "In6.Cu")
		(teardrops
			(best_length_ratio 0.4)
			(max_length 1)
			(best_width_ratio 0.9)
			(max_width 2)
			(curved_edges yes)
			(filter_ratio 0.9)
			(enabled yes)
			(allow_two_segments yes)
			(prefer_zone_connections yes)
		)
		(net 1)
	)
	(via
		(at 101.45 170.81)
		(size 0.45)
		(drill 0.1)
		(layers "F.Cu" "B.Cu")
		(remove_unused_layers yes)
		(keep_end_layers yes)
		(zone_layer_connections "In1.Cu" "In4.Cu" "In6.Cu")
		(teardrops
			(best_length_ratio 0.4)
			(max_length 1)
			(best_width_ratio 0.9)
			(max_width 2)
			(curved_edges yes)
			(filter_ratio 0.9)
			(enabled yes)
			(allow_two_segments yes)
			(prefer_zone_connections yes)
		)
		(net 1)
	)
	(via
		(at 126.45 158.81)
		(size 0.45)
		(drill 0.1)
		(layers "F.Cu" "B.Cu")
		(remove_unused_layers yes)
		(keep_end_layers yes)
		(zone_layer_connections "In1.Cu" "In4.Cu" "In6.Cu")
		(teardrops
			(best_length_ratio 0.4)
			(max_length 1)
			(best_width_ratio 0.9)
			(max_width 2)
			(curved_edges yes)
			(filter_ratio 0.9)
			(enabled yes)
			(allow_two_segments yes)
			(prefer_zone_connections yes)
		)
		(net 1)
	)
	(via
		(at 184.45 152.25)
		(size 0.45)
		(drill 0.1)
		(layers "F.Cu" "B.Cu")
		(teardrops
			(best_length_ratio 0.4)
			(max_length 1)
			(best_width_ratio 0.9)
			(max_width 2)
			(curved_edges yes)
			(filter_ratio 0.9)
			(enabled yes)
			(allow_two_segments yes)
			(prefer_zone_connections yes)
		)
		(net 1)
	)
	(via
		(at 126.45 160.81)
		(size 0.45)
		(drill 0.1)
		(layers "F.Cu" "B.Cu")
		(remove_unused_layers yes)
		(keep_end_layers yes)
		(zone_layer_connections "In1.Cu" "In4.Cu" "In6.Cu")
		(teardrops
			(best_length_ratio 0.4)
			(max_length 1)
			(best_width_ratio 0.9)
			(max_width 2)
			(curved_edges yes)
			(filter_ratio 0.9)
			(enabled yes)
			(allow_two_segments yes)
			(prefer_zone_connections yes)
		)
		(net 1)
	)
	(via
		(at 167.95 83.81)
		(size 0.45)
		(drill 0.1)
		(layers "F.Cu" "B.Cu")
		(remove_unused_layers yes)
		(keep_end_layers yes)
		(zone_layer_connections "In1.Cu" "In4.Cu" "In6.Cu")
		(teardrops
			(best_length_ratio 0.4)
			(max_length 1)
			(best_width_ratio 0.9)
			(max_width 2)
			(curved_edges yes)
			(filter_ratio 0.9)
			(enabled yes)
			(allow_two_segments yes)
			(prefer_zone_connections yes)
		)
		(net 1)
	)
	(via
		(at 318.95 77.31)
		(size 0.45)
		(drill 0.1)
		(layers "F.Cu" "B.Cu")
		(remove_unused_layers yes)
		(keep_end_layers yes)
		(zone_layer_connections "In1.Cu" "In4.Cu" "In6.Cu")
		(teardrops
			(best_length_ratio 0.4)
			(max_length 1)
			(best_width_ratio 0.9)
			(max_width 2)
			(curved_edges yes)
			(filter_ratio 0.9)
			(enabled yes)
			(allow_two_segments yes)
			(prefer_zone_connections yes)
		)
		(net 1)
	)
	(via
		(at 107.95 70.31)
		(size 0.45)
		(drill 0.1)
		(layers "F.Cu" "B.Cu")
		(remove_unused_layers yes)
		(keep_end_layers yes)
		(zone_layer_connections "In1.Cu" "In4.Cu" "In6.Cu")
		(teardrops
			(best_length_ratio 0.4)
			(max_length 1)
			(best_width_ratio 0.9)
			(max_width 2)
			(curved_edges yes)
			(filter_ratio 0.9)
			(enabled yes)
			(allow_two_segments yes)
			(prefer_zone_connections yes)
		)
		(net 1)
	)
	(via
		(at 134.29 132.86)
		(size 0.45)
		(drill 0.1)
		(layers "F.Cu" "B.Cu")
		(remove_unused_layers yes)
		(keep_end_layers yes)
		(zone_layer_connections "In1.Cu" "In4.Cu" "In6.Cu")
		(teardrops
			(best_length_ratio 0.4)
			(max_length 1)
			(best_width_ratio 0.9)
			(max_width 2)
			(curved_edges yes)
			(filter_ratio 0.9)
			(enabled yes)
			(allow_two_segments yes)
			(prefer_zone_connections yes)
		)
		(net 1)
	)
	(via
		(at 248.95 123.31)
		(size 0.45)
		(drill 0.1)
		(layers "F.Cu" "B.Cu")
		(remove_unused_layers yes)
		(keep_end_layers yes)
		(zone_layer_connections "In1.Cu" "In4.Cu" "In6.Cu")
		(teardrops
			(best_length_ratio 0.4)
			(max_length 1)
			(best_width_ratio 0.9)
			(max_width 2)
			(curved_edges yes)
			(filter_ratio 0.9)
			(enabled yes)
			(allow_two_segments yes)
			(prefer_zone_connections yes)
		)
		(net 1)
	)
	(via
		(at 256.45 115.81)
		(size 0.45)
		(drill 0.1)
		(layers "F.Cu" "B.Cu")
		(remove_unused_layers yes)
		(keep_end_layers yes)
		(zone_layer_connections "In1.Cu" "In4.Cu" "In6.Cu")
		(teardrops
			(best_length_ratio 0.4)
			(max_length 1)
			(best_width_ratio 0.9)
			(max_width 2)
			(curved_edges yes)
			(filter_ratio 0.9)
			(enabled yes)
			(allow_two_segments yes)
			(prefer_zone_connections yes)
		)
		(net 1)
	)
	(via
		(at 231.45 84.81)
		(size 0.45)
		(drill 0.1)
		(layers "F.Cu" "B.Cu")
		(remove_unused_layers yes)
		(keep_end_layers yes)
		(free yes)
		(zone_layer_connections "In1.Cu" "In4.Cu" "In6.Cu")
		(teardrops
			(best_length_ratio 0.4)
			(max_length 1)
			(best_width_ratio 0.9)
			(max_width 2)
			(curved_edges yes)
			(filter_ratio 0.9)
			(enabled yes)
			(allow_two_segments yes)
			(prefer_zone_connections yes)
		)
		(net 1)
	)
	(via
		(at 300.45 106.81)
		(size 0.45)
		(drill 0.1)
		(layers "F.Cu" "B.Cu")
		(remove_unused_layers yes)
		(keep_end_layers yes)
		(zone_layer_connections "In1.Cu" "In4.Cu" "In6.Cu")
		(teardrops
			(best_length_ratio 0.4)
			(max_length 1)
			(best_width_ratio 0.9)
			(max_width 2)
			(curved_edges yes)
			(filter_ratio 0.9)
			(enabled yes)
			(allow_two_segments yes)
			(prefer_zone_connections yes)
		)
		(net 1)
	)
	(via
		(at 175.9 155.5)
		(size 0.45)
		(drill 0.1)
		(layers "F.Cu" "B.Cu")
		(teardrops
			(best_length_ratio 0.4)
			(max_length 1)
			(best_width_ratio 0.9)
			(max_width 2)
			(curved_edges yes)
			(filter_ratio 0.9)
			(enabled yes)
			(allow_two_segments yes)
			(prefer_zone_connections yes)
		)
		(net 1)
	)
	(via
		(at 296.45 118.81)
		(size 0.45)
		(drill 0.1)
		(layers "F.Cu" "B.Cu")
		(remove_unused_layers yes)
		(keep_end_layers yes)
		(zone_layer_connections "In1.Cu" "In4.Cu" "In6.Cu")
		(teardrops
			(best_length_ratio 0.4)
			(max_length 1)
			(best_width_ratio 0.9)
			(max_width 2)
			(curved_edges yes)
			(filter_ratio 0.9)
			(enabled yes)
			(allow_two_segments yes)
			(prefer_zone_connections yes)
		)
		(net 1)
	)
	(via
		(at 312.16 163.41)
		(size 0.45)
		(drill 0.1)
		(layers "F.Cu" "B.Cu")
		(remove_unused_layers yes)
		(keep_end_layers yes)
		(zone_layer_connections "In1.Cu" "In4.Cu" "In6.Cu")
		(teardrops
			(best_length_ratio 0.4)
			(max_length 1)
			(best_width_ratio 0.9)
			(max_width 2)
			(curved_edges yes)
			(filter_ratio 0.9)
			(enabled yes)
			(allow_two_segments yes)
			(prefer_zone_connections yes)
		)
		(net 1)
	)
	(via
		(at 317.549999 140.759999)
		(size 0.45)
		(drill 0.1)
		(layers "F.Cu" "B.Cu")
		(remove_unused_layers yes)
		(keep_end_layers yes)
		(zone_layer_connections "In1.Cu" "In4.Cu" "In6.Cu")
		(teardrops
			(best_length_ratio 0.4)
			(max_length 1)
			(best_width_ratio 0.9)
			(max_width 2)
			(curved_edges yes)
			(filter_ratio 0.9)
			(enabled yes)
			(allow_two_segments yes)
			(prefer_zone_connections yes)
		)
		(net 1)
	)
	(via
		(at 285.95 93.31)
		(size 0.45)
		(drill 0.1)
		(layers "F.Cu" "B.Cu")
		(remove_unused_layers yes)
		(keep_end_layers yes)
		(zone_layer_connections "In1.Cu" "In4.Cu" "In6.Cu")
		(teardrops
			(best_length_ratio 0.4)
			(max_length 1)
			(best_width_ratio 0.9)
			(max_width 2)
			(curved_edges yes)
			(filter_ratio 0.9)
			(enabled yes)
			(allow_two_segments yes)
			(prefer_zone_connections yes)
		)
		(net 1)
	)
	(via
		(at 150.175 86.91)
		(size 0.45)
		(drill 0.1)
		(layers "F.Cu" "B.Cu")
		(remove_unused_layers yes)
		(keep_end_layers yes)
		(free yes)
		(zone_layer_connections "In1.Cu" "In4.Cu" "In6.Cu")
		(teardrops
			(best_length_ratio 0.4)
			(max_length 1)
			(best_width_ratio 0.9)
			(max_width 2)
			(curved_edges yes)
			(filter_ratio 0.9)
			(enabled yes)
			(allow_two_segments yes)
			(prefer_zone_connections yes)
		)
		(net 1)
	)
	(via
		(at 201.45 91.56)
		(size 0.45)
		(drill 0.1)
		(layers "F.Cu" "B.Cu")
		(remove_unused_layers yes)
		(keep_end_layers yes)
		(zone_layer_connections "In1.Cu" "In4.Cu" "In6.Cu")
		(teardrops
			(best_length_ratio 0.4)
			(max_length 1)
			(best_width_ratio 0.9)
			(max_width 2)
			(curved_edges yes)
			(filter_ratio 0.9)
			(enabled yes)
			(allow_two_segments yes)
			(prefer_zone_connections yes)
		)
		(net 1)
	)
	(via
		(at 152.5685 86.5595)
		(size 0.45)
		(drill 0.1)
		(layers "F.Cu" "B.Cu")
		(remove_unused_layers yes)
		(keep_end_layers yes)
		(zone_layer_connections "In1.Cu" "In4.Cu" "In6.Cu")
		(teardrops
			(best_length_ratio 0.4)
			(max_length 1)
			(best_width_ratio 0.9)
			(max_width 2)
			(curved_edges yes)
			(filter_ratio 0.9)
			(enabled yes)
			(allow_two_segments yes)
			(prefer_zone_connections yes)
		)
		(net 1)
	)
	(via
		(at 160.95 70.31)
		(size 0.45)
		(drill 0.1)
		(layers "F.Cu" "B.Cu")
		(remove_unused_layers yes)
		(keep_end_layers yes)
		(zone_layer_connections "In1.Cu" "In4.Cu" "In6.Cu")
		(teardrops
			(best_length_ratio 0.4)
			(max_length 1)
			(best_width_ratio 0.9)
			(max_width 2)
			(curved_edges yes)
			(filter_ratio 0.9)
			(enabled yes)
			(allow_two_segments yes)
			(prefer_zone_connections yes)
		)
		(net 1)
	)
	(via
		(at 257.95 120.31)
		(size 0.45)
		(drill 0.1)
		(layers "F.Cu" "B.Cu")
		(remove_unused_layers yes)
		(keep_end_layers yes)
		(zone_layer_connections "In1.Cu" "In4.Cu" "In6.Cu")
		(teardrops
			(best_length_ratio 0.4)
			(max_length 1)
			(best_width_ratio 0.9)
			(max_width 2)
			(curved_edges yes)
			(filter_ratio 0.9)
			(enabled yes)
			(allow_two_segments yes)
			(prefer_zone_connections yes)
		)
		(net 1)
	)
	(via
		(at 314.4645 99.6365)
		(size 0.45)
		(drill 0.1)
		(layers "F.Cu" "B.Cu")
		(remove_unused_layers yes)
		(keep_end_layers yes)
		(free yes)
		(zone_layer_connections "In1.Cu" "In4.Cu" "In6.Cu")
		(teardrops
			(best_length_ratio 0.4)
			(max_length 1)
			(best_width_ratio 0.9)
			(max_width 2)
			(curved_edges yes)
			(filter_ratio 0.9)
			(enabled yes)
			(allow_two_segments yes)
			(prefer_zone_connections yes)
		)
		(net 1)
	)
	(via
		(at 197.45 100.31)
		(size 0.45)
		(drill 0.1)
		(layers "F.Cu" "B.Cu")
		(remove_unused_layers yes)
		(keep_end_layers yes)
		(zone_layer_connections "In1.Cu" "In4.Cu" "In6.Cu")
		(teardrops
			(best_length_ratio 0.4)
			(max_length 1)
			(best_width_ratio 0.9)
			(max_width 2)
			(curved_edges yes)
			(filter_ratio 0.9)
			(enabled yes)
			(allow_two_segments yes)
			(prefer_zone_connections yes)
		)
		(net 1)
	)
	(via
		(at 173.153893 106.909175)
		(size 0.45)
		(drill 0.1)
		(layers "F.Cu" "B.Cu")
		(remove_unused_layers yes)
		(keep_end_layers yes)
		(zone_layer_connections "In1.Cu" "In4.Cu" "In6.Cu")
		(teardrops
			(best_length_ratio 0.4)
			(max_length 1)
			(best_width_ratio 0.9)
			(max_width 2)
			(curved_edges yes)
			(filter_ratio 0.9)
			(enabled yes)
			(allow_two_segments yes)
			(prefer_zone_connections yes)
		)
		(net 1)
	)
	(via
		(at 136.8 73.01)
		(size 0.45)
		(drill 0.1)
		(layers "F.Cu" "B.Cu")
		(remove_unused_layers yes)
		(keep_end_layers yes)
		(zone_layer_connections "In1.Cu" "In4.Cu" "In6.Cu")
		(teardrops
			(best_length_ratio 0.4)
			(max_length 1)
			(best_width_ratio 0.9)
			(max_width 2)
			(curved_edges yes)
			(filter_ratio 0.9)
			(enabled yes)
			(allow_two_segments yes)
			(prefer_zone_connections yes)
		)
		(net 1)
	)
	(via
		(at 135.95 90.31)
		(size 0.45)
		(drill 0.1)
		(layers "F.Cu" "B.Cu")
		(remove_unused_layers yes)
		(keep_end_layers yes)
		(zone_layer_connections "In1.Cu" "In4.Cu" "In6.Cu")
		(teardrops
			(best_length_ratio 0.4)
			(max_length 1)
			(best_width_ratio 0.9)
			(max_width 2)
			(curved_edges yes)
			(filter_ratio 0.9)
			(enabled yes)
			(allow_two_segments yes)
			(prefer_zone_connections yes)
		)
		(net 1)
	)
	(via
		(at 208.45 139.81)
		(size 0.45)
		(drill 0.1)
		(layers "F.Cu" "B.Cu")
		(remove_unused_layers yes)
		(keep_end_layers yes)
		(zone_layer_connections "In1.Cu" "In4.Cu" "In6.Cu")
		(teardrops
			(best_length_ratio 0.4)
			(max_length 1)
			(best_width_ratio 0.9)
			(max_width 2)
			(curved_edges yes)
			(filter_ratio 0.9)
			(enabled yes)
			(allow_two_segments yes)
			(prefer_zone_connections yes)
		)
		(net 1)
	)
	(via
		(at 95.45 144.81)
		(size 0.45)
		(drill 0.1)
		(layers "F.Cu" "B.Cu")
		(remove_unused_layers yes)
		(keep_end_layers yes)
		(zone_layer_connections "In1.Cu" "In4.Cu" "In6.Cu")
		(teardrops
			(best_length_ratio 0.4)
			(max_length 1)
			(best_width_ratio 0.9)
			(max_width 2)
			(curved_edges yes)
			(filter_ratio 0.9)
			(enabled yes)
			(allow_two_segments yes)
			(prefer_zone_connections yes)
		)
		(net 1)
	)
	(via
		(at 106.95 71.31)
		(size 0.45)
		(drill 0.1)
		(layers "F.Cu" "B.Cu")
		(remove_unused_layers yes)
		(keep_end_layers yes)
		(zone_layer_connections "In1.Cu" "In4.Cu" "In6.Cu")
		(teardrops
			(best_length_ratio 0.4)
			(max_length 1)
			(best_width_ratio 0.9)
			(max_width 2)
			(curved_edges yes)
			(filter_ratio 0.9)
			(enabled yes)
			(allow_two_segments yes)
			(prefer_zone_connections yes)
		)
		(net 1)
	)
	(via
		(at 277.95 118.31)
		(size 0.45)
		(drill 0.1)
		(layers "F.Cu" "B.Cu")
		(remove_unused_layers yes)
		(keep_end_layers yes)
		(zone_layer_connections "In1.Cu" "In4.Cu" "In6.Cu")
		(teardrops
			(best_length_ratio 0.4)
			(max_length 1)
			(best_width_ratio 0.9)
			(max_width 2)
			(curved_edges yes)
			(filter_ratio 0.9)
			(enabled yes)
			(allow_two_segments yes)
			(prefer_zone_connections yes)
		)
		(net 1)
	)
	(via
		(at 254.95 123.31)
		(size 0.45)
		(drill 0.1)
		(layers "F.Cu" "B.Cu")
		(remove_unused_layers yes)
		(keep_end_layers yes)
		(zone_layer_connections "In1.Cu" "In4.Cu" "In6.Cu")
		(teardrops
			(best_length_ratio 0.4)
			(max_length 1)
			(best_width_ratio 0.9)
			(max_width 2)
			(curved_edges yes)
			(filter_ratio 0.9)
			(enabled yes)
			(allow_two_segments yes)
			(prefer_zone_connections yes)
		)
		(net 1)
	)
	(via
		(at 202.95 84.31)
		(size 0.45)
		(drill 0.1)
		(layers "F.Cu" "B.Cu")
		(remove_unused_layers yes)
		(keep_end_layers yes)
		(zone_layer_connections "In1.Cu" "In4.Cu" "In6.Cu")
		(teardrops
			(best_length_ratio 0.4)
			(max_length 1)
			(best_width_ratio 0.9)
			(max_width 2)
			(curved_edges yes)
			(filter_ratio 0.9)
			(enabled yes)
			(allow_two_segments yes)
			(prefer_zone_connections yes)
		)
		(net 1)
	)
	(via
		(at 128.9 81.28)
		(size 0.45)
		(drill 0.1)
		(layers "F.Cu" "B.Cu")
		(remove_unused_layers yes)
		(keep_end_layers yes)
		(zone_layer_connections "In1.Cu" "In4.Cu" "In6.Cu")
		(teardrops
			(best_length_ratio 0.4)
			(max_length 1)
			(best_width_ratio 0.9)
			(max_width 2)
			(curved_edges yes)
			(filter_ratio 0.9)
			(enabled yes)
			(allow_two_segments yes)
			(prefer_zone_connections yes)
		)
		(net 1)
	)
	(via
		(at 150.45 131.86)
		(size 0.45)
		(drill 0.1)
		(layers "F.Cu" "B.Cu")
		(remove_unused_layers yes)
		(keep_end_layers yes)
		(zone_layer_connections "In1.Cu" "In4.Cu" "In6.Cu")
		(teardrops
			(best_length_ratio 0.4)
			(max_length 1)
			(best_width_ratio 0.9)
			(max_width 2)
			(curved_edges yes)
			(filter_ratio 0.9)
			(enabled yes)
			(allow_two_segments yes)
			(prefer_zone_connections yes)
		)
		(net 1)
	)
	(via
		(at 212 161.45)
		(size 0.45)
		(drill 0.1)
		(layers "F.Cu" "B.Cu")
		(teardrops
			(best_length_ratio 0.4)
			(max_length 1)
			(best_width_ratio 0.9)
			(max_width 2)
			(curved_edges yes)
			(filter_ratio 0.9)
			(enabled yes)
			(allow_two_segments yes)
			(prefer_zone_connections yes)
		)
		(net 1)
	)
	(via
		(at 147.45 131.86)
		(size 0.45)
		(drill 0.1)
		(layers "F.Cu" "B.Cu")
		(remove_unused_layers yes)
		(keep_end_layers yes)
		(zone_layer_connections "In1.Cu" "In4.Cu" "In6.Cu")
		(teardrops
			(best_length_ratio 0.4)
			(max_length 1)
			(best_width_ratio 0.9)
			(max_width 2)
			(curved_edges yes)
			(filter_ratio 0.9)
			(enabled yes)
			(allow_two_segments yes)
			(prefer_zone_connections yes)
		)
		(net 1)
	)
	(via
		(at 263.95 106.81)
		(size 0.45)
		(drill 0.1)
		(layers "F.Cu" "B.Cu")
		(remove_unused_layers yes)
		(keep_end_layers yes)
		(zone_layer_connections "In1.Cu" "In4.Cu" "In6.Cu")
		(teardrops
			(best_length_ratio 0.4)
			(max_length 1)
			(best_width_ratio 0.9)
			(max_width 2)
			(curved_edges yes)
			(filter_ratio 0.9)
			(enabled yes)
			(allow_two_segments yes)
			(prefer_zone_connections yes)
		)
		(net 1)
	)
	(via
		(at 286.45 145.81)
		(size 0.45)
		(drill 0.1)
		(layers "F.Cu" "B.Cu")
		(remove_unused_layers yes)
		(keep_end_layers yes)
		(zone_layer_connections "In1.Cu" "In4.Cu" "In6.Cu")
		(teardrops
			(best_length_ratio 0.4)
			(max_length 1)
			(best_width_ratio 0.9)
			(max_width 2)
			(curved_edges yes)
			(filter_ratio 0.9)
			(enabled yes)
			(allow_two_segments yes)
			(prefer_zone_connections yes)
		)
		(net 1)
	)
	(via
		(at 281.95 90.31)
		(size 0.45)
		(drill 0.1)
		(layers "F.Cu" "B.Cu")
		(remove_unused_layers yes)
		(keep_end_layers yes)
		(zone_layer_connections "In1.Cu" "In4.Cu" "In6.Cu")
		(teardrops
			(best_length_ratio 0.4)
			(max_length 1)
			(best_width_ratio 0.9)
			(max_width 2)
			(curved_edges yes)
			(filter_ratio 0.9)
			(enabled yes)
			(allow_two_segments yes)
			(prefer_zone_connections yes)
		)
		(net 1)
	)
	(via
		(at 105.1 83.81)
		(size 0.45)
		(drill 0.1)
		(layers "F.Cu" "B.Cu")
		(remove_unused_layers yes)
		(keep_end_layers yes)
		(zone_layer_connections "In1.Cu" "In4.Cu" "In6.Cu")
		(teardrops
			(best_length_ratio 0.4)
			(max_length 1)
			(best_width_ratio 0.9)
			(max_width 2)
			(curved_edges yes)
			(filter_ratio 0.9)
			(enabled yes)
			(allow_two_segments yes)
			(prefer_zone_connections yes)
		)
		(net 1)
	)
	(via
		(at 263.95 115.81)
		(size 0.45)
		(drill 0.1)
		(layers "F.Cu" "B.Cu")
		(remove_unused_layers yes)
		(keep_end_layers yes)
		(zone_layer_connections "In1.Cu" "In4.Cu" "In6.Cu")
		(teardrops
			(best_length_ratio 0.4)
			(max_length 1)
			(best_width_ratio 0.9)
			(max_width 2)
			(curved_edges yes)
			(filter_ratio 0.9)
			(enabled yes)
			(allow_two_segments yes)
			(prefer_zone_connections yes)
		)
		(net 1)
	)
	(via
		(at 135.3 71.51)
		(size 0.45)
		(drill 0.1)
		(layers "F.Cu" "B.Cu")
		(remove_unused_layers yes)
		(keep_end_layers yes)
		(free yes)
		(zone_layer_connections "In1.Cu" "In4.Cu" "In6.Cu")
		(teardrops
			(best_length_ratio 0.4)
			(max_length 1)
			(best_width_ratio 0.9)
			(max_width 2)
			(curved_edges yes)
			(filter_ratio 0.9)
			(enabled yes)
			(allow_two_segments yes)
			(prefer_zone_connections yes)
		)
		(net 1)
	)
	(via
		(at 141.8 106)
		(size 0.45)
		(drill 0.1)
		(layers "F.Cu" "B.Cu")
		(remove_unused_layers yes)
		(keep_end_layers yes)
		(zone_layer_connections "In1.Cu" "In4.Cu" "In6.Cu")
		(teardrops
			(best_length_ratio 0.4)
			(max_length 1)
			(best_width_ratio 0.9)
			(max_width 2)
			(curved_edges yes)
			(filter_ratio 0.9)
			(enabled yes)
			(allow_two_segments yes)
			(prefer_zone_connections yes)
		)
		(net 1)
	)
	(via
		(at 280.95 106.31)
		(size 0.45)
		(drill 0.1)
		(layers "F.Cu" "B.Cu")
		(remove_unused_layers yes)
		(keep_end_layers yes)
		(zone_layer_connections "In1.Cu" "In4.Cu" "In6.Cu")
		(teardrops
			(best_length_ratio 0.4)
			(max_length 1)
			(best_width_ratio 0.9)
			(max_width 2)
			(curved_edges yes)
			(filter_ratio 0.9)
			(enabled yes)
			(allow_two_segments yes)
			(prefer_zone_connections yes)
		)
		(net 1)
	)
	(via
		(at 130.28 144.8)
		(size 0.45)
		(drill 0.1)
		(layers "F.Cu" "B.Cu")
		(remove_unused_layers yes)
		(keep_end_layers yes)
		(zone_layer_connections "In1.Cu" "In4.Cu" "In6.Cu")
		(teardrops
			(best_length_ratio 0.4)
			(max_length 1)
			(best_width_ratio 0.9)
			(max_width 2)
			(curved_edges yes)
			(filter_ratio 0.9)
			(enabled yes)
			(allow_two_segments yes)
			(prefer_zone_connections yes)
		)
		(net 1)
	)
	(via
		(at 198.95 104.81)
		(size 0.45)
		(drill 0.1)
		(layers "F.Cu" "B.Cu")
		(remove_unused_layers yes)
		(keep_end_layers yes)
		(zone_layer_connections "In1.Cu" "In4.Cu" "In6.Cu")
		(teardrops
			(best_length_ratio 0.4)
			(max_length 1)
			(best_width_ratio 0.9)
			(max_width 2)
			(curved_edges yes)
			(filter_ratio 0.9)
			(enabled yes)
			(allow_two_segments yes)
			(prefer_zone_connections yes)
		)
		(net 1)
	)
	(via
		(at 161.45 154.81)
		(size 0.45)
		(drill 0.1)
		(layers "F.Cu" "B.Cu")
		(remove_unused_layers yes)
		(keep_end_layers yes)
		(zone_layer_connections "In1.Cu" "In4.Cu" "In6.Cu")
		(teardrops
			(best_length_ratio 0.4)
			(max_length 1)
			(best_width_ratio 0.9)
			(max_width 2)
			(curved_edges yes)
			(filter_ratio 0.9)
			(enabled yes)
			(allow_two_segments yes)
			(prefer_zone_connections yes)
		)
		(net 1)
	)
	(via
		(at 260.95 109.81)
		(size 0.45)
		(drill 0.1)
		(layers "F.Cu" "B.Cu")
		(remove_unused_layers yes)
		(keep_end_layers yes)
		(zone_layer_connections "In1.Cu" "In4.Cu" "In6.Cu")
		(teardrops
			(best_length_ratio 0.4)
			(max_length 1)
			(best_width_ratio 0.9)
			(max_width 2)
			(curved_edges yes)
			(filter_ratio 0.9)
			(enabled yes)
			(allow_two_segments yes)
			(prefer_zone_connections yes)
		)
		(net 1)
	)
	(via
		(at 288.95 119.31)
		(size 0.45)
		(drill 0.1)
		(layers "F.Cu" "B.Cu")
		(remove_unused_layers yes)
		(keep_end_layers yes)
		(zone_layer_connections "In1.Cu" "In4.Cu" "In6.Cu")
		(teardrops
			(best_length_ratio 0.4)
			(max_length 1)
			(best_width_ratio 0.9)
			(max_width 2)
			(curved_edges yes)
			(filter_ratio 0.9)
			(enabled yes)
			(allow_two_segments yes)
			(prefer_zone_connections yes)
		)
		(net 1)
	)
	(via
		(at 99.6 86.084)
		(size 0.45)
		(drill 0.1)
		(layers "F.Cu" "B.Cu")
		(remove_unused_layers yes)
		(keep_end_layers yes)
		(zone_layer_connections "In1.Cu" "In4.Cu" "In6.Cu")
		(teardrops
			(best_length_ratio 0.4)
			(max_length 1)
			(best_width_ratio 0.9)
			(max_width 2)
			(curved_edges yes)
			(filter_ratio 0.9)
			(enabled yes)
			(allow_two_segments yes)
			(prefer_zone_connections yes)
		)
		(net 1)
	)
	(via
		(at 113.45 72.31)
		(size 0.45)
		(drill 0.1)
		(layers "F.Cu" "B.Cu")
		(remove_unused_layers yes)
		(keep_end_layers yes)
		(zone_layer_connections "In1.Cu" "In4.Cu" "In6.Cu")
		(teardrops
			(best_length_ratio 0.4)
			(max_length 1)
			(best_width_ratio 0.9)
			(max_width 2)
			(curved_edges yes)
			(filter_ratio 0.9)
			(enabled yes)
			(allow_two_segments yes)
			(prefer_zone_connections yes)
		)
		(net 1)
	)
	(via
		(at 236.95 120.31)
		(size 0.45)
		(drill 0.1)
		(layers "F.Cu" "B.Cu")
		(remove_unused_layers yes)
		(keep_end_layers yes)
		(free yes)
		(zone_layer_connections "In1.Cu" "In4.Cu" "In6.Cu")
		(teardrops
			(best_length_ratio 0.4)
			(max_length 1)
			(best_width_ratio 0.9)
			(max_width 2)
			(curved_edges yes)
			(filter_ratio 0.9)
			(enabled yes)
			(allow_two_segments yes)
			(prefer_zone_connections yes)
		)
		(net 1)
	)
	(via
		(at 191.6 161.675)
		(size 0.45)
		(drill 0.1)
		(layers "F.Cu" "B.Cu")
		(teardrops
			(best_length_ratio 0.4)
			(max_length 1)
			(best_width_ratio 0.9)
			(max_width 2)
			(curved_edges yes)
			(filter_ratio 0.9)
			(enabled yes)
			(allow_two_segments yes)
			(prefer_zone_connections yes)
		)
		(net 1)
	)
	(via
		(at 154.205 155.825)
		(size 0.45)
		(drill 0.1)
		(layers "F.Cu" "B.Cu")
		(remove_unused_layers yes)
		(keep_end_layers yes)
		(zone_layer_connections "In1.Cu" "In4.Cu" "In6.Cu")
		(teardrops
			(best_length_ratio 0.4)
			(max_length 1)
			(best_width_ratio 0.9)
			(max_width 2)
			(curved_edges yes)
			(filter_ratio 0.9)
			(enabled yes)
			(allow_two_segments yes)
			(prefer_zone_connections yes)
		)
		(net 1)
	)
	(via
		(at 151.45 72.81)
		(size 0.45)
		(drill 0.1)
		(layers "F.Cu" "B.Cu")
		(remove_unused_layers yes)
		(keep_end_layers yes)
		(zone_layer_connections "In1.Cu" "In4.Cu" "In6.Cu")
		(teardrops
			(best_length_ratio 0.4)
			(max_length 1)
			(best_width_ratio 0.9)
			(max_width 2)
			(curved_edges yes)
			(filter_ratio 0.9)
			(enabled yes)
			(allow_two_segments yes)
			(prefer_zone_connections yes)
		)
		(net 1)
	)
	(via
		(at 314.4645 101.6365)
		(size 0.45)
		(drill 0.1)
		(layers "F.Cu" "B.Cu")
		(remove_unused_layers yes)
		(keep_end_layers yes)
		(free yes)
		(zone_layer_connections "In1.Cu" "In4.Cu" "In6.Cu")
		(teardrops
			(best_length_ratio 0.4)
			(max_length 1)
			(best_width_ratio 0.9)
			(max_width 2)
			(curved_edges yes)
			(filter_ratio 0.9)
			(enabled yes)
			(allow_two_segments yes)
			(prefer_zone_connections yes)
		)
		(net 1)
	)
	(via
		(at 220.85 152.65)
		(size 0.45)
		(drill 0.1)
		(layers "F.Cu" "B.Cu")
		(teardrops
			(best_length_ratio 0.4)
			(max_length 1)
			(best_width_ratio 0.9)
			(max_width 2)
			(curved_edges yes)
			(filter_ratio 0.9)
			(enabled yes)
			(allow_two_segments yes)
			(prefer_zone_connections yes)
		)
		(net 1)
	)
	(via
		(at 113.04 137.91)
		(size 0.45)
		(drill 0.1)
		(layers "F.Cu" "B.Cu")
		(remove_unused_layers yes)
		(keep_end_layers yes)
		(zone_layer_connections "In1.Cu" "In4.Cu" "In6.Cu")
		(teardrops
			(best_length_ratio 0.4)
			(max_length 1)
			(best_width_ratio 0.9)
			(max_width 2)
			(curved_edges yes)
			(filter_ratio 0.9)
			(enabled yes)
			(allow_two_segments yes)
			(prefer_zone_connections yes)
		)
		(net 1)
	)
	(via
		(at 270.7 159.3)
		(size 0.45)
		(drill 0.1)
		(layers "F.Cu" "B.Cu")
		(remove_unused_layers yes)
		(keep_end_layers yes)
		(zone_layer_connections "In1.Cu" "In4.Cu" "In6.Cu")
		(teardrops
			(best_length_ratio 0.4)
			(max_length 1)
			(best_width_ratio 0.9)
			(max_width 2)
			(curved_edges yes)
			(filter_ratio 0.9)
			(enabled yes)
			(allow_two_segments yes)
			(prefer_zone_connections yes)
		)
		(net 1)
	)
	(via
		(at 148.95 92.31)
		(size 0.45)
		(drill 0.1)
		(layers "F.Cu" "B.Cu")
		(remove_unused_layers yes)
		(keep_end_layers yes)
		(zone_layer_connections "In1.Cu" "In4.Cu" "In6.Cu")
		(teardrops
			(best_length_ratio 0.4)
			(max_length 1)
			(best_width_ratio 0.9)
			(max_width 2)
			(curved_edges yes)
			(filter_ratio 0.9)
			(enabled yes)
			(allow_two_segments yes)
			(prefer_zone_connections yes)
		)
		(net 1)
	)
	(via
		(at 199.95 84.31)
		(size 0.45)
		(drill 0.1)
		(layers "F.Cu" "B.Cu")
		(remove_unused_layers yes)
		(keep_end_layers yes)
		(zone_layer_connections "In1.Cu" "In4.Cu" "In6.Cu")
		(teardrops
			(best_length_ratio 0.4)
			(max_length 1)
			(best_width_ratio 0.9)
			(max_width 2)
			(curved_edges yes)
			(filter_ratio 0.9)
			(enabled yes)
			(allow_two_segments yes)
			(prefer_zone_connections yes)
		)
		(net 1)
	)
	(via
		(at 203.95 70.31)
		(size 0.45)
		(drill 0.1)
		(layers "F.Cu" "B.Cu")
		(remove_unused_layers yes)
		(keep_end_layers yes)
		(free yes)
		(zone_layer_connections "In1.Cu" "In4.Cu" "In6.Cu")
		(teardrops
			(best_length_ratio 0.4)
			(max_length 1)
			(best_width_ratio 0.9)
			(max_width 2)
			(curved_edges yes)
			(filter_ratio 0.9)
			(enabled yes)
			(allow_two_segments yes)
			(prefer_zone_connections yes)
		)
		(net 1)
	)
	(via
		(at 201.7 88.56)
		(size 0.45)
		(drill 0.1)
		(layers "F.Cu" "B.Cu")
		(remove_unused_layers yes)
		(keep_end_layers yes)
		(zone_layer_connections "In1.Cu" "In4.Cu" "In6.Cu")
		(teardrops
			(best_length_ratio 0.4)
			(max_length 1)
			(best_width_ratio 0.9)
			(max_width 2)
			(curved_edges yes)
			(filter_ratio 0.9)
			(enabled yes)
			(allow_two_segments yes)
			(prefer_zone_connections yes)
		)
		(net 1)
	)
	(via
		(at 231.45 70.31)
		(size 0.45)
		(drill 0.1)
		(layers "F.Cu" "B.Cu")
		(remove_unused_layers yes)
		(keep_end_layers yes)
		(free yes)
		(zone_layer_connections "In1.Cu" "In4.Cu" "In6.Cu")
		(teardrops
			(best_length_ratio 0.4)
			(max_length 1)
			(best_width_ratio 0.9)
			(max_width 2)
			(curved_edges yes)
			(filter_ratio 0.9)
			(enabled yes)
			(allow_two_segments yes)
			(prefer_zone_connections yes)
		)
		(net 1)
	)
	(via
		(at 202.6 161.3)
		(size 0.45)
		(drill 0.1)
		(layers "F.Cu" "B.Cu")
		(teardrops
			(best_length_ratio 0.4)
			(max_length 1)
			(best_width_ratio 0.9)
			(max_width 2)
			(curved_edges yes)
			(filter_ratio 0.9)
			(enabled yes)
			(allow_two_segments yes)
			(prefer_zone_connections yes)
		)
		(net 1)
	)
	(via
		(at 152.5685 85.0595)
		(size 0.45)
		(drill 0.1)
		(layers "F.Cu" "B.Cu")
		(remove_unused_layers yes)
		(keep_end_layers yes)
		(zone_layer_connections "In1.Cu" "In4.Cu" "In6.Cu")
		(teardrops
			(best_length_ratio 0.4)
			(max_length 1)
			(best_width_ratio 0.9)
			(max_width 2)
			(curved_edges yes)
			(filter_ratio 0.9)
			(enabled yes)
			(allow_two_segments yes)
			(prefer_zone_connections yes)
		)
		(net 1)
	)
	(via
		(at 314.4645 115.4465)
		(size 0.45)
		(drill 0.1)
		(layers "F.Cu" "B.Cu")
		(remove_unused_layers yes)
		(keep_end_layers yes)
		(free yes)
		(zone_layer_connections "In1.Cu" "In4.Cu" "In6.Cu")
		(teardrops
			(best_length_ratio 0.4)
			(max_length 1)
			(best_width_ratio 0.9)
			(max_width 2)
			(curved_edges yes)
			(filter_ratio 0.9)
			(enabled yes)
			(allow_two_segments yes)
			(prefer_zone_connections yes)
		)
		(net 1)
	)
	(via
		(at 140.22 142.36)
		(size 0.45)
		(drill 0.1)
		(layers "F.Cu" "B.Cu")
		(remove_unused_layers yes)
		(keep_end_layers yes)
		(zone_layer_connections "In1.Cu" "In4.Cu" "In6.Cu")
		(teardrops
			(best_length_ratio 0.4)
			(max_length 1)
			(best_width_ratio 0.9)
			(max_width 2)
			(curved_edges yes)
			(filter_ratio 0.9)
			(enabled yes)
			(allow_two_segments yes)
			(prefer_zone_connections yes)
		)
		(net 1)
	)
	(via
		(at 297.95 123.31)
		(size 0.45)
		(drill 0.1)
		(layers "F.Cu" "B.Cu")
		(remove_unused_layers yes)
		(keep_end_layers yes)
		(zone_layer_connections "In1.Cu" "In4.Cu" "In6.Cu")
		(teardrops
			(best_length_ratio 0.4)
			(max_length 1)
			(best_width_ratio 0.9)
			(max_width 2)
			(curved_edges yes)
			(filter_ratio 0.9)
			(enabled yes)
			(allow_two_segments yes)
			(prefer_zone_connections yes)
		)
		(net 1)
	)
	(via
		(at 198.95 98.81)
		(size 0.45)
		(drill 0.1)
		(layers "F.Cu" "B.Cu")
		(remove_unused_layers yes)
		(keep_end_layers yes)
		(zone_layer_connections "In1.Cu" "In4.Cu" "In6.Cu")
		(teardrops
			(best_length_ratio 0.4)
			(max_length 1)
			(best_width_ratio 0.9)
			(max_width 2)
			(curved_edges yes)
			(filter_ratio 0.9)
			(enabled yes)
			(allow_two_segments yes)
			(prefer_zone_connections yes)
		)
		(net 1)
	)
	(via
		(at 259.45 121.81)
		(size 0.45)
		(drill 0.1)
		(layers "F.Cu" "B.Cu")
		(remove_unused_layers yes)
		(keep_end_layers yes)
		(zone_layer_connections "In1.Cu" "In4.Cu" "In6.Cu")
		(teardrops
			(best_length_ratio 0.4)
			(max_length 1)
			(best_width_ratio 0.9)
			(max_width 2)
			(curved_edges yes)
			(filter_ratio 0.9)
			(enabled yes)
			(allow_two_segments yes)
			(prefer_zone_connections yes)
		)
		(net 1)
	)
	(via
		(at 263.95 126.31)
		(size 0.45)
		(drill 0.1)
		(layers "F.Cu" "B.Cu")
		(remove_unused_layers yes)
		(keep_end_layers yes)
		(zone_layer_connections "In1.Cu" "In4.Cu" "In6.Cu")
		(teardrops
			(best_length_ratio 0.4)
			(max_length 1)
			(best_width_ratio 0.9)
			(max_width 2)
			(curved_edges yes)
			(filter_ratio 0.9)
			(enabled yes)
			(allow_two_segments yes)
			(prefer_zone_connections yes)
		)
		(net 1)
	)
	(via
		(at 151.45 74.31)
		(size 0.45)
		(drill 0.1)
		(layers "F.Cu" "B.Cu")
		(remove_unused_layers yes)
		(keep_end_layers yes)
		(zone_layer_connections "In1.Cu" "In4.Cu" "In6.Cu")
		(teardrops
			(best_length_ratio 0.4)
			(max_length 1)
			(best_width_ratio 0.9)
			(max_width 2)
			(curved_edges yes)
			(filter_ratio 0.9)
			(enabled yes)
			(allow_two_segments yes)
			(prefer_zone_connections yes)
		)
		(net 1)
	)
	(via
		(at 213.45 90.81)
		(size 0.45)
		(drill 0.1)
		(layers "F.Cu" "B.Cu")
		(remove_unused_layers yes)
		(keep_end_layers yes)
		(free yes)
		(zone_layer_connections "In1.Cu" "In4.Cu" "In6.Cu")
		(teardrops
			(best_length_ratio 0.4)
			(max_length 1)
			(best_width_ratio 0.9)
			(max_width 2)
			(curved_edges yes)
			(filter_ratio 0.9)
			(enabled yes)
			(allow_two_segments yes)
			(prefer_zone_connections yes)
		)
		(net 1)
	)
	(via
		(at 131.45 170.81)
		(size 0.45)
		(drill 0.1)
		(layers "F.Cu" "B.Cu")
		(remove_unused_layers yes)
		(keep_end_layers yes)
		(zone_layer_connections "In1.Cu" "In4.Cu" "In6.Cu")
		(teardrops
			(best_length_ratio 0.4)
			(max_length 1)
			(best_width_ratio 0.9)
			(max_width 2)
			(curved_edges yes)
			(filter_ratio 0.9)
			(enabled yes)
			(allow_two_segments yes)
			(prefer_zone_connections yes)
		)
		(net 1)
	)
	(via
		(at 290.95 147.31)
		(size 0.45)
		(drill 0.1)
		(layers "F.Cu" "B.Cu")
		(remove_unused_layers yes)
		(keep_end_layers yes)
		(zone_layer_connections "In1.Cu" "In4.Cu" "In6.Cu")
		(teardrops
			(best_length_ratio 0.4)
			(max_length 1)
			(best_width_ratio 0.9)
			(max_width 2)
			(curved_edges yes)
			(filter_ratio 0.9)
			(enabled yes)
			(allow_two_segments yes)
			(prefer_zone_connections yes)
		)
		(net 1)
	)
	(via
		(at 196.05 161.921)
		(size 0.45)
		(drill 0.1)
		(layers "F.Cu" "B.Cu")
		(teardrops
			(best_length_ratio 0.4)
			(max_length 1)
			(best_width_ratio 0.9)
			(max_width 2)
			(curved_edges yes)
			(filter_ratio 0.9)
			(enabled yes)
			(allow_two_segments yes)
			(prefer_zone_connections yes)
		)
		(net 1)
	)
	(via
		(at 173.203893 94.909175)
		(size 0.45)
		(drill 0.1)
		(layers "F.Cu" "B.Cu")
		(remove_unused_layers yes)
		(keep_end_layers yes)
		(zone_layer_connections "In1.Cu" "In4.Cu" "In6.Cu")
		(teardrops
			(best_length_ratio 0.4)
			(max_length 1)
			(best_width_ratio 0.9)
			(max_width 2)
			(curved_edges yes)
			(filter_ratio 0.9)
			(enabled yes)
			(allow_two_segments yes)
			(prefer_zone_connections yes)
		)
		(net 1)
	)
	(via
		(at 211.6 169.975)
		(size 0.45)
		(drill 0.1)
		(layers "F.Cu" "B.Cu")
		(teardrops
			(best_length_ratio 0.4)
			(max_length 1)
			(best_width_ratio 0.9)
			(max_width 2)
			(curved_edges yes)
			(filter_ratio 0.9)
			(enabled yes)
			(allow_two_segments yes)
			(prefer_zone_connections yes)
		)
		(net 1)
	)
	(via
		(at 310.075 78.342002)
		(size 0.45)
		(drill 0.1)
		(layers "F.Cu" "B.Cu")
		(remove_unused_layers yes)
		(keep_end_layers yes)
		(zone_layer_connections "In1.Cu" "In4.Cu" "In6.Cu")
		(teardrops
			(best_length_ratio 0.4)
			(max_length 1)
			(best_width_ratio 0.9)
			(max_width 2)
			(curved_edges yes)
			(filter_ratio 0.9)
			(enabled yes)
			(allow_two_segments yes)
			(prefer_zone_connections yes)
		)
		(net 1)
	)
	(via
		(at 163.4 150.2)
		(size 0.45)
		(drill 0.1)
		(layers "F.Cu" "B.Cu")
		(teardrops
			(best_length_ratio 0.4)
			(max_length 1)
			(best_width_ratio 0.9)
			(max_width 2)
			(curved_edges yes)
			(filter_ratio 0.9)
			(enabled yes)
			(allow_two_segments yes)
			(prefer_zone_connections yes)
		)
		(net 1)
	)
	(via
		(at 159.15 72.45)
		(size 0.45)
		(drill 0.1)
		(layers "F.Cu" "B.Cu")
		(remove_unused_layers yes)
		(keep_end_layers yes)
		(zone_layer_connections "In1.Cu" "In4.Cu" "In6.Cu")
		(teardrops
			(best_length_ratio 0.4)
			(max_length 1)
			(best_width_ratio 0.9)
			(max_width 2)
			(curved_edges yes)
			(filter_ratio 0.9)
			(enabled yes)
			(allow_two_segments yes)
			(prefer_zone_connections yes)
		)
		(net 1)
	)
	(via
		(at 136.52 162.76)
		(size 0.45)
		(drill 0.1)
		(layers "F.Cu" "B.Cu")
		(remove_unused_layers yes)
		(keep_end_layers yes)
		(zone_layer_connections "In1.Cu" "In4.Cu" "In6.Cu")
		(teardrops
			(best_length_ratio 0.4)
			(max_length 1)
			(best_width_ratio 0.9)
			(max_width 2)
			(curved_edges yes)
			(filter_ratio 0.9)
			(enabled yes)
			(allow_two_segments yes)
			(prefer_zone_connections yes)
		)
		(net 1)
	)
	(via
		(at 239.95 130.81)
		(size 0.45)
		(drill 0.1)
		(layers "F.Cu" "B.Cu")
		(remove_unused_layers yes)
		(keep_end_layers yes)
		(zone_layer_connections "In1.Cu" "In4.Cu" "In6.Cu")
		(teardrops
			(best_length_ratio 0.4)
			(max_length 1)
			(best_width_ratio 0.9)
			(max_width 2)
			(curved_edges yes)
			(filter_ratio 0.9)
			(enabled yes)
			(allow_two_segments yes)
			(prefer_zone_connections yes)
		)
		(net 1)
	)
	(via
		(at 281.45 98.31)
		(size 0.45)
		(drill 0.1)
		(layers "F.Cu" "B.Cu")
		(remove_unused_layers yes)
		(keep_end_layers yes)
		(zone_layer_connections "In1.Cu" "In4.Cu" "In6.Cu")
		(teardrops
			(best_length_ratio 0.4)
			(max_length 1)
			(best_width_ratio 0.9)
			(max_width 2)
			(curved_edges yes)
			(filter_ratio 0.9)
			(enabled yes)
			(allow_two_segments yes)
			(prefer_zone_connections yes)
		)
		(net 1)
	)
	(via
		(at 234.4 167.2)
		(size 0.45)
		(drill 0.1)
		(layers "F.Cu" "B.Cu")
		(teardrops
			(best_length_ratio 0.4)
			(max_length 1)
			(best_width_ratio 0.9)
			(max_width 2)
			(curved_edges yes)
			(filter_ratio 0.9)
			(enabled yes)
			(allow_two_segments yes)
			(prefer_zone_connections yes)
		)
		(net 1)
	)
	(via
		(at 95.45 130.81)
		(size 0.45)
		(drill 0.1)
		(layers "F.Cu" "B.Cu")
		(remove_unused_layers yes)
		(keep_end_layers yes)
		(zone_layer_connections "In1.Cu" "In4.Cu" "In6.Cu")
		(teardrops
			(best_length_ratio 0.4)
			(max_length 1)
			(best_width_ratio 0.9)
			(max_width 2)
			(curved_edges yes)
			(filter_ratio 0.9)
			(enabled yes)
			(allow_two_segments yes)
			(prefer_zone_connections yes)
		)
		(net 1)
	)
	(via
		(at 95.45 74.81)
		(size 0.45)
		(drill 0.1)
		(layers "F.Cu" "B.Cu")
		(remove_unused_layers yes)
		(keep_end_layers yes)
		(zone_layer_connections "In1.Cu" "In4.Cu" "In6.Cu")
		(teardrops
			(best_length_ratio 0.4)
			(max_length 1)
			(best_width_ratio 0.9)
			(max_width 2)
			(curved_edges yes)
			(filter_ratio 0.9)
			(enabled yes)
			(allow_two_segments yes)
			(prefer_zone_connections yes)
		)
		(net 1)
	)
	(via
		(at 297.45 136.31)
		(size 0.45)
		(drill 0.1)
		(layers "F.Cu" "B.Cu")
		(remove_unused_layers yes)
		(keep_end_layers yes)
		(zone_layer_connections "In1.Cu" "In4.Cu" "In6.Cu")
		(teardrops
			(best_length_ratio 0.4)
			(max_length 1)
			(best_width_ratio 0.9)
			(max_width 2)
			(curved_edges yes)
			(filter_ratio 0.9)
			(enabled yes)
			(allow_two_segments yes)
			(prefer_zone_connections yes)
		)
		(net 1)
	)
	(via
		(at 98.608195 165.099903)
		(size 0.45)
		(drill 0.1)
		(layers "F.Cu" "B.Cu")
		(remove_unused_layers yes)
		(keep_end_layers yes)
		(zone_layer_connections "In1.Cu" "In4.Cu" "In6.Cu")
		(teardrops
			(best_length_ratio 0.4)
			(max_length 1)
			(best_width_ratio 0.9)
			(max_width 2)
			(curved_edges yes)
			(filter_ratio 0.9)
			(enabled yes)
			(allow_two_segments yes)
			(prefer_zone_connections yes)
		)
		(net 1)
	)
	(via
		(at 102 169.47)
		(size 0.45)
		(drill 0.1)
		(layers "F.Cu" "B.Cu")
		(remove_unused_layers yes)
		(keep_end_layers yes)
		(zone_layer_connections "In1.Cu" "In4.Cu" "In6.Cu")
		(teardrops
			(best_length_ratio 0.4)
			(max_length 1)
			(best_width_ratio 0.9)
			(max_width 2)
			(curved_edges yes)
			(filter_ratio 0.9)
			(enabled yes)
			(allow_two_segments yes)
			(prefer_zone_connections yes)
		)
		(net 1)
	)
	(via
		(at 105.45 137.81)
		(size 0.45)
		(drill 0.1)
		(layers "F.Cu" "B.Cu")
		(remove_unused_layers yes)
		(keep_end_layers yes)
		(zone_layer_connections "In1.Cu" "In4.Cu" "In6.Cu")
		(teardrops
			(best_length_ratio 0.4)
			(max_length 1)
			(best_width_ratio 0.9)
			(max_width 2)
			(curved_edges yes)
			(filter_ratio 0.9)
			(enabled yes)
			(allow_two_segments yes)
			(prefer_zone_connections yes)
		)
		(net 1)
	)
	(via
		(at 232.95 89.31)
		(size 0.45)
		(drill 0.1)
		(layers "F.Cu" "B.Cu")
		(remove_unused_layers yes)
		(keep_end_layers yes)
		(free yes)
		(zone_layer_connections "In1.Cu" "In4.Cu" "In6.Cu")
		(teardrops
			(best_length_ratio 0.4)
			(max_length 1)
			(best_width_ratio 0.9)
			(max_width 2)
			(curved_edges yes)
			(filter_ratio 0.9)
			(enabled yes)
			(allow_two_segments yes)
			(prefer_zone_connections yes)
		)
		(net 1)
	)
	(via
		(at 190.65 160.25)
		(size 0.45)
		(drill 0.1)
		(layers "F.Cu" "B.Cu")
		(teardrops
			(best_length_ratio 0.4)
			(max_length 1)
			(best_width_ratio 0.9)
			(max_width 2)
			(curved_edges yes)
			(filter_ratio 0.9)
			(enabled yes)
			(allow_two_segments yes)
			(prefer_zone_connections yes)
		)
		(net 1)
	)
	(via
		(at 101.45 90.81)
		(size 0.45)
		(drill 0.1)
		(layers "F.Cu" "B.Cu")
		(remove_unused_layers yes)
		(keep_end_layers yes)
		(zone_layer_connections "In1.Cu" "In4.Cu" "In6.Cu")
		(teardrops
			(best_length_ratio 0.4)
			(max_length 1)
			(best_width_ratio 0.9)
			(max_width 2)
			(curved_edges yes)
			(filter_ratio 0.9)
			(enabled yes)
			(allow_two_segments yes)
			(prefer_zone_connections yes)
		)
		(net 1)
	)
	(via
		(at 310.95 170.81)
		(size 0.45)
		(drill 0.1)
		(layers "F.Cu" "B.Cu")
		(remove_unused_layers yes)
		(keep_end_layers yes)
		(zone_layer_connections "In1.Cu" "In4.Cu" "In6.Cu")
		(teardrops
			(best_length_ratio 0.4)
			(max_length 1)
			(best_width_ratio 0.9)
			(max_width 2)
			(curved_edges yes)
			(filter_ratio 0.9)
			(enabled yes)
			(allow_two_segments yes)
			(prefer_zone_connections yes)
		)
		(net 1)
	)
	(via
		(at 311.474999 120.86)
		(size 0.45)
		(drill 0.1)
		(layers "F.Cu" "B.Cu")
		(remove_unused_layers yes)
		(keep_end_layers yes)
		(zone_layer_connections "In1.Cu" "In4.Cu" "In6.Cu")
		(teardrops
			(best_length_ratio 0.4)
			(max_length 1)
			(best_width_ratio 0.9)
			(max_width 2)
			(curved_edges yes)
			(filter_ratio 0.9)
			(enabled yes)
			(allow_two_segments yes)
			(prefer_zone_connections yes)
		)
		(net 1)
	)
	(via
		(at 290.95 92.81)
		(size 0.45)
		(drill 0.1)
		(layers "F.Cu" "B.Cu")
		(remove_unused_layers yes)
		(keep_end_layers yes)
		(zone_layer_connections "In1.Cu" "In4.Cu" "In6.Cu")
		(teardrops
			(best_length_ratio 0.4)
			(max_length 1)
			(best_width_ratio 0.9)
			(max_width 2)
			(curved_edges yes)
			(filter_ratio 0.9)
			(enabled yes)
			(allow_two_segments yes)
			(prefer_zone_connections yes)
		)
		(net 1)
	)
	(via
		(at 174.703893 102.409175)
		(size 0.45)
		(drill 0.1)
		(layers "F.Cu" "B.Cu")
		(remove_unused_layers yes)
		(keep_end_layers yes)
		(zone_layer_connections "In1.Cu" "In4.Cu" "In6.Cu")
		(teardrops
			(best_length_ratio 0.4)
			(max_length 1)
			(best_width_ratio 0.9)
			(max_width 2)
			(curved_edges yes)
			(filter_ratio 0.9)
			(enabled yes)
			(allow_two_segments yes)
			(prefer_zone_connections yes)
		)
		(net 1)
	)
	(via
		(at 277.95 106.31)
		(size 0.45)
		(drill 0.1)
		(layers "F.Cu" "B.Cu")
		(remove_unused_layers yes)
		(keep_end_layers yes)
		(zone_layer_connections "In1.Cu" "In4.Cu" "In6.Cu")
		(teardrops
			(best_length_ratio 0.4)
			(max_length 1)
			(best_width_ratio 0.9)
			(max_width 2)
			(curved_edges yes)
			(filter_ratio 0.9)
			(enabled yes)
			(allow_two_segments yes)
			(prefer_zone_connections yes)
		)
		(net 1)
	)
	(via
		(at 296.75 101.11)
		(size 0.45)
		(drill 0.1)
		(layers "F.Cu" "B.Cu")
		(remove_unused_layers yes)
		(keep_end_layers yes)
		(zone_layer_connections "In1.Cu" "In4.Cu" "In6.Cu")
		(teardrops
			(best_length_ratio 0.4)
			(max_length 1)
			(best_width_ratio 0.9)
			(max_width 2)
			(curved_edges yes)
			(filter_ratio 0.9)
			(enabled yes)
			(allow_two_segments yes)
			(prefer_zone_connections yes)
		)
		(net 1)
	)
	(via
		(at 187.95 70.31)
		(size 0.45)
		(drill 0.1)
		(layers "F.Cu" "B.Cu")
		(remove_unused_layers yes)
		(keep_end_layers yes)
		(zone_layer_connections "In1.Cu" "In4.Cu" "In6.Cu")
		(teardrops
			(best_length_ratio 0.4)
			(max_length 1)
			(best_width_ratio 0.9)
			(max_width 2)
			(curved_edges yes)
			(filter_ratio 0.9)
			(enabled yes)
			(allow_two_segments yes)
			(prefer_zone_connections yes)
		)
		(net 1)
	)
	(via
		(at 112.95 113.31)
		(size 0.45)
		(drill 0.1)
		(layers "F.Cu" "B.Cu")
		(remove_unused_layers yes)
		(keep_end_layers yes)
		(zone_layer_connections "In1.Cu" "In4.Cu" "In6.Cu")
		(teardrops
			(best_length_ratio 0.4)
			(max_length 1)
			(best_width_ratio 0.9)
			(max_width 2)
			(curved_edges yes)
			(filter_ratio 0.9)
			(enabled yes)
			(allow_two_segments yes)
			(prefer_zone_connections yes)
		)
		(net 1)
	)
	(via
		(at 196.95 83.81)
		(size 0.45)
		(drill 0.1)
		(layers "F.Cu" "B.Cu")
		(remove_unused_layers yes)
		(keep_end_layers yes)
		(zone_layer_connections "In1.Cu" "In4.Cu" "In6.Cu")
		(teardrops
			(best_length_ratio 0.4)
			(max_length 1)
			(best_width_ratio 0.9)
			(max_width 2)
			(curved_edges yes)
			(filter_ratio 0.9)
			(enabled yes)
			(allow_two_segments yes)
			(prefer_zone_connections yes)
		)
		(net 1)
	)
	(via
		(at 204.2 123.4)
		(size 0.45)
		(drill 0.1)
		(layers "F.Cu" "B.Cu")
		(remove_unused_layers yes)
		(keep_end_layers yes)
		(zone_layer_connections "In1.Cu" "In4.Cu" "In6.Cu")
		(teardrops
			(best_length_ratio 0.4)
			(max_length 1)
			(best_width_ratio 0.9)
			(max_width 2)
			(curved_edges yes)
			(filter_ratio 0.9)
			(enabled yes)
			(allow_two_segments yes)
			(prefer_zone_connections yes)
		)
		(net 1)
	)
	(via
		(at 95.45 128.81)
		(size 0.45)
		(drill 0.1)
		(layers "F.Cu" "B.Cu")
		(remove_unused_layers yes)
		(keep_end_layers yes)
		(zone_layer_connections "In1.Cu" "In4.Cu" "In6.Cu")
		(teardrops
			(best_length_ratio 0.4)
			(max_length 1)
			(best_width_ratio 0.9)
			(max_width 2)
			(curved_edges yes)
			(filter_ratio 0.9)
			(enabled yes)
			(allow_two_segments yes)
			(prefer_zone_connections yes)
		)
		(net 1)
	)
	(via
		(at 222.45 90.81)
		(size 0.45)
		(drill 0.1)
		(layers "F.Cu" "B.Cu")
		(remove_unused_layers yes)
		(keep_end_layers yes)
		(free yes)
		(zone_layer_connections "In1.Cu" "In4.Cu" "In6.Cu")
		(teardrops
			(best_length_ratio 0.4)
			(max_length 1)
			(best_width_ratio 0.9)
			(max_width 2)
			(curved_edges yes)
			(filter_ratio 0.9)
			(enabled yes)
			(allow_two_segments yes)
			(prefer_zone_connections yes)
		)
		(net 1)
	)
	(via
		(at 135.45 159.31)
		(size 0.45)
		(drill 0.1)
		(layers "F.Cu" "B.Cu")
		(remove_unused_layers yes)
		(keep_end_layers yes)
		(zone_layer_connections "In1.Cu" "In4.Cu" "In6.Cu")
		(teardrops
			(best_length_ratio 0.4)
			(max_length 1)
			(best_width_ratio 0.9)
			(max_width 2)
			(curved_edges yes)
			(filter_ratio 0.9)
			(enabled yes)
			(allow_two_segments yes)
			(prefer_zone_connections yes)
		)
		(net 1)
	)
	(via
		(at 241.95 157.31)
		(size 0.45)
		(drill 0.1)
		(layers "F.Cu" "B.Cu")
		(remove_unused_layers yes)
		(keep_end_layers yes)
		(free yes)
		(zone_layer_connections "In1.Cu" "In4.Cu" "In6.Cu")
		(teardrops
			(best_length_ratio 0.4)
			(max_length 1)
			(best_width_ratio 0.9)
			(max_width 2)
			(curved_edges yes)
			(filter_ratio 0.9)
			(enabled yes)
			(allow_two_segments yes)
			(prefer_zone_connections yes)
		)
		(net 1)
	)
	(via
		(at 174.7 103.85)
		(size 0.45)
		(drill 0.1)
		(layers "F.Cu" "B.Cu")
		(remove_unused_layers yes)
		(keep_end_layers yes)
		(zone_layer_connections "In1.Cu" "In4.Cu" "In6.Cu")
		(teardrops
			(best_length_ratio 0.4)
			(max_length 1)
			(best_width_ratio 0.9)
			(max_width 2)
			(curved_edges yes)
			(filter_ratio 0.9)
			(enabled yes)
			(allow_two_segments yes)
			(prefer_zone_connections yes)
		)
		(net 1)
	)
	(via
		(at 108.95 74.31)
		(size 0.45)
		(drill 0.1)
		(layers "F.Cu" "B.Cu")
		(remove_unused_layers yes)
		(keep_end_layers yes)
		(zone_layer_connections "In1.Cu" "In4.Cu" "In6.Cu")
		(teardrops
			(best_length_ratio 0.4)
			(max_length 1)
			(best_width_ratio 0.9)
			(max_width 2)
			(curved_edges yes)
			(filter_ratio 0.9)
			(enabled yes)
			(allow_two_segments yes)
			(prefer_zone_connections yes)
		)
		(net 1)
	)
	(via
		(at 226.95 86.31)
		(size 0.45)
		(drill 0.1)
		(layers "F.Cu" "B.Cu")
		(remove_unused_layers yes)
		(keep_end_layers yes)
		(zone_layer_connections "In1.Cu" "In4.Cu" "In6.Cu")
		(teardrops
			(best_length_ratio 0.4)
			(max_length 1)
			(best_width_ratio 0.9)
			(max_width 2)
			(curved_edges yes)
			(filter_ratio 0.9)
			(enabled yes)
			(allow_two_segments yes)
			(prefer_zone_connections yes)
		)
		(net 1)
	)
	(via
		(at 304.697 75.04)
		(size 0.45)
		(drill 0.1)
		(layers "F.Cu" "B.Cu")
		(remove_unused_layers yes)
		(keep_end_layers yes)
		(zone_layer_connections "In1.Cu" "In4.Cu" "In6.Cu")
		(teardrops
			(best_length_ratio 0.4)
			(max_length 1)
			(best_width_ratio 0.9)
			(max_width 2)
			(curved_edges yes)
			(filter_ratio 0.9)
			(enabled yes)
			(allow_two_segments yes)
			(prefer_zone_connections yes)
		)
		(net 1)
	)
	(via
		(at 285.45 81.31)
		(size 0.45)
		(drill 0.1)
		(layers "F.Cu" "B.Cu")
		(remove_unused_layers yes)
		(keep_end_layers yes)
		(zone_layer_connections "In1.Cu" "In4.Cu" "In6.Cu")
		(teardrops
			(best_length_ratio 0.4)
			(max_length 1)
			(best_width_ratio 0.9)
			(max_width 2)
			(curved_edges yes)
			(filter_ratio 0.9)
			(enabled yes)
			(allow_two_segments yes)
			(prefer_zone_connections yes)
		)
		(net 1)
	)
	(via
		(at 197.55 161.9)
		(size 0.45)
		(drill 0.1)
		(layers "F.Cu" "B.Cu")
		(teardrops
			(best_length_ratio 0.4)
			(max_length 1)
			(best_width_ratio 0.9)
			(max_width 2)
			(curved_edges yes)
			(filter_ratio 0.9)
			(enabled yes)
			(allow_two_segments yes)
			(prefer_zone_connections yes)
		)
		(net 1)
	)
	(via
		(at 314.45 69.31)
		(size 0.45)
		(drill 0.1)
		(layers "F.Cu" "B.Cu")
		(remove_unused_layers yes)
		(keep_end_layers yes)
		(zone_layer_connections "In1.Cu" "In4.Cu" "In6.Cu")
		(teardrops
			(best_length_ratio 0.4)
			(max_length 1)
			(best_width_ratio 0.9)
			(max_width 2)
			(curved_edges yes)
			(filter_ratio 0.9)
			(enabled yes)
			(allow_two_segments yes)
			(prefer_zone_connections yes)
		)
		(net 1)
	)
	(via
		(at 309.18 118.71)
		(size 0.45)
		(drill 0.1)
		(layers "F.Cu" "B.Cu")
		(remove_unused_layers yes)
		(keep_end_layers yes)
		(free yes)
		(zone_layer_connections "In1.Cu" "In4.Cu" "In6.Cu")
		(teardrops
			(best_length_ratio 0.4)
			(max_length 1)
			(best_width_ratio 0.9)
			(max_width 2)
			(curved_edges yes)
			(filter_ratio 0.9)
			(enabled yes)
			(allow_two_segments yes)
			(prefer_zone_connections yes)
		)
		(net 1)
	)
	(via
		(at 311.45 78.81)
		(size 0.45)
		(drill 0.1)
		(layers "F.Cu" "B.Cu")
		(remove_unused_layers yes)
		(keep_end_layers yes)
		(free yes)
		(zone_layer_connections "In1.Cu" "In4.Cu" "In6.Cu")
		(teardrops
			(best_length_ratio 0.4)
			(max_length 1)
			(best_width_ratio 0.9)
			(max_width 2)
			(curved_edges yes)
			(filter_ratio 0.9)
			(enabled yes)
			(allow_two_segments yes)
			(prefer_zone_connections yes)
		)
		(net 1)
	)
	(via
		(at 108.075 161.1)
		(size 0.45)
		(drill 0.1)
		(layers "F.Cu" "B.Cu")
		(remove_unused_layers yes)
		(keep_end_layers yes)
		(free yes)
		(zone_layer_connections "In1.Cu" "In4.Cu" "In6.Cu")
		(teardrops
			(best_length_ratio 0.4)
			(max_length 1)
			(best_width_ratio 0.9)
			(max_width 2)
			(curved_edges yes)
			(filter_ratio 0.9)
			(enabled yes)
			(allow_two_segments yes)
			(prefer_zone_connections yes)
		)
		(net 1)
	)
	(via
		(at 227.4 143.5)
		(size 0.45)
		(drill 0.1)
		(layers "F.Cu" "B.Cu")
		(teardrops
			(best_length_ratio 0.4)
			(max_length 1)
			(best_width_ratio 0.9)
			(max_width 2)
			(curved_edges yes)
			(filter_ratio 0.9)
			(enabled yes)
			(allow_two_segments yes)
			(prefer_zone_connections yes)
		)
		(net 1)
	)
	(via
		(at 212.05 149.921)
		(size 0.45)
		(drill 0.1)
		(layers "F.Cu" "B.Cu")
		(teardrops
			(best_length_ratio 0.4)
			(max_length 1)
			(best_width_ratio 0.9)
			(max_width 2)
			(curved_edges yes)
			(filter_ratio 0.9)
			(enabled yes)
			(allow_two_segments yes)
			(prefer_zone_connections yes)
		)
		(net 1)
	)
	(via
		(at 309.174999 103.87)
		(size 0.45)
		(drill 0.1)
		(layers "F.Cu" "B.Cu")
		(remove_unused_layers yes)
		(keep_end_layers yes)
		(zone_layer_connections "In1.Cu" "In4.Cu" "In6.Cu")
		(teardrops
			(best_length_ratio 0.4)
			(max_length 1)
			(best_width_ratio 0.9)
			(max_width 2)
			(curved_edges yes)
			(filter_ratio 0.9)
			(enabled yes)
			(allow_two_segments yes)
			(prefer_zone_connections yes)
		)
		(net 1)
	)
	(via
		(at 220.8 154.1)
		(size 0.45)
		(drill 0.1)
		(layers "F.Cu" "B.Cu")
		(teardrops
			(best_length_ratio 0.4)
			(max_length 1)
			(best_width_ratio 0.9)
			(max_width 2)
			(curved_edges yes)
			(filter_ratio 0.9)
			(enabled yes)
			(allow_two_segments yes)
			(prefer_zone_connections yes)
		)
		(net 1)
	)
	(via
		(at 276.45 110.81)
		(size 0.45)
		(drill 0.1)
		(layers "F.Cu" "B.Cu")
		(remove_unused_layers yes)
		(keep_end_layers yes)
		(zone_layer_connections "In1.Cu" "In4.Cu" "In6.Cu")
		(teardrops
			(best_length_ratio 0.4)
			(max_length 1)
			(best_width_ratio 0.9)
			(max_width 2)
			(curved_edges yes)
			(filter_ratio 0.9)
			(enabled yes)
			(allow_two_segments yes)
			(prefer_zone_connections yes)
		)
		(net 1)
	)
	(via
		(at 206.65 165.2)
		(size 0.45)
		(drill 0.1)
		(layers "F.Cu" "B.Cu")
		(teardrops
			(best_length_ratio 0.4)
			(max_length 1)
			(best_width_ratio 0.9)
			(max_width 2)
			(curved_edges yes)
			(filter_ratio 0.9)
			(enabled yes)
			(allow_two_segments yes)
			(prefer_zone_connections yes)
		)
		(net 1)
	)
	(via
		(at 114.45 82.31)
		(size 0.45)
		(drill 0.1)
		(layers "F.Cu" "B.Cu")
		(remove_unused_layers yes)
		(keep_end_layers yes)
		(zone_layer_connections "In1.Cu" "In4.Cu" "In6.Cu")
		(teardrops
			(best_length_ratio 0.4)
			(max_length 1)
			(best_width_ratio 0.9)
			(max_width 2)
			(curved_edges yes)
			(filter_ratio 0.9)
			(enabled yes)
			(allow_two_segments yes)
			(prefer_zone_connections yes)
		)
		(net 1)
	)
	(via
		(at 210.5 164.35)
		(size 0.45)
		(drill 0.1)
		(layers "F.Cu" "B.Cu")
		(teardrops
			(best_length_ratio 0.4)
			(max_length 1)
			(best_width_ratio 0.9)
			(max_width 2)
			(curved_edges yes)
			(filter_ratio 0.9)
			(enabled yes)
			(allow_two_segments yes)
			(prefer_zone_connections yes)
		)
		(net 1)
	)
	(via
		(at 134.95 157.81)
		(size 0.45)
		(drill 0.1)
		(layers "F.Cu" "B.Cu")
		(remove_unused_layers yes)
		(keep_end_layers yes)
		(zone_layer_connections "In1.Cu" "In4.Cu" "In6.Cu")
		(teardrops
			(best_length_ratio 0.4)
			(max_length 1)
			(best_width_ratio 0.9)
			(max_width 2)
			(curved_edges yes)
			(filter_ratio 0.9)
			(enabled yes)
			(allow_two_segments yes)
			(prefer_zone_connections yes)
		)
		(net 1)
	)
	(via
		(at 147.45 141.86)
		(size 0.45)
		(drill 0.1)
		(layers "F.Cu" "B.Cu")
		(remove_unused_layers yes)
		(keep_end_layers yes)
		(zone_layer_connections "In1.Cu" "In4.Cu" "In6.Cu")
		(teardrops
			(best_length_ratio 0.4)
			(max_length 1)
			(best_width_ratio 0.9)
			(max_width 2)
			(curved_edges yes)
			(filter_ratio 0.9)
			(enabled yes)
			(allow_two_segments yes)
			(prefer_zone_connections yes)
		)
		(net 1)
	)
	(via
		(at 155.45 134.86)
		(size 0.45)
		(drill 0.1)
		(layers "F.Cu" "B.Cu")
		(remove_unused_layers yes)
		(keep_end_layers yes)
		(zone_layer_connections "In1.Cu" "In4.Cu" "In6.Cu")
		(teardrops
			(best_length_ratio 0.4)
			(max_length 1)
			(best_width_ratio 0.9)
			(max_width 2)
			(curved_edges yes)
			(filter_ratio 0.9)
			(enabled yes)
			(allow_two_segments yes)
			(prefer_zone_connections yes)
		)
		(net 1)
	)
	(via
		(at 288.199 74.96)
		(size 0.45)
		(drill 0.1)
		(layers "F.Cu" "B.Cu")
		(remove_unused_layers yes)
		(keep_end_layers yes)
		(free yes)
		(zone_layer_connections "In1.Cu" "In4.Cu" "In6.Cu")
		(teardrops
			(best_length_ratio 0.4)
			(max_length 1)
			(best_width_ratio 0.9)
			(max_width 2)
			(curved_edges yes)
			(filter_ratio 0.9)
			(enabled yes)
			(allow_two_segments yes)
			(prefer_zone_connections yes)
		)
		(net 1)
	)
	(via
		(at 152.5685 71.0605)
		(size 0.45)
		(drill 0.1)
		(layers "F.Cu" "B.Cu")
		(remove_unused_layers yes)
		(keep_end_layers yes)
		(zone_layer_connections "In1.Cu" "In4.Cu" "In6.Cu")
		(teardrops
			(best_length_ratio 0.4)
			(max_length 1)
			(best_width_ratio 0.9)
			(max_width 2)
			(curved_edges yes)
			(filter_ratio 0.9)
			(enabled yes)
			(allow_two_segments yes)
			(prefer_zone_connections yes)
		)
		(net 1)
	)
	(via
		(at 161.45 90.81)
		(size 0.45)
		(drill 0.1)
		(layers "F.Cu" "B.Cu")
		(remove_unused_layers yes)
		(keep_end_layers yes)
		(zone_layer_connections "In1.Cu" "In4.Cu" "In6.Cu")
		(teardrops
			(best_length_ratio 0.4)
			(max_length 1)
			(best_width_ratio 0.9)
			(max_width 2)
			(curved_edges yes)
			(filter_ratio 0.9)
			(enabled yes)
			(allow_two_segments yes)
			(prefer_zone_connections yes)
		)
		(net 1)
	)
	(via
		(at 255.45 166.41)
		(size 0.45)
		(drill 0.1)
		(layers "F.Cu" "B.Cu")
		(remove_unused_layers yes)
		(keep_end_layers yes)
		(zone_layer_connections "In1.Cu" "In4.Cu" "In6.Cu")
		(teardrops
			(best_length_ratio 0.4)
			(max_length 1)
			(best_width_ratio 0.9)
			(max_width 2)
			(curved_edges yes)
			(filter_ratio 0.9)
			(enabled yes)
			(allow_two_segments yes)
			(prefer_zone_connections yes)
		)
		(net 1)
	)
	(via
		(at 297.95 126.81)
		(size 0.45)
		(drill 0.1)
		(layers "F.Cu" "B.Cu")
		(remove_unused_layers yes)
		(keep_end_layers yes)
		(zone_layer_connections "In1.Cu" "In4.Cu" "In6.Cu")
		(teardrops
			(best_length_ratio 0.4)
			(max_length 1)
			(best_width_ratio 0.9)
			(max_width 2)
			(curved_edges yes)
			(filter_ratio 0.9)
			(enabled yes)
			(allow_two_segments yes)
			(prefer_zone_connections yes)
		)
		(net 1)
	)
	(via
		(at 114.33 107.65)
		(size 0.45)
		(drill 0.1)
		(layers "F.Cu" "B.Cu")
		(remove_unused_layers yes)
		(keep_end_layers yes)
		(zone_layer_connections "In1.Cu" "In4.Cu" "In6.Cu")
		(teardrops
			(best_length_ratio 0.4)
			(max_length 1)
			(best_width_ratio 0.9)
			(max_width 2)
			(curved_edges yes)
			(filter_ratio 0.9)
			(enabled yes)
			(allow_two_segments yes)
			(prefer_zone_connections yes)
		)
		(net 1)
	)
	(via
		(at 99.45 134.81)
		(size 0.45)
		(drill 0.1)
		(layers "F.Cu" "B.Cu")
		(remove_unused_layers yes)
		(keep_end_layers yes)
		(zone_layer_connections "In1.Cu" "In4.Cu" "In6.Cu")
		(teardrops
			(best_length_ratio 0.4)
			(max_length 1)
			(best_width_ratio 0.9)
			(max_width 2)
			(curved_edges yes)
			(filter_ratio 0.9)
			(enabled yes)
			(allow_two_segments yes)
			(prefer_zone_connections yes)
		)
		(net 1)
	)
	(via
		(at 249.45 166.41)
		(size 0.45)
		(drill 0.1)
		(layers "F.Cu" "B.Cu")
		(remove_unused_layers yes)
		(keep_end_layers yes)
		(free yes)
		(zone_layer_connections "In1.Cu" "In4.Cu" "In6.Cu")
		(teardrops
			(best_length_ratio 0.4)
			(max_length 1)
			(best_width_ratio 0.9)
			(max_width 2)
			(curved_edges yes)
			(filter_ratio 0.9)
			(enabled yes)
			(allow_two_segments yes)
			(prefer_zone_connections yes)
		)
		(net 1)
	)
	(via
		(at 284.95 94.31)
		(size 0.45)
		(drill 0.1)
		(layers "F.Cu" "B.Cu")
		(remove_unused_layers yes)
		(keep_end_layers yes)
		(zone_layer_connections "In1.Cu" "In4.Cu" "In6.Cu")
		(teardrops
			(best_length_ratio 0.4)
			(max_length 1)
			(best_width_ratio 0.9)
			(max_width 2)
			(curved_edges yes)
			(filter_ratio 0.9)
			(enabled yes)
			(allow_two_segments yes)
			(prefer_zone_connections yes)
		)
		(net 1)
	)
	(via
		(at 291.6 85.66)
		(size 0.45)
		(drill 0.1)
		(layers "F.Cu" "B.Cu")
		(remove_unused_layers yes)
		(keep_end_layers yes)
		(zone_layer_connections "In1.Cu" "In4.Cu" "In6.Cu")
		(teardrops
			(best_length_ratio 0.4)
			(max_length 1)
			(best_width_ratio 0.9)
			(max_width 2)
			(curved_edges yes)
			(filter_ratio 0.9)
			(enabled yes)
			(allow_two_segments yes)
			(prefer_zone_connections yes)
		)
		(net 1)
	)
	(via
		(at 115.809999 76.475)
		(size 0.45)
		(drill 0.1)
		(layers "F.Cu" "B.Cu")
		(remove_unused_layers yes)
		(keep_end_layers yes)
		(zone_layer_connections "In1.Cu" "In4.Cu" "In6.Cu")
		(teardrops
			(best_length_ratio 0.4)
			(max_length 1)
			(best_width_ratio 0.9)
			(max_width 2)
			(curved_edges yes)
			(filter_ratio 0.9)
			(enabled yes)
			(allow_two_segments yes)
			(prefer_zone_connections yes)
		)
		(net 1)
	)
	(via
		(at 195.70861 78.102163)
		(size 0.45)
		(drill 0.1)
		(layers "F.Cu" "B.Cu")
		(remove_unused_layers yes)
		(keep_end_layers yes)
		(zone_layer_connections "In1.Cu" "In4.Cu" "In6.Cu")
		(teardrops
			(best_length_ratio 0.4)
			(max_length 1)
			(best_width_ratio 0.9)
			(max_width 2)
			(curved_edges yes)
			(filter_ratio 0.9)
			(enabled yes)
			(allow_two_segments yes)
			(prefer_zone_connections yes)
		)
		(net 1)
	)
	(via
		(at 97.45 140.81)
		(size 0.45)
		(drill 0.1)
		(layers "F.Cu" "B.Cu")
		(remove_unused_layers yes)
		(keep_end_layers yes)
		(zone_layer_connections "In1.Cu" "In4.Cu" "In6.Cu")
		(teardrops
			(best_length_ratio 0.4)
			(max_length 1)
			(best_width_ratio 0.9)
			(max_width 2)
			(curved_edges yes)
			(filter_ratio 0.9)
			(enabled yes)
			(allow_two_segments yes)
			(prefer_zone_connections yes)
		)
		(net 1)
	)
	(via
		(at 317.4895 134.71)
		(size 0.45)
		(drill 0.1)
		(layers "F.Cu" "B.Cu")
		(remove_unused_layers yes)
		(keep_end_layers yes)
		(zone_layer_connections "In1.Cu" "In4.Cu" "In6.Cu")
		(teardrops
			(best_length_ratio 0.4)
			(max_length 1)
			(best_width_ratio 0.9)
			(max_width 2)
			(curved_edges yes)
			(filter_ratio 0.9)
			(enabled yes)
			(allow_two_segments yes)
			(prefer_zone_connections yes)
		)
		(net 1)
	)
	(via
		(at 127.449999 170.81)
		(size 0.45)
		(drill 0.1)
		(layers "F.Cu" "B.Cu")
		(remove_unused_layers yes)
		(keep_end_layers yes)
		(zone_layer_connections "In1.Cu" "In4.Cu" "In6.Cu")
		(teardrops
			(best_length_ratio 0.4)
			(max_length 1)
			(best_width_ratio 0.9)
			(max_width 2)
			(curved_edges yes)
			(filter_ratio 0.9)
			(enabled yes)
			(allow_two_segments yes)
			(prefer_zone_connections yes)
		)
		(net 1)
	)
	(via
		(at 151.45 71.31)
		(size 0.45)
		(drill 0.1)
		(layers "F.Cu" "B.Cu")
		(remove_unused_layers yes)
		(keep_end_layers yes)
		(zone_layer_connections "In1.Cu" "In4.Cu" "In6.Cu")
		(teardrops
			(best_length_ratio 0.4)
			(max_length 1)
			(best_width_ratio 0.9)
			(max_width 2)
			(curved_edges yes)
			(filter_ratio 0.9)
			(enabled yes)
			(allow_two_segments yes)
			(prefer_zone_connections yes)
		)
		(net 1)
	)
	(via
		(at 219.45 84.81)
		(size 0.45)
		(drill 0.1)
		(layers "F.Cu" "B.Cu")
		(remove_unused_layers yes)
		(keep_end_layers yes)
		(zone_layer_connections "In1.Cu" "In4.Cu" "In6.Cu")
		(teardrops
			(best_length_ratio 0.4)
			(max_length 1)
			(best_width_ratio 0.9)
			(max_width 2)
			(curved_edges yes)
			(filter_ratio 0.9)
			(enabled yes)
			(allow_two_segments yes)
			(prefer_zone_connections yes)
		)
		(net 1)
	)
	(via
		(at 122.07 169.435)
		(size 0.45)
		(drill 0.1)
		(layers "F.Cu" "B.Cu")
		(remove_unused_layers yes)
		(keep_end_layers yes)
		(zone_layer_connections "In1.Cu" "In4.Cu" "In6.Cu")
		(teardrops
			(best_length_ratio 0.4)
			(max_length 1)
			(best_width_ratio 0.9)
			(max_width 2)
			(curved_edges yes)
			(filter_ratio 0.9)
			(enabled yes)
			(allow_two_segments yes)
			(prefer_zone_connections yes)
		)
		(net 1)
	)
	(via
		(at 99.458 159.1)
		(size 0.45)
		(drill 0.1)
		(layers "F.Cu" "B.Cu")
		(remove_unused_layers yes)
		(keep_end_layers yes)
		(zone_layer_connections "In1.Cu" "In4.Cu" "In6.Cu")
		(teardrops
			(best_length_ratio 0.4)
			(max_length 1)
			(best_width_ratio 0.9)
			(max_width 2)
			(curved_edges yes)
			(filter_ratio 0.9)
			(enabled yes)
			(allow_two_segments yes)
			(prefer_zone_connections yes)
		)
		(net 1)
	)
	(via
		(at 112.89 149.88)
		(size 0.45)
		(drill 0.1)
		(layers "F.Cu" "B.Cu")
		(remove_unused_layers yes)
		(keep_end_layers yes)
		(zone_layer_connections "In1.Cu" "In4.Cu" "In6.Cu")
		(teardrops
			(best_length_ratio 0.4)
			(max_length 1)
			(best_width_ratio 0.9)
			(max_width 2)
			(curved_edges yes)
			(filter_ratio 0.9)
			(enabled yes)
			(allow_two_segments yes)
			(prefer_zone_connections yes)
		)
		(net 1)
	)
	(via
		(at 258.45 166.41)
		(size 0.45)
		(drill 0.1)
		(layers "F.Cu" "B.Cu")
		(remove_unused_layers yes)
		(keep_end_layers yes)
		(free yes)
		(zone_layer_connections "In1.Cu" "In4.Cu" "In6.Cu")
		(teardrops
			(best_length_ratio 0.4)
			(max_length 1)
			(best_width_ratio 0.9)
			(max_width 2)
			(curved_edges yes)
			(filter_ratio 0.9)
			(enabled yes)
			(allow_two_segments yes)
			(prefer_zone_connections yes)
		)
		(net 1)
	)
	(via
		(at 126.45 77.81)
		(size 0.45)
		(drill 0.1)
		(layers "F.Cu" "B.Cu")
		(remove_unused_layers yes)
		(keep_end_layers yes)
		(zone_layer_connections "In1.Cu" "In4.Cu" "In6.Cu")
		(teardrops
			(best_length_ratio 0.4)
			(max_length 1)
			(best_width_ratio 0.9)
			(max_width 2)
			(curved_edges yes)
			(filter_ratio 0.9)
			(enabled yes)
			(allow_two_segments yes)
			(prefer_zone_connections yes)
		)
		(net 1)
	)
	(via
		(at 308.45 87.81)
		(size 0.45)
		(drill 0.1)
		(layers "F.Cu" "B.Cu")
		(remove_unused_layers yes)
		(keep_end_layers yes)
		(zone_layer_connections "In1.Cu" "In4.Cu" "In6.Cu")
		(teardrops
			(best_length_ratio 0.4)
			(max_length 1)
			(best_width_ratio 0.9)
			(max_width 2)
			(curved_edges yes)
			(filter_ratio 0.9)
			(enabled yes)
			(allow_two_segments yes)
			(prefer_zone_connections yes)
		)
		(net 1)
	)
	(via
		(at 150.560241 114.575)
		(size 0.45)
		(drill 0.1)
		(layers "F.Cu" "B.Cu")
		(remove_unused_layers yes)
		(keep_end_layers yes)
		(zone_layer_connections "In1.Cu" "In4.Cu" "In6.Cu")
		(teardrops
			(best_length_ratio 0.4)
			(max_length 1)
			(best_width_ratio 0.9)
			(max_width 2)
			(curved_edges yes)
			(filter_ratio 0.9)
			(enabled yes)
			(allow_two_segments yes)
			(prefer_zone_connections yes)
		)
		(net 1)
	)
	(via
		(at 159.45 68.81)
		(size 0.45)
		(drill 0.1)
		(layers "F.Cu" "B.Cu")
		(remove_unused_layers yes)
		(keep_end_layers yes)
		(zone_layer_connections "In1.Cu" "In4.Cu" "In6.Cu")
		(teardrops
			(best_length_ratio 0.4)
			(max_length 1)
			(best_width_ratio 0.9)
			(max_width 2)
			(curved_edges yes)
			(filter_ratio 0.9)
			(enabled yes)
			(allow_two_segments yes)
			(prefer_zone_connections yes)
		)
		(net 1)
	)
	(via
		(at 292.95 170.81)
		(size 0.45)
		(drill 0.1)
		(layers "F.Cu" "B.Cu")
		(remove_unused_layers yes)
		(keep_end_layers yes)
		(zone_layer_connections "In1.Cu" "In4.Cu" "In6.Cu")
		(teardrops
			(best_length_ratio 0.4)
			(max_length 1)
			(best_width_ratio 0.9)
			(max_width 2)
			(curved_edges yes)
			(filter_ratio 0.9)
			(enabled yes)
			(allow_two_segments yes)
			(prefer_zone_connections yes)
		)
		(net 1)
	)
	(via
		(at 237.3 152.1)
		(size 0.45)
		(drill 0.1)
		(layers "F.Cu" "B.Cu")
		(remove_unused_layers yes)
		(keep_end_layers yes)
		(zone_layer_connections "In1.Cu" "In4.Cu" "In6.Cu")
		(teardrops
			(best_length_ratio 0.4)
			(max_length 1)
			(best_width_ratio 0.9)
			(max_width 2)
			(curved_edges yes)
			(filter_ratio 0.9)
			(enabled yes)
			(allow_two_segments yes)
			(prefer_zone_connections yes)
		)
		(net 1)
	)
	(via
		(at 144.45 80.81)
		(size 0.45)
		(drill 0.1)
		(layers "F.Cu" "B.Cu")
		(remove_unused_layers yes)
		(keep_end_layers yes)
		(zone_layer_connections "In1.Cu" "In4.Cu" "In6.Cu")
		(teardrops
			(best_length_ratio 0.4)
			(max_length 1)
			(best_width_ratio 0.9)
			(max_width 2)
			(curved_edges yes)
			(filter_ratio 0.9)
			(enabled yes)
			(allow_two_segments yes)
			(prefer_zone_connections yes)
		)
		(net 1)
	)
	(via
		(at 156.882 147.63)
		(size 0.45)
		(drill 0.1)
		(layers "F.Cu" "B.Cu")
		(remove_unused_layers yes)
		(keep_end_layers yes)
		(zone_layer_connections "In1.Cu" "In4.Cu" "In6.Cu")
		(teardrops
			(best_length_ratio 0.4)
			(max_length 1)
			(best_width_ratio 0.9)
			(max_width 2)
			(curved_edges yes)
			(filter_ratio 0.9)
			(enabled yes)
			(allow_two_segments yes)
			(prefer_zone_connections yes)
		)
		(net 1)
	)
	(via
		(at 190.75 158.9)
		(size 0.45)
		(drill 0.1)
		(layers "F.Cu" "B.Cu")
		(teardrops
			(best_length_ratio 0.4)
			(max_length 1)
			(best_width_ratio 0.9)
			(max_width 2)
			(curved_edges yes)
			(filter_ratio 0.9)
			(enabled yes)
			(allow_two_segments yes)
			(prefer_zone_connections yes)
		)
		(net 1)
	)
	(via
		(at 208.95 158.85)
		(size 0.45)
		(drill 0.1)
		(layers "F.Cu" "B.Cu")
		(remove_unused_layers yes)
		(keep_end_layers yes)
		(zone_layer_connections "In1.Cu" "In3.Cu" "In4.Cu" "In6.Cu")
		(teardrops
			(best_length_ratio 0.4)
			(max_length 1)
			(best_width_ratio 0.9)
			(max_width 2)
			(curved_edges yes)
			(filter_ratio 0.9)
			(enabled yes)
			(allow_two_segments yes)
			(prefer_zone_connections yes)
		)
		(net 1)
	)
	(via
		(at 135.95 83.81)
		(size 0.45)
		(drill 0.1)
		(layers "F.Cu" "B.Cu")
		(remove_unused_layers yes)
		(keep_end_layers yes)
		(zone_layer_connections "In1.Cu" "In4.Cu" "In6.Cu")
		(teardrops
			(best_length_ratio 0.4)
			(max_length 1)
			(best_width_ratio 0.9)
			(max_width 2)
			(curved_edges yes)
			(filter_ratio 0.9)
			(enabled yes)
			(allow_two_segments yes)
			(prefer_zone_connections yes)
		)
		(net 1)
	)
	(via
		(at 311.4005 94.3865)
		(size 0.45)
		(drill 0.1)
		(layers "F.Cu" "B.Cu")
		(remove_unused_layers yes)
		(keep_end_layers yes)
		(zone_layer_connections "In1.Cu" "In4.Cu" "In6.Cu")
		(teardrops
			(best_length_ratio 0.4)
			(max_length 1)
			(best_width_ratio 0.9)
			(max_width 2)
			(curved_edges yes)
			(filter_ratio 0.9)
			(enabled yes)
			(allow_two_segments yes)
			(prefer_zone_connections yes)
		)
		(net 1)
	)
	(via
		(at 318.95 80.31)
		(size 0.45)
		(drill 0.1)
		(layers "F.Cu" "B.Cu")
		(remove_unused_layers yes)
		(keep_end_layers yes)
		(zone_layer_connections "In1.Cu" "In4.Cu" "In6.Cu")
		(teardrops
			(best_length_ratio 0.4)
			(max_length 1)
			(best_width_ratio 0.9)
			(max_width 2)
			(curved_edges yes)
			(filter_ratio 0.9)
			(enabled yes)
			(allow_two_segments yes)
			(prefer_zone_connections yes)
		)
		(net 1)
	)
	(via
		(at 99.46 162.1)
		(size 0.45)
		(drill 0.1)
		(layers "F.Cu" "B.Cu")
		(remove_unused_layers yes)
		(keep_end_layers yes)
		(zone_layer_connections "In1.Cu" "In4.Cu" "In6.Cu")
		(teardrops
			(best_length_ratio 0.4)
			(max_length 1)
			(best_width_ratio 0.9)
			(max_width 2)
			(curved_edges yes)
			(filter_ratio 0.9)
			(enabled yes)
			(allow_two_segments yes)
			(prefer_zone_connections yes)
		)
		(net 1)
	)
	(via
		(at 317.7 163.31)
		(size 0.45)
		(drill 0.1)
		(layers "F.Cu" "B.Cu")
		(remove_unused_layers yes)
		(keep_end_layers yes)
		(zone_layer_connections "In1.Cu" "In4.Cu" "In6.Cu")
		(teardrops
			(best_length_ratio 0.4)
			(max_length 1)
			(best_width_ratio 0.9)
			(max_width 2)
			(curved_edges yes)
			(filter_ratio 0.9)
			(enabled yes)
			(allow_two_segments yes)
			(prefer_zone_connections yes)
		)
		(net 1)
	)
	(via
		(at 112.95 111.31)
		(size 0.45)
		(drill 0.1)
		(layers "F.Cu" "B.Cu")
		(remove_unused_layers yes)
		(keep_end_layers yes)
		(zone_layer_connections "In1.Cu" "In4.Cu" "In6.Cu")
		(teardrops
			(best_length_ratio 0.4)
			(max_length 1)
			(best_width_ratio 0.9)
			(max_width 2)
			(curved_edges yes)
			(filter_ratio 0.9)
			(enabled yes)
			(allow_two_segments yes)
			(prefer_zone_connections yes)
		)
		(net 1)
	)
	(via
		(at 95.45 122.81)
		(size 0.45)
		(drill 0.1)
		(layers "F.Cu" "B.Cu")
		(remove_unused_layers yes)
		(keep_end_layers yes)
		(zone_layer_connections "In1.Cu" "In4.Cu" "In6.Cu")
		(teardrops
			(best_length_ratio 0.4)
			(max_length 1)
			(best_width_ratio 0.9)
			(max_width 2)
			(curved_edges yes)
			(filter_ratio 0.9)
			(enabled yes)
			(allow_two_segments yes)
			(prefer_zone_connections yes)
		)
		(net 1)
	)
	(via
		(at 220.6 160.5)
		(size 0.45)
		(drill 0.1)
		(layers "F.Cu" "B.Cu")
		(teardrops
			(best_length_ratio 0.4)
			(max_length 1)
			(best_width_ratio 0.9)
			(max_width 2)
			(curved_edges yes)
			(filter_ratio 0.9)
			(enabled yes)
			(allow_two_segments yes)
			(prefer_zone_connections yes)
		)
		(net 1)
	)
	(via
		(at 285.45 125.31)
		(size 0.45)
		(drill 0.1)
		(layers "F.Cu" "B.Cu")
		(remove_unused_layers yes)
		(keep_end_layers yes)
		(zone_layer_connections "In1.Cu" "In4.Cu" "In6.Cu")
		(teardrops
			(best_length_ratio 0.4)
			(max_length 1)
			(best_width_ratio 0.9)
			(max_width 2)
			(curved_edges yes)
			(filter_ratio 0.9)
			(enabled yes)
			(allow_two_segments yes)
			(prefer_zone_connections yes)
		)
		(net 1)
	)
	(via
		(at 127.29 145.86)
		(size 0.45)
		(drill 0.1)
		(layers "F.Cu" "B.Cu")
		(remove_unused_layers yes)
		(keep_end_layers yes)
		(zone_layer_connections "In1.Cu" "In4.Cu" "In6.Cu")
		(teardrops
			(best_length_ratio 0.4)
			(max_length 1)
			(best_width_ratio 0.9)
			(max_width 2)
			(curved_edges yes)
			(filter_ratio 0.9)
			(enabled yes)
			(allow_two_segments yes)
			(prefer_zone_connections yes)
		)
		(net 1)
	)
	(via
		(at 197.9 158.275)
		(size 0.45)
		(drill 0.1)
		(layers "F.Cu" "B.Cu")
		(teardrops
			(best_length_ratio 0.4)
			(max_length 1)
			(best_width_ratio 0.9)
			(max_width 2)
			(curved_edges yes)
			(filter_ratio 0.9)
			(enabled yes)
			(allow_two_segments yes)
			(prefer_zone_connections yes)
		)
		(net 1)
	)
	(via
		(at 214.5 123)
		(size 0.45)
		(drill 0.1)
		(layers "F.Cu" "B.Cu")
		(remove_unused_layers yes)
		(keep_end_layers yes)
		(zone_layer_connections "In1.Cu" "In4.Cu" "In6.Cu")
		(teardrops
			(best_length_ratio 0.4)
			(max_length 1)
			(best_width_ratio 0.9)
			(max_width 2)
			(curved_edges yes)
			(filter_ratio 0.9)
			(enabled yes)
			(allow_two_segments yes)
			(prefer_zone_connections yes)
		)
		(net 1)
	)
	(via
		(at 127.249587 104.234703)
		(size 0.45)
		(drill 0.1)
		(layers "F.Cu" "B.Cu")
		(remove_unused_layers yes)
		(keep_end_layers yes)
		(zone_layer_connections "In1.Cu" "In4.Cu" "In6.Cu")
		(teardrops
			(best_length_ratio 0.4)
			(max_length 1)
			(best_width_ratio 0.9)
			(max_width 2)
			(curved_edges yes)
			(filter_ratio 0.9)
			(enabled yes)
			(allow_two_segments yes)
			(prefer_zone_connections yes)
		)
		(net 1)
	)
	(via
		(at 172.95 92.31)
		(size 0.45)
		(drill 0.1)
		(layers "F.Cu" "B.Cu")
		(remove_unused_layers yes)
		(keep_end_layers yes)
		(zone_layer_connections "In1.Cu" "In4.Cu" "In6.Cu")
		(teardrops
			(best_length_ratio 0.4)
			(max_length 1)
			(best_width_ratio 0.9)
			(max_width 2)
			(curved_edges yes)
			(filter_ratio 0.9)
			(enabled yes)
			(allow_two_segments yes)
			(prefer_zone_connections yes)
		)
		(net 1)
	)
	(via
		(at 105.45 139.31)
		(size 0.45)
		(drill 0.1)
		(layers "F.Cu" "B.Cu")
		(remove_unused_layers yes)
		(keep_end_layers yes)
		(zone_layer_connections "In1.Cu" "In4.Cu" "In6.Cu")
		(teardrops
			(best_length_ratio 0.4)
			(max_length 1)
			(best_width_ratio 0.9)
			(max_width 2)
			(curved_edges yes)
			(filter_ratio 0.9)
			(enabled yes)
			(allow_two_segments yes)
			(prefer_zone_connections yes)
		)
		(net 1)
	)
	(via
		(at 297.45 89.81)
		(size 0.45)
		(drill 0.1)
		(layers "F.Cu" "B.Cu")
		(remove_unused_layers yes)
		(keep_end_layers yes)
		(zone_layer_connections "In1.Cu" "In4.Cu" "In6.Cu")
		(teardrops
			(best_length_ratio 0.4)
			(max_length 1)
			(best_width_ratio 0.9)
			(max_width 2)
			(curved_edges yes)
			(filter_ratio 0.9)
			(enabled yes)
			(allow_two_segments yes)
			(prefer_zone_connections yes)
		)
		(net 1)
	)
	(via
		(at 95.45 163.31)
		(size 0.45)
		(drill 0.1)
		(layers "F.Cu" "B.Cu")
		(remove_unused_layers yes)
		(keep_end_layers yes)
		(zone_layer_connections "In1.Cu" "In4.Cu" "In6.Cu")
		(teardrops
			(best_length_ratio 0.4)
			(max_length 1)
			(best_width_ratio 0.9)
			(max_width 2)
			(curved_edges yes)
			(filter_ratio 0.9)
			(enabled yes)
			(allow_two_segments yes)
			(prefer_zone_connections yes)
		)
		(net 1)
	)
	(via
		(at 212.11 133.26)
		(size 0.45)
		(drill 0.1)
		(layers "F.Cu" "B.Cu")
		(remove_unused_layers yes)
		(keep_end_layers yes)
		(zone_layer_connections "In1.Cu" "In4.Cu" "In6.Cu")
		(teardrops
			(best_length_ratio 0.4)
			(max_length 1)
			(best_width_ratio 0.9)
			(max_width 2)
			(curved_edges yes)
			(filter_ratio 0.9)
			(enabled yes)
			(allow_two_segments yes)
			(prefer_zone_connections yes)
		)
		(net 1)
	)
	(via
		(at 209.05 161.85)
		(size 0.45)
		(drill 0.1)
		(layers "F.Cu" "B.Cu")
		(teardrops
			(best_length_ratio 0.4)
			(max_length 1)
			(best_width_ratio 0.9)
			(max_width 2)
			(curved_edges yes)
			(filter_ratio 0.9)
			(enabled yes)
			(allow_two_segments yes)
			(prefer_zone_connections yes)
		)
		(net 1)
	)
	(via
		(at 135.29 135.86)
		(size 0.45)
		(drill 0.1)
		(layers "F.Cu" "B.Cu")
		(remove_unused_layers yes)
		(keep_end_layers yes)
		(zone_layer_connections "In1.Cu" "In4.Cu" "In6.Cu")
		(teardrops
			(best_length_ratio 0.4)
			(max_length 1)
			(best_width_ratio 0.9)
			(max_width 2)
			(curved_edges yes)
			(filter_ratio 0.9)
			(enabled yes)
			(allow_two_segments yes)
			(prefer_zone_connections yes)
		)
		(net 1)
	)
	(via
		(at 194.25 154.45)
		(size 0.45)
		(drill 0.1)
		(layers "F.Cu" "B.Cu")
		(teardrops
			(best_length_ratio 0.4)
			(max_length 1)
			(best_width_ratio 0.9)
			(max_width 2)
			(curved_edges yes)
			(filter_ratio 0.9)
			(enabled yes)
			(allow_two_segments yes)
			(prefer_zone_connections yes)
		)
		(net 1)
	)
	(via
		(at 250.45 121.81)
		(size 0.45)
		(drill 0.1)
		(layers "F.Cu" "B.Cu")
		(remove_unused_layers yes)
		(keep_end_layers yes)
		(zone_layer_connections "In1.Cu" "In4.Cu" "In6.Cu")
		(teardrops
			(best_length_ratio 0.4)
			(max_length 1)
			(best_width_ratio 0.9)
			(max_width 2)
			(curved_edges yes)
			(filter_ratio 0.9)
			(enabled yes)
			(allow_two_segments yes)
			(prefer_zone_connections yes)
		)
		(net 1)
	)
	(via
		(at 124.36 133.38)
		(size 0.45)
		(drill 0.1)
		(layers "F.Cu" "B.Cu")
		(remove_unused_layers yes)
		(keep_end_layers yes)
		(zone_layer_connections "In1.Cu" "In4.Cu" "In6.Cu")
		(teardrops
			(best_length_ratio 0.4)
			(max_length 1)
			(best_width_ratio 0.9)
			(max_width 2)
			(curved_edges yes)
			(filter_ratio 0.9)
			(enabled yes)
			(allow_two_segments yes)
			(prefer_zone_connections yes)
		)
		(net 1)
	)
	(via
		(at 111.33 96.46)
		(size 0.45)
		(drill 0.1)
		(layers "F.Cu" "B.Cu")
		(remove_unused_layers yes)
		(keep_end_layers yes)
		(zone_layer_connections "In1.Cu" "In4.Cu" "In6.Cu")
		(teardrops
			(best_length_ratio 0.4)
			(max_length 1)
			(best_width_ratio 0.9)
			(max_width 2)
			(curved_edges yes)
			(filter_ratio 0.9)
			(enabled yes)
			(allow_two_segments yes)
			(prefer_zone_connections yes)
		)
		(net 1)
	)
	(via
		(at 115.45 80.81)
		(size 0.45)
		(drill 0.1)
		(layers "F.Cu" "B.Cu")
		(remove_unused_layers yes)
		(keep_end_layers yes)
		(zone_layer_connections "In1.Cu" "In4.Cu" "In6.Cu")
		(teardrops
			(best_length_ratio 0.4)
			(max_length 1)
			(best_width_ratio 0.9)
			(max_width 2)
			(curved_edges yes)
			(filter_ratio 0.9)
			(enabled yes)
			(allow_two_segments yes)
			(prefer_zone_connections yes)
		)
		(net 1)
	)
	(via
		(at 203.1 124.5)
		(size 0.45)
		(drill 0.1)
		(layers "F.Cu" "B.Cu")
		(remove_unused_layers yes)
		(keep_end_layers yes)
		(zone_layer_connections "In1.Cu" "In4.Cu" "In6.Cu")
		(teardrops
			(best_length_ratio 0.4)
			(max_length 1)
			(best_width_ratio 0.9)
			(max_width 2)
			(curved_edges yes)
			(filter_ratio 0.9)
			(enabled yes)
			(allow_two_segments yes)
			(prefer_zone_connections yes)
		)
		(net 1)
	)
	(via
		(at 238.45 121.81)
		(size 0.45)
		(drill 0.1)
		(layers "F.Cu" "B.Cu")
		(remove_unused_layers yes)
		(keep_end_layers yes)
		(zone_layer_connections "In1.Cu" "In4.Cu" "In6.Cu")
		(teardrops
			(best_length_ratio 0.4)
			(max_length 1)
			(best_width_ratio 0.9)
			(max_width 2)
			(curved_edges yes)
			(filter_ratio 0.9)
			(enabled yes)
			(allow_two_segments yes)
			(prefer_zone_connections yes)
		)
		(net 1)
	)
	(via
		(at 215 167.5)
		(size 0.45)
		(drill 0.1)
		(layers "F.Cu" "B.Cu")
		(teardrops
			(best_length_ratio 0.4)
			(max_length 1)
			(best_width_ratio 0.9)
			(max_width 2)
			(curved_edges yes)
			(filter_ratio 0.9)
			(enabled yes)
			(allow_two_segments yes)
			(prefer_zone_connections yes)
		)
		(net 1)
	)
	(via
		(at 133.8 73.01)
		(size 0.45)
		(drill 0.1)
		(layers "F.Cu" "B.Cu")
		(remove_unused_layers yes)
		(keep_end_layers yes)
		(zone_layer_connections "In1.Cu" "In4.Cu" "In6.Cu")
		(teardrops
			(best_length_ratio 0.4)
			(max_length 1)
			(best_width_ratio 0.9)
			(max_width 2)
			(curved_edges yes)
			(filter_ratio 0.9)
			(enabled yes)
			(allow_two_segments yes)
			(prefer_zone_connections yes)
		)
		(net 1)
	)
	(via
		(at 268.95 166.41)
		(size 0.45)
		(drill 0.1)
		(layers "F.Cu" "B.Cu")
		(remove_unused_layers yes)
		(keep_end_layers yes)
		(zone_layer_connections "In1.Cu" "In4.Cu" "In6.Cu")
		(teardrops
			(best_length_ratio 0.4)
			(max_length 1)
			(best_width_ratio 0.9)
			(max_width 2)
			(curved_edges yes)
			(filter_ratio 0.9)
			(enabled yes)
			(allow_two_segments yes)
			(prefer_zone_connections yes)
		)
		(net 1)
	)
	(via
		(at 95.45 98.81)
		(size 0.45)
		(drill 0.1)
		(layers "F.Cu" "B.Cu")
		(remove_unused_layers yes)
		(keep_end_layers yes)
		(zone_layer_connections "In1.Cu" "In4.Cu" "In6.Cu")
		(teardrops
			(best_length_ratio 0.4)
			(max_length 1)
			(best_width_ratio 0.9)
			(max_width 2)
			(curved_edges yes)
			(filter_ratio 0.9)
			(enabled yes)
			(allow_two_segments yes)
			(prefer_zone_connections yes)
		)
		(net 1)
	)
	(via
		(at 292.701 74.96)
		(size 0.45)
		(drill 0.1)
		(layers "F.Cu" "B.Cu")
		(remove_unused_layers yes)
		(keep_end_layers yes)
		(free yes)
		(zone_layer_connections "In1.Cu" "In4.Cu" "In6.Cu")
		(teardrops
			(best_length_ratio 0.4)
			(max_length 1)
			(best_width_ratio 0.9)
			(max_width 2)
			(curved_edges yes)
			(filter_ratio 0.9)
			(enabled yes)
			(allow_two_segments yes)
			(prefer_zone_connections yes)
		)
		(net 1)
	)
	(via
		(at 217.55 149.921)
		(size 0.45)
		(drill 0.1)
		(layers "F.Cu" "B.Cu")
		(teardrops
			(best_length_ratio 0.4)
			(max_length 1)
			(best_width_ratio 0.9)
			(max_width 2)
			(curved_edges yes)
			(filter_ratio 0.9)
			(enabled yes)
			(allow_two_segments yes)
			(prefer_zone_connections yes)
		)
		(net 1)
	)
	(via
		(at 116.95 73.81)
		(size 0.45)
		(drill 0.1)
		(layers "F.Cu" "B.Cu")
		(remove_unused_layers yes)
		(keep_end_layers yes)
		(zone_layer_connections "In1.Cu" "In4.Cu" "In6.Cu")
		(teardrops
			(best_length_ratio 0.4)
			(max_length 1)
			(best_width_ratio 0.9)
			(max_width 2)
			(curved_edges yes)
			(filter_ratio 0.9)
			(enabled yes)
			(allow_two_segments yes)
			(prefer_zone_connections yes)
		)
		(net 1)
	)
	(via
		(at 215.15 161.65)
		(size 0.45)
		(drill 0.1)
		(layers "F.Cu" "B.Cu")
		(teardrops
			(best_length_ratio 0.4)
			(max_length 1)
			(best_width_ratio 0.9)
			(max_width 2)
			(curved_edges yes)
			(filter_ratio 0.9)
			(enabled yes)
			(allow_two_segments yes)
			(prefer_zone_connections yes)
		)
		(net 1)
	)
	(via
		(at 127.29 142.86)
		(size 0.45)
		(drill 0.1)
		(layers "F.Cu" "B.Cu")
		(remove_unused_layers yes)
		(keep_end_layers yes)
		(zone_layer_connections "In1.Cu" "In4.Cu" "In6.Cu")
		(teardrops
			(best_length_ratio 0.4)
			(max_length 1)
			(best_width_ratio 0.9)
			(max_width 2)
			(curved_edges yes)
			(filter_ratio 0.9)
			(enabled yes)
			(allow_two_segments yes)
			(prefer_zone_connections yes)
		)
		(net 1)
	)
	(via
		(at 227.84 70.21)
		(size 0.45)
		(drill 0.1)
		(layers "F.Cu" "B.Cu")
		(remove_unused_layers yes)
		(keep_end_layers yes)
		(zone_layer_connections "In1.Cu" "In4.Cu" "In6.Cu")
		(teardrops
			(best_length_ratio 0.4)
			(max_length 1)
			(best_width_ratio 0.9)
			(max_width 2)
			(curved_edges yes)
			(filter_ratio 0.9)
			(enabled yes)
			(allow_two_segments yes)
			(prefer_zone_connections yes)
		)
		(net 1)
	)
	(via
		(at 114.4 147.361)
		(size 0.45)
		(drill 0.1)
		(layers "F.Cu" "B.Cu")
		(remove_unused_layers yes)
		(keep_end_layers yes)
		(zone_layer_connections "In1.Cu" "In4.Cu" "In6.Cu")
		(teardrops
			(best_length_ratio 0.4)
			(max_length 1)
			(best_width_ratio 0.9)
			(max_width 2)
			(curved_edges yes)
			(filter_ratio 0.9)
			(enabled yes)
			(allow_two_segments yes)
			(prefer_zone_connections yes)
		)
		(net 1)
	)
	(via
		(at 309.95 69.81)
		(size 0.45)
		(drill 0.1)
		(layers "F.Cu" "B.Cu")
		(remove_unused_layers yes)
		(keep_end_layers yes)
		(zone_layer_connections "In1.Cu" "In4.Cu" "In6.Cu")
		(teardrops
			(best_length_ratio 0.4)
			(max_length 1)
			(best_width_ratio 0.9)
			(max_width 2)
			(curved_edges yes)
			(filter_ratio 0.9)
			(enabled yes)
			(allow_two_segments yes)
			(prefer_zone_connections yes)
		)
		(net 1)
	)
	(via
		(at 318.4645 98.6365)
		(size 0.45)
		(drill 0.1)
		(layers "F.Cu" "B.Cu")
		(remove_unused_layers yes)
		(keep_end_layers yes)
		(free yes)
		(zone_layer_connections "In1.Cu" "In4.Cu" "In6.Cu")
		(teardrops
			(best_length_ratio 0.4)
			(max_length 1)
			(best_width_ratio 0.9)
			(max_width 2)
			(curved_edges yes)
			(filter_ratio 0.9)
			(enabled yes)
			(allow_two_segments yes)
			(prefer_zone_connections yes)
		)
		(net 1)
	)
	(via
		(at 310.95 164.56)
		(size 0.45)
		(drill 0.1)
		(layers "F.Cu" "B.Cu")
		(remove_unused_layers yes)
		(keep_end_layers yes)
		(zone_layer_connections "In1.Cu" "In4.Cu" "In6.Cu")
		(teardrops
			(best_length_ratio 0.4)
			(max_length 1)
			(best_width_ratio 0.9)
			(max_width 2)
			(curved_edges yes)
			(filter_ratio 0.9)
			(enabled yes)
			(allow_two_segments yes)
			(prefer_zone_connections yes)
		)
		(net 1)
	)
	(via
		(at 315.95 70.81)
		(size 0.45)
		(drill 0.1)
		(layers "F.Cu" "B.Cu")
		(remove_unused_layers yes)
		(keep_end_layers yes)
		(zone_layer_connections "In1.Cu" "In4.Cu" "In6.Cu")
		(teardrops
			(best_length_ratio 0.4)
			(max_length 1)
			(best_width_ratio 0.9)
			(max_width 2)
			(curved_edges yes)
			(filter_ratio 0.9)
			(enabled yes)
			(allow_two_segments yes)
			(prefer_zone_connections yes)
		)
		(net 1)
	)
	(via
		(at 302.95 145.31)
		(size 0.45)
		(drill 0.1)
		(layers "F.Cu" "B.Cu")
		(remove_unused_layers yes)
		(keep_end_layers yes)
		(zone_layer_connections "In1.Cu" "In4.Cu" "In6.Cu")
		(teardrops
			(best_length_ratio 0.4)
			(max_length 1)
			(best_width_ratio 0.9)
			(max_width 2)
			(curved_edges yes)
			(filter_ratio 0.9)
			(enabled yes)
			(allow_two_segments yes)
			(prefer_zone_connections yes)
		)
		(net 1)
	)
	(via
		(at 150.45 75.31)
		(size 0.45)
		(drill 0.1)
		(layers "F.Cu" "B.Cu")
		(remove_unused_layers yes)
		(keep_end_layers yes)
		(zone_layer_connections "In1.Cu" "In4.Cu" "In6.Cu")
		(teardrops
			(best_length_ratio 0.4)
			(max_length 1)
			(best_width_ratio 0.9)
			(max_width 2)
			(curved_edges yes)
			(filter_ratio 0.9)
			(enabled yes)
			(allow_two_segments yes)
			(prefer_zone_connections yes)
		)
		(net 1)
	)
	(via
		(at 146.45 92.31)
		(size 0.45)
		(drill 0.1)
		(layers "F.Cu" "B.Cu")
		(remove_unused_layers yes)
		(keep_end_layers yes)
		(zone_layer_connections "In1.Cu" "In4.Cu" "In6.Cu")
		(teardrops
			(best_length_ratio 0.4)
			(max_length 1)
			(best_width_ratio 0.9)
			(max_width 2)
			(curved_edges yes)
			(filter_ratio 0.9)
			(enabled yes)
			(allow_two_segments yes)
			(prefer_zone_connections yes)
		)
		(net 1)
	)
	(via
		(at 194.78616 133.957423)
		(size 0.45)
		(drill 0.1)
		(layers "F.Cu" "B.Cu")
		(remove_unused_layers yes)
		(keep_end_layers yes)
		(zone_layer_connections "In1.Cu" "In4.Cu" "In6.Cu")
		(teardrops
			(best_length_ratio 0.4)
			(max_length 1)
			(best_width_ratio 0.9)
			(max_width 2)
			(curved_edges yes)
			(filter_ratio 0.9)
			(enabled yes)
			(allow_two_segments yes)
			(prefer_zone_connections yes)
		)
		(net 1)
	)
	(via
		(at 259.45 111.31)
		(size 0.45)
		(drill 0.1)
		(layers "F.Cu" "B.Cu")
		(remove_unused_layers yes)
		(keep_end_layers yes)
		(free yes)
		(zone_layer_connections "In1.Cu" "In4.Cu" "In6.Cu")
		(teardrops
			(best_length_ratio 0.4)
			(max_length 1)
			(best_width_ratio 0.9)
			(max_width 2)
			(curved_edges yes)
			(filter_ratio 0.9)
			(enabled yes)
			(allow_two_segments yes)
			(prefer_zone_connections yes)
		)
		(net 1)
	)
	(via
		(at 213.45 148.65)
		(size 0.45)
		(drill 0.1)
		(layers "F.Cu" "B.Cu")
		(teardrops
			(best_length_ratio 0.4)
			(max_length 1)
			(best_width_ratio 0.9)
			(max_width 2)
			(curved_edges yes)
			(filter_ratio 0.9)
			(enabled yes)
			(allow_two_segments yes)
			(prefer_zone_connections yes)
		)
		(net 1)
	)
	(via
		(at 287.95 138.31)
		(size 0.45)
		(drill 0.1)
		(layers "F.Cu" "B.Cu")
		(remove_unused_layers yes)
		(keep_end_layers yes)
		(zone_layer_connections "In1.Cu" "In4.Cu" "In6.Cu")
		(teardrops
			(best_length_ratio 0.4)
			(max_length 1)
			(best_width_ratio 0.9)
			(max_width 2)
			(curved_edges yes)
			(filter_ratio 0.9)
			(enabled yes)
			(allow_two_segments yes)
			(prefer_zone_connections yes)
		)
		(net 1)
	)
	(via
		(at 165 150.2)
		(size 0.45)
		(drill 0.1)
		(layers "F.Cu" "B.Cu")
		(teardrops
			(best_length_ratio 0.4)
			(max_length 1)
			(best_width_ratio 0.9)
			(max_width 2)
			(curved_edges yes)
			(filter_ratio 0.9)
			(enabled yes)
			(allow_two_segments yes)
			(prefer_zone_connections yes)
		)
		(net 1)
	)
	(via
		(at 311.4645 99.6365)
		(size 0.45)
		(drill 0.1)
		(layers "F.Cu" "B.Cu")
		(remove_unused_layers yes)
		(keep_end_layers yes)
		(free yes)
		(zone_layer_connections "In1.Cu" "In4.Cu" "In6.Cu")
		(teardrops
			(best_length_ratio 0.4)
			(max_length 1)
			(best_width_ratio 0.9)
			(max_width 2)
			(curved_edges yes)
			(filter_ratio 0.9)
			(enabled yes)
			(allow_two_segments yes)
			(prefer_zone_connections yes)
		)
		(net 1)
	)
	(via
		(at 144.45 78.31)
		(size 0.45)
		(drill 0.1)
		(layers "F.Cu" "B.Cu")
		(remove_unused_layers yes)
		(keep_end_layers yes)
		(zone_layer_connections "In1.Cu" "In4.Cu" "In6.Cu")
		(teardrops
			(best_length_ratio 0.4)
			(max_length 1)
			(best_width_ratio 0.9)
			(max_width 2)
			(curved_edges yes)
			(filter_ratio 0.9)
			(enabled yes)
			(allow_two_segments yes)
			(prefer_zone_connections yes)
		)
		(net 1)
	)
	(via
		(at 130.29 146.81)
		(size 0.45)
		(drill 0.1)
		(layers "F.Cu" "B.Cu")
		(remove_unused_layers yes)
		(keep_end_layers yes)
		(zone_layer_connections "In1.Cu" "In4.Cu" "In6.Cu")
		(teardrops
			(best_length_ratio 0.4)
			(max_length 1)
			(best_width_ratio 0.9)
			(max_width 2)
			(curved_edges yes)
			(filter_ratio 0.9)
			(enabled yes)
			(allow_two_segments yes)
			(prefer_zone_connections yes)
		)
		(net 1)
	)
	(via
		(at 231.74 73.35)
		(size 0.45)
		(drill 0.1)
		(layers "F.Cu" "B.Cu")
		(remove_unused_layers yes)
		(keep_end_layers yes)
		(free yes)
		(zone_layer_connections "In1.Cu" "In4.Cu" "In6.Cu")
		(teardrops
			(best_length_ratio 0.4)
			(max_length 1)
			(best_width_ratio 0.9)
			(max_width 2)
			(curved_edges yes)
			(filter_ratio 0.9)
			(enabled yes)
			(allow_two_segments yes)
			(prefer_zone_connections yes)
		)
		(net 1)
	)
	(via
		(at 278.95 141.31)
		(size 0.45)
		(drill 0.1)
		(layers "F.Cu" "B.Cu")
		(remove_unused_layers yes)
		(keep_end_layers yes)
		(zone_layer_connections "In1.Cu" "In4.Cu" "In6.Cu")
		(teardrops
			(best_length_ratio 0.4)
			(max_length 1)
			(best_width_ratio 0.9)
			(max_width 2)
			(curved_edges yes)
			(filter_ratio 0.9)
			(enabled yes)
			(allow_two_segments yes)
			(prefer_zone_connections yes)
		)
		(net 1)
	)
	(via
		(at 150.45 141.86)
		(size 0.45)
		(drill 0.1)
		(layers "F.Cu" "B.Cu")
		(remove_unused_layers yes)
		(keep_end_layers yes)
		(zone_layer_connections "In1.Cu" "In4.Cu" "In6.Cu")
		(teardrops
			(best_length_ratio 0.4)
			(max_length 1)
			(best_width_ratio 0.9)
			(max_width 2)
			(curved_edges yes)
			(filter_ratio 0.9)
			(enabled yes)
			(allow_two_segments yes)
			(prefer_zone_connections yes)
		)
		(net 1)
	)
	(via
		(at 152.8255 69.9595)
		(size 0.45)
		(drill 0.1)
		(layers "F.Cu" "B.Cu")
		(remove_unused_layers yes)
		(keep_end_layers yes)
		(zone_layer_connections "In1.Cu" "In4.Cu" "In6.Cu")
		(teardrops
			(best_length_ratio 0.4)
			(max_length 1)
			(best_width_ratio 0.9)
			(max_width 2)
			(curved_edges yes)
			(filter_ratio 0.9)
			(enabled yes)
			(allow_two_segments yes)
			(prefer_zone_connections yes)
		)
		(net 1)
	)
	(via
		(at 312.95 77.31)
		(size 0.45)
		(drill 0.1)
		(layers "F.Cu" "B.Cu")
		(remove_unused_layers yes)
		(keep_end_layers yes)
		(zone_layer_connections "In1.Cu" "In4.Cu" "In6.Cu")
		(teardrops
			(best_length_ratio 0.4)
			(max_length 1)
			(best_width_ratio 0.9)
			(max_width 2)
			(curved_edges yes)
			(filter_ratio 0.9)
			(enabled yes)
			(allow_two_segments yes)
			(prefer_zone_connections yes)
		)
		(net 1)
	)
	(via
		(at 100.45 133.81)
		(size 0.45)
		(drill 0.1)
		(layers "F.Cu" "B.Cu")
		(remove_unused_layers yes)
		(keep_end_layers yes)
		(zone_layer_connections "In1.Cu" "In4.Cu" "In6.Cu")
		(teardrops
			(best_length_ratio 0.4)
			(max_length 1)
			(best_width_ratio 0.9)
			(max_width 2)
			(curved_edges yes)
			(filter_ratio 0.9)
			(enabled yes)
			(allow_two_segments yes)
			(prefer_zone_connections yes)
		)
		(net 1)
	)
	(via
		(at 128.45 169.81)
		(size 0.45)
		(drill 0.1)
		(layers "F.Cu" "B.Cu")
		(remove_unused_layers yes)
		(keep_end_layers yes)
		(zone_layer_connections "In1.Cu" "In4.Cu" "In6.Cu")
		(teardrops
			(best_length_ratio 0.4)
			(max_length 1)
			(best_width_ratio 0.9)
			(max_width 2)
			(curved_edges yes)
			(filter_ratio 0.9)
			(enabled yes)
			(allow_two_segments yes)
			(prefer_zone_connections yes)
		)
		(net 1)
	)
	(via
		(at 156.95 86.31)
		(size 0.45)
		(drill 0.1)
		(layers "F.Cu" "B.Cu")
		(remove_unused_layers yes)
		(keep_end_layers yes)
		(zone_layer_connections "In1.Cu" "In4.Cu" "In6.Cu")
		(teardrops
			(best_length_ratio 0.4)
			(max_length 1)
			(best_width_ratio 0.9)
			(max_width 2)
			(curved_edges yes)
			(filter_ratio 0.9)
			(enabled yes)
			(allow_two_segments yes)
			(prefer_zone_connections yes)
		)
		(net 1)
	)
	(via
		(at 225.45 87.81)
		(size 0.45)
		(drill 0.1)
		(layers "F.Cu" "B.Cu")
		(remove_unused_layers yes)
		(keep_end_layers yes)
		(zone_layer_connections "In1.Cu" "In4.Cu" "In6.Cu")
		(teardrops
			(best_length_ratio 0.4)
			(max_length 1)
			(best_width_ratio 0.9)
			(max_width 2)
			(curved_edges yes)
			(filter_ratio 0.9)
			(enabled yes)
			(allow_two_segments yes)
			(prefer_zone_connections yes)
		)
		(net 1)
	)
	(via
		(at 305.33 146.61)
		(size 0.45)
		(drill 0.1)
		(layers "F.Cu" "B.Cu")
		(remove_unused_layers yes)
		(keep_end_layers yes)
		(zone_layer_connections "In1.Cu" "In4.Cu" "In6.Cu")
		(teardrops
			(best_length_ratio 0.4)
			(max_length 1)
			(best_width_ratio 0.9)
			(max_width 2)
			(curved_edges yes)
			(filter_ratio 0.9)
			(enabled yes)
			(allow_two_segments yes)
			(prefer_zone_connections yes)
		)
		(net 1)
	)
	(via
		(at 107.95 72.81)
		(size 0.45)
		(drill 0.1)
		(layers "F.Cu" "B.Cu")
		(remove_unused_layers yes)
		(keep_end_layers yes)
		(zone_layer_connections "In1.Cu" "In4.Cu" "In6.Cu")
		(teardrops
			(best_length_ratio 0.4)
			(max_length 1)
			(best_width_ratio 0.9)
			(max_width 2)
			(curved_edges yes)
			(filter_ratio 0.9)
			(enabled yes)
			(allow_two_segments yes)
			(prefer_zone_connections yes)
		)
		(net 1)
	)
	(via
		(at 290.95 144.31)
		(size 0.45)
		(drill 0.1)
		(layers "F.Cu" "B.Cu")
		(remove_unused_layers yes)
		(keep_end_layers yes)
		(zone_layer_connections "In1.Cu" "In4.Cu" "In6.Cu")
		(teardrops
			(best_length_ratio 0.4)
			(max_length 1)
			(best_width_ratio 0.9)
			(max_width 2)
			(curved_edges yes)
			(filter_ratio 0.9)
			(enabled yes)
			(allow_two_segments yes)
			(prefer_zone_connections yes)
		)
		(net 1)
	)
	(via
		(at 114.5 132.6)
		(size 0.45)
		(drill 0.1)
		(layers "F.Cu" "B.Cu")
		(remove_unused_layers yes)
		(keep_end_layers yes)
		(zone_layer_connections "In1.Cu" "In4.Cu" "In6.Cu")
		(teardrops
			(best_length_ratio 0.4)
			(max_length 1)
			(best_width_ratio 0.9)
			(max_width 2)
			(curved_edges yes)
			(filter_ratio 0.9)
			(enabled yes)
			(allow_two_segments yes)
			(prefer_zone_connections yes)
		)
		(net 1)
	)
	(via
		(at 103.45 130.81)
		(size 0.45)
		(drill 0.1)
		(layers "F.Cu" "B.Cu")
		(remove_unused_layers yes)
		(keep_end_layers yes)
		(zone_layer_connections "In1.Cu" "In4.Cu" "In6.Cu")
		(teardrops
			(best_length_ratio 0.4)
			(max_length 1)
			(best_width_ratio 0.9)
			(max_width 2)
			(curved_edges yes)
			(filter_ratio 0.9)
			(enabled yes)
			(allow_two_segments yes)
			(prefer_zone_connections yes)
		)
		(net 1)
	)
	(via
		(at 156.583172 73.385248)
		(size 0.45)
		(drill 0.1)
		(layers "F.Cu" "B.Cu")
		(remove_unused_layers yes)
		(keep_end_layers yes)
		(zone_layer_connections "In1.Cu" "In4.Cu" "In6.Cu")
		(teardrops
			(best_length_ratio 0.4)
			(max_length 1)
			(best_width_ratio 0.9)
			(max_width 2)
			(curved_edges yes)
			(filter_ratio 0.9)
			(enabled yes)
			(allow_two_segments yes)
			(prefer_zone_connections yes)
		)
		(net 1)
	)
	(via
		(at 179.5 149.95)
		(size 0.45)
		(drill 0.1)
		(layers "F.Cu" "B.Cu")
		(teardrops
			(best_length_ratio 0.4)
			(max_length 1)
			(best_width_ratio 0.9)
			(max_width 2)
			(curved_edges yes)
			(filter_ratio 0.9)
			(enabled yes)
			(allow_two_segments yes)
			(prefer_zone_connections yes)
		)
		(net 1)
	)
	(via
		(at 125.45 159.81)
		(size 0.45)
		(drill 0.1)
		(layers "F.Cu" "B.Cu")
		(remove_unused_layers yes)
		(keep_end_layers yes)
		(zone_layer_connections "In1.Cu" "In4.Cu" "In6.Cu")
		(teardrops
			(best_length_ratio 0.4)
			(max_length 1)
			(best_width_ratio 0.9)
			(max_width 2)
			(curved_edges yes)
			(filter_ratio 0.9)
			(enabled yes)
			(allow_two_segments yes)
			(prefer_zone_connections yes)
		)
		(net 1)
	)
	(via
		(at 201.95 104.81)
		(size 0.45)
		(drill 0.1)
		(layers "F.Cu" "B.Cu")
		(remove_unused_layers yes)
		(keep_end_layers yes)
		(zone_layer_connections "In1.Cu" "In4.Cu" "In6.Cu")
		(teardrops
			(best_length_ratio 0.4)
			(max_length 1)
			(best_width_ratio 0.9)
			(max_width 2)
			(curved_edges yes)
			(filter_ratio 0.9)
			(enabled yes)
			(allow_two_segments yes)
			(prefer_zone_connections yes)
		)
		(net 1)
	)
	(via
		(at 290.95 157.31)
		(size 0.45)
		(drill 0.1)
		(layers "F.Cu" "B.Cu")
		(remove_unused_layers yes)
		(keep_end_layers yes)
		(zone_layer_connections "In1.Cu" "In4.Cu" "In6.Cu")
		(teardrops
			(best_length_ratio 0.4)
			(max_length 1)
			(best_width_ratio 0.9)
			(max_width 2)
			(curved_edges yes)
			(filter_ratio 0.9)
			(enabled yes)
			(allow_two_segments yes)
			(prefer_zone_connections yes)
		)
		(net 1)
	)
	(via
		(at 317.7 160.91)
		(size 0.45)
		(drill 0.1)
		(layers "F.Cu" "B.Cu")
		(remove_unused_layers yes)
		(keep_end_layers yes)
		(zone_layer_connections "In1.Cu" "In4.Cu" "In6.Cu")
		(teardrops
			(best_length_ratio 0.4)
			(max_length 1)
			(best_width_ratio 0.9)
			(max_width 2)
			(curved_edges yes)
			(filter_ratio 0.9)
			(enabled yes)
			(allow_two_segments yes)
			(prefer_zone_connections yes)
		)
		(net 1)
	)
	(via
		(at 96.45 125.81)
		(size 0.45)
		(drill 0.1)
		(layers "F.Cu" "B.Cu")
		(remove_unused_layers yes)
		(keep_end_layers yes)
		(zone_layer_connections "In1.Cu" "In4.Cu" "In6.Cu")
		(teardrops
			(best_length_ratio 0.4)
			(max_length 1)
			(best_width_ratio 0.9)
			(max_width 2)
			(curved_edges yes)
			(filter_ratio 0.9)
			(enabled yes)
			(allow_two_segments yes)
			(prefer_zone_connections yes)
		)
		(net 1)
	)
	(via
		(at 99.95 97.81)
		(size 0.45)
		(drill 0.1)
		(layers "F.Cu" "B.Cu")
		(remove_unused_layers yes)
		(keep_end_layers yes)
		(zone_layer_connections "In1.Cu" "In4.Cu" "In6.Cu")
		(teardrops
			(best_length_ratio 0.4)
			(max_length 1)
			(best_width_ratio 0.9)
			(max_width 2)
			(curved_edges yes)
			(filter_ratio 0.9)
			(enabled yes)
			(allow_two_segments yes)
			(prefer_zone_connections yes)
		)
		(net 1)
	)
	(via
		(at 206.15 165.45)
		(size 0.45)
		(drill 0.1)
		(layers "F.Cu" "B.Cu")
		(teardrops
			(best_length_ratio 0.4)
			(max_length 1)
			(best_width_ratio 0.9)
			(max_width 2)
			(curved_edges yes)
			(filter_ratio 0.9)
			(enabled yes)
			(allow_two_segments yes)
			(prefer_zone_connections yes)
		)
		(net 1)
	)
	(via
		(at 158.95 83.81)
		(size 0.45)
		(drill 0.1)
		(layers "F.Cu" "B.Cu")
		(remove_unused_layers yes)
		(keep_end_layers yes)
		(zone_layer_connections "In1.Cu" "In4.Cu" "In6.Cu")
		(teardrops
			(best_length_ratio 0.4)
			(max_length 1)
			(best_width_ratio 0.9)
			(max_width 2)
			(curved_edges yes)
			(filter_ratio 0.9)
			(enabled yes)
			(allow_two_segments yes)
			(prefer_zone_connections yes)
		)
		(net 1)
	)
	(via
		(at 174.703893 96.409175)
		(size 0.45)
		(drill 0.1)
		(layers "F.Cu" "B.Cu")
		(remove_unused_layers yes)
		(keep_end_layers yes)
		(zone_layer_connections "In1.Cu" "In4.Cu" "In6.Cu")
		(teardrops
			(best_length_ratio 0.4)
			(max_length 1)
			(best_width_ratio 0.9)
			(max_width 2)
			(curved_edges yes)
			(filter_ratio 0.9)
			(enabled yes)
			(allow_two_segments yes)
			(prefer_zone_connections yes)
		)
		(net 1)
	)
	(via
		(at 187.3 123.6)
		(size 0.45)
		(drill 0.1)
		(layers "F.Cu" "B.Cu")
		(remove_unused_layers yes)
		(keep_end_layers yes)
		(zone_layer_connections "In1.Cu" "In4.Cu" "In6.Cu")
		(teardrops
			(best_length_ratio 0.4)
			(max_length 1)
			(best_width_ratio 0.9)
			(max_width 2)
			(curved_edges yes)
			(filter_ratio 0.9)
			(enabled yes)
			(allow_two_segments yes)
			(prefer_zone_connections yes)
		)
		(net 1)
	)
	(via
		(at 193.95 70.31)
		(size 0.45)
		(drill 0.1)
		(layers "F.Cu" "B.Cu")
		(remove_unused_layers yes)
		(keep_end_layers yes)
		(free yes)
		(zone_layer_connections "In1.Cu" "In4.Cu" "In6.Cu")
		(teardrops
			(best_length_ratio 0.4)
			(max_length 1)
			(best_width_ratio 0.9)
			(max_width 2)
			(curved_edges yes)
			(filter_ratio 0.9)
			(enabled yes)
			(allow_two_segments yes)
			(prefer_zone_connections yes)
		)
		(net 1)
	)
	(via
		(at 95.45 146.81)
		(size 0.45)
		(drill 0.1)
		(layers "F.Cu" "B.Cu")
		(remove_unused_layers yes)
		(keep_end_layers yes)
		(zone_layer_connections "In1.Cu" "In4.Cu" "In6.Cu")
		(teardrops
			(best_length_ratio 0.4)
			(max_length 1)
			(best_width_ratio 0.9)
			(max_width 2)
			(curved_edges yes)
			(filter_ratio 0.9)
			(enabled yes)
			(allow_two_segments yes)
			(prefer_zone_connections yes)
		)
		(net 1)
	)
	(via
		(at 118.45 164.81)
		(size 0.45)
		(drill 0.1)
		(layers "F.Cu" "B.Cu")
		(remove_unused_layers yes)
		(keep_end_layers yes)
		(zone_layer_connections "In1.Cu" "In4.Cu" "In6.Cu")
		(teardrops
			(best_length_ratio 0.4)
			(max_length 1)
			(best_width_ratio 0.9)
			(max_width 2)
			(curved_edges yes)
			(filter_ratio 0.9)
			(enabled yes)
			(allow_two_segments yes)
			(prefer_zone_connections yes)
		)
		(net 1)
	)
	(via
		(at 131.29 134.86)
		(size 0.45)
		(drill 0.1)
		(layers "F.Cu" "B.Cu")
		(remove_unused_layers yes)
		(keep_end_layers yes)
		(zone_layer_connections "In1.Cu" "In4.Cu" "In6.Cu")
		(teardrops
			(best_length_ratio 0.4)
			(max_length 1)
			(best_width_ratio 0.9)
			(max_width 2)
			(curved_edges yes)
			(filter_ratio 0.9)
			(enabled yes)
			(allow_two_segments yes)
			(prefer_zone_connections yes)
		)
		(net 1)
	)
	(via
		(at 307.518 80.538)
		(size 0.45)
		(drill 0.1)
		(layers "F.Cu" "B.Cu")
		(remove_unused_layers yes)
		(keep_end_layers yes)
		(zone_layer_connections "In1.Cu" "In4.Cu" "In6.Cu")
		(teardrops
			(best_length_ratio 0.4)
			(max_length 1)
			(best_width_ratio 0.9)
			(max_width 2)
			(curved_edges yes)
			(filter_ratio 0.9)
			(enabled yes)
			(allow_two_segments yes)
			(prefer_zone_connections yes)
		)
		(net 1)
	)
	(via
		(at 127.29 132.86)
		(size 0.45)
		(drill 0.1)
		(layers "F.Cu" "B.Cu")
		(remove_unused_layers yes)
		(keep_end_layers yes)
		(zone_layer_connections "In1.Cu" "In4.Cu" "In6.Cu")
		(teardrops
			(best_length_ratio 0.4)
			(max_length 1)
			(best_width_ratio 0.9)
			(max_width 2)
			(curved_edges yes)
			(filter_ratio 0.9)
			(enabled yes)
			(allow_two_segments yes)
			(prefer_zone_connections yes)
		)
		(net 1)
	)
	(via
		(at 292.95 105.31)
		(size 0.45)
		(drill 0.1)
		(layers "F.Cu" "B.Cu")
		(remove_unused_layers yes)
		(keep_end_layers yes)
		(zone_layer_connections "In1.Cu" "In4.Cu" "In6.Cu")
		(teardrops
			(best_length_ratio 0.4)
			(max_length 1)
			(best_width_ratio 0.9)
			(max_width 2)
			(curved_edges yes)
			(filter_ratio 0.9)
			(enabled yes)
			(allow_two_segments yes)
			(prefer_zone_connections yes)
		)
		(net 1)
	)
	(via
		(at 215.55 167.5)
		(size 0.45)
		(drill 0.1)
		(layers "F.Cu" "B.Cu")
		(teardrops
			(best_length_ratio 0.4)
			(max_length 1)
			(best_width_ratio 0.9)
			(max_width 2)
			(curved_edges yes)
			(filter_ratio 0.9)
			(enabled yes)
			(allow_two_segments yes)
			(prefer_zone_connections yes)
		)
		(net 1)
	)
	(via
		(at 151.45 138.86)
		(size 0.45)
		(drill 0.1)
		(layers "F.Cu" "B.Cu")
		(remove_unused_layers yes)
		(keep_end_layers yes)
		(zone_layer_connections "In1.Cu" "In4.Cu" "In6.Cu")
		(teardrops
			(best_length_ratio 0.4)
			(max_length 1)
			(best_width_ratio 0.9)
			(max_width 2)
			(curved_edges yes)
			(filter_ratio 0.9)
			(enabled yes)
			(allow_two_segments yes)
			(prefer_zone_connections yes)
		)
		(net 1)
	)
	(via
		(at 154.45 142.86)
		(size 0.45)
		(drill 0.1)
		(layers "F.Cu" "B.Cu")
		(remove_unused_layers yes)
		(keep_end_layers yes)
		(zone_layer_connections "In1.Cu" "In4.Cu" "In6.Cu")
		(teardrops
			(best_length_ratio 0.4)
			(max_length 1)
			(best_width_ratio 0.9)
			(max_width 2)
			(curved_edges yes)
			(filter_ratio 0.9)
			(enabled yes)
			(allow_two_segments yes)
			(prefer_zone_connections yes)
		)
		(net 1)
	)
	(via
		(at 208.5 161.85)
		(size 0.45)
		(drill 0.1)
		(layers "F.Cu" "B.Cu")
		(teardrops
			(best_length_ratio 0.4)
			(max_length 1)
			(best_width_ratio 0.9)
			(max_width 2)
			(curved_edges yes)
			(filter_ratio 0.9)
			(enabled yes)
			(allow_two_segments yes)
			(prefer_zone_connections yes)
		)
		(net 1)
	)
	(via
		(at 121.8 141.85)
		(size 0.45)
		(drill 0.1)
		(layers "F.Cu" "B.Cu")
		(remove_unused_layers yes)
		(keep_end_layers yes)
		(zone_layer_connections "In1.Cu" "In4.Cu" "In6.Cu")
		(teardrops
			(best_length_ratio 0.4)
			(max_length 1)
			(best_width_ratio 0.9)
			(max_width 2)
			(curved_edges yes)
			(filter_ratio 0.9)
			(enabled yes)
			(allow_two_segments yes)
			(prefer_zone_connections yes)
		)
		(net 1)
	)
	(via
		(at 181.86 113.53)
		(size 0.45)
		(drill 0.1)
		(layers "F.Cu" "B.Cu")
		(remove_unused_layers yes)
		(keep_end_layers yes)
		(zone_layer_connections "In1.Cu" "In4.Cu" "In6.Cu")
		(teardrops
			(best_length_ratio 0.4)
			(max_length 1)
			(best_width_ratio 0.9)
			(max_width 2)
			(curved_edges yes)
			(filter_ratio 0.9)
			(enabled yes)
			(allow_two_segments yes)
			(prefer_zone_connections yes)
		)
		(net 1)
	)
	(via
		(at 289.45 142.81)
		(size 0.45)
		(drill 0.1)
		(layers "F.Cu" "B.Cu")
		(remove_unused_layers yes)
		(keep_end_layers yes)
		(zone_layer_connections "In1.Cu" "In4.Cu" "In6.Cu")
		(teardrops
			(best_length_ratio 0.4)
			(max_length 1)
			(best_width_ratio 0.9)
			(max_width 2)
			(curved_edges yes)
			(filter_ratio 0.9)
			(enabled yes)
			(allow_two_segments yes)
			(prefer_zone_connections yes)
		)
		(net 1)
	)
	(via
		(at 122.68 137.38)
		(size 0.45)
		(drill 0.1)
		(layers "F.Cu" "B.Cu")
		(remove_unused_layers yes)
		(keep_end_layers yes)
		(zone_layer_connections "In1.Cu" "In4.Cu" "In6.Cu")
		(teardrops
			(best_length_ratio 0.4)
			(max_length 1)
			(best_width_ratio 0.9)
			(max_width 2)
			(curved_edges yes)
			(filter_ratio 0.9)
			(enabled yes)
			(allow_two_segments yes)
			(prefer_zone_connections yes)
		)
		(net 1)
	)
	(via
		(at 125.45 165.81)
		(size 0.45)
		(drill 0.1)
		(layers "F.Cu" "B.Cu")
		(remove_unused_layers yes)
		(keep_end_layers yes)
		(zone_layer_connections "In1.Cu" "In4.Cu" "In6.Cu")
		(teardrops
			(best_length_ratio 0.4)
			(max_length 1)
			(best_width_ratio 0.9)
			(max_width 2)
			(curved_edges yes)
			(filter_ratio 0.9)
			(enabled yes)
			(allow_two_segments yes)
			(prefer_zone_connections yes)
		)
		(net 1)
	)
	(via
		(at 311.45 84.81)
		(size 0.45)
		(drill 0.1)
		(layers "F.Cu" "B.Cu")
		(remove_unused_layers yes)
		(keep_end_layers yes)
		(zone_layer_connections "In1.Cu" "In4.Cu" "In6.Cu")
		(teardrops
			(best_length_ratio 0.4)
			(max_length 1)
			(best_width_ratio 0.9)
			(max_width 2)
			(curved_edges yes)
			(filter_ratio 0.9)
			(enabled yes)
			(allow_two_segments yes)
			(prefer_zone_connections yes)
		)
		(net 1)
	)
	(via
		(at 217.375 170)
		(size 0.45)
		(drill 0.1)
		(layers "F.Cu" "B.Cu")
		(teardrops
			(best_length_ratio 0.4)
			(max_length 1)
			(best_width_ratio 0.9)
			(max_width 2)
			(curved_edges yes)
			(filter_ratio 0.9)
			(enabled yes)
			(allow_two_segments yes)
			(prefer_zone_connections yes)
		)
		(net 1)
	)
	(via
		(at 123.45 161.81)
		(size 0.45)
		(drill 0.1)
		(layers "F.Cu" "B.Cu")
		(remove_unused_layers yes)
		(keep_end_layers yes)
		(zone_layer_connections "In1.Cu" "In4.Cu" "In6.Cu")
		(teardrops
			(best_length_ratio 0.4)
			(max_length 1)
			(best_width_ratio 0.9)
			(max_width 2)
			(curved_edges yes)
			(filter_ratio 0.9)
			(enabled yes)
			(allow_two_segments yes)
			(prefer_zone_connections yes)
		)
		(net 1)
	)
	(via
		(at 205.35 131.9)
		(size 0.45)
		(drill 0.1)
		(layers "F.Cu" "B.Cu")
		(remove_unused_layers yes)
		(keep_end_layers yes)
		(zone_layer_connections "In1.Cu" "In4.Cu" "In6.Cu")
		(teardrops
			(best_length_ratio 0.4)
			(max_length 1)
			(best_width_ratio 0.9)
			(max_width 2)
			(curved_edges yes)
			(filter_ratio 0.9)
			(enabled yes)
			(allow_two_segments yes)
			(prefer_zone_connections yes)
		)
		(net 1)
	)
	(via
		(at 101.45 100.81)
		(size 0.45)
		(drill 0.1)
		(layers "F.Cu" "B.Cu")
		(remove_unused_layers yes)
		(keep_end_layers yes)
		(zone_layer_connections "In1.Cu" "In4.Cu" "In6.Cu")
		(teardrops
			(best_length_ratio 0.4)
			(max_length 1)
			(best_width_ratio 0.9)
			(max_width 2)
			(curved_edges yes)
			(filter_ratio 0.9)
			(enabled yes)
			(allow_two_segments yes)
			(prefer_zone_connections yes)
		)
		(net 1)
	)
	(via
		(at 184.5 157.9)
		(size 0.45)
		(drill 0.1)
		(layers "F.Cu" "B.Cu")
		(teardrops
			(best_length_ratio 0.4)
			(max_length 1)
			(best_width_ratio 0.9)
			(max_width 2)
			(curved_edges yes)
			(filter_ratio 0.9)
			(enabled yes)
			(allow_two_segments yes)
			(prefer_zone_connections yes)
		)
		(net 1)
	)
	(via
		(at 177.18 93.36)
		(size 0.45)
		(drill 0.1)
		(layers "F.Cu" "B.Cu")
		(remove_unused_layers yes)
		(keep_end_layers yes)
		(zone_layer_connections "In1.Cu" "In4.Cu" "In6.Cu")
		(teardrops
			(best_length_ratio 0.4)
			(max_length 1)
			(best_width_ratio 0.9)
			(max_width 2)
			(curved_edges yes)
			(filter_ratio 0.9)
			(enabled yes)
			(allow_two_segments yes)
			(prefer_zone_connections yes)
		)
		(net 1)
	)
	(via
		(at 135.45 168.81)
		(size 0.45)
		(drill 0.1)
		(layers "F.Cu" "B.Cu")
		(remove_unused_layers yes)
		(keep_end_layers yes)
		(zone_layer_connections "In1.Cu" "In4.Cu" "In6.Cu")
		(teardrops
			(best_length_ratio 0.4)
			(max_length 1)
			(best_width_ratio 0.9)
			(max_width 2)
			(curved_edges yes)
			(filter_ratio 0.9)
			(enabled yes)
			(allow_two_segments yes)
			(prefer_zone_connections yes)
		)
		(net 1)
	)
	(via
		(at 312.074999 104.4)
		(size 0.45)
		(drill 0.1)
		(layers "F.Cu" "B.Cu")
		(remove_unused_layers yes)
		(keep_end_layers yes)
		(zone_layer_connections "In1.Cu" "In4.Cu" "In6.Cu")
		(teardrops
			(best_length_ratio 0.4)
			(max_length 1)
			(best_width_ratio 0.9)
			(max_width 2)
			(curved_edges yes)
			(filter_ratio 0.9)
			(enabled yes)
			(allow_two_segments yes)
			(prefer_zone_connections yes)
		)
		(net 1)
	)
	(via
		(at 195.528622 134.699885)
		(size 0.45)
		(drill 0.1)
		(layers "F.Cu" "B.Cu")
		(remove_unused_layers yes)
		(keep_end_layers yes)
		(zone_layer_connections "In1.Cu" "In4.Cu" "In6.Cu")
		(teardrops
			(best_length_ratio 0.4)
			(max_length 1)
			(best_width_ratio 0.9)
			(max_width 2)
			(curved_edges yes)
			(filter_ratio 0.9)
			(enabled yes)
			(allow_two_segments yes)
			(prefer_zone_connections yes)
		)
		(net 1)
	)
	(via
		(at 292.45 130.31)
		(size 0.45)
		(drill 0.1)
		(layers "F.Cu" "B.Cu")
		(remove_unused_layers yes)
		(keep_end_layers yes)
		(zone_layer_connections "In1.Cu" "In4.Cu" "In6.Cu")
		(teardrops
			(best_length_ratio 0.4)
			(max_length 1)
			(best_width_ratio 0.9)
			(max_width 2)
			(curved_edges yes)
			(filter_ratio 0.9)
			(enabled yes)
			(allow_two_segments yes)
			(prefer_zone_connections yes)
		)
		(net 1)
	)
	(via
		(at 126.95 150.81)
		(size 0.45)
		(drill 0.1)
		(layers "F.Cu" "B.Cu")
		(remove_unused_layers yes)
		(keep_end_layers yes)
		(zone_layer_connections "In1.Cu" "In4.Cu" "In6.Cu")
		(teardrops
			(best_length_ratio 0.4)
			(max_length 1)
			(best_width_ratio 0.9)
			(max_width 2)
			(curved_edges yes)
			(filter_ratio 0.9)
			(enabled yes)
			(allow_two_segments yes)
			(prefer_zone_connections yes)
		)
		(net 1)
	)
	(via
		(at 186 157.9)
		(size 0.45)
		(drill 0.1)
		(layers "F.Cu" "B.Cu")
		(teardrops
			(best_length_ratio 0.4)
			(max_length 1)
			(best_width_ratio 0.9)
			(max_width 2)
			(curved_edges yes)
			(filter_ratio 0.9)
			(enabled yes)
			(allow_two_segments yes)
			(prefer_zone_connections yes)
		)
		(net 1)
	)
	(via
		(at 197.7 152.4)
		(size 0.45)
		(drill 0.1)
		(layers "F.Cu" "B.Cu")
		(teardrops
			(best_length_ratio 0.4)
			(max_length 1)
			(best_width_ratio 0.9)
			(max_width 2)
			(curved_edges yes)
			(filter_ratio 0.9)
			(enabled yes)
			(allow_two_segments yes)
			(prefer_zone_connections yes)
		)
		(net 1)
	)
	(via
		(at 289.45 139.81)
		(size 0.45)
		(drill 0.1)
		(layers "F.Cu" "B.Cu")
		(remove_unused_layers yes)
		(keep_end_layers yes)
		(zone_layer_connections "In1.Cu" "In4.Cu" "In6.Cu")
		(teardrops
			(best_length_ratio 0.4)
			(max_length 1)
			(best_width_ratio 0.9)
			(max_width 2)
			(curved_edges yes)
			(filter_ratio 0.9)
			(enabled yes)
			(allow_two_segments yes)
			(prefer_zone_connections yes)
		)
		(net 1)
	)
	(via
		(at 112.45 169.81)
		(size 0.45)
		(drill 0.1)
		(layers "F.Cu" "B.Cu")
		(remove_unused_layers yes)
		(keep_end_layers yes)
		(zone_layer_connections "In1.Cu" "In4.Cu" "In6.Cu")
		(teardrops
			(best_length_ratio 0.4)
			(max_length 1)
			(best_width_ratio 0.9)
			(max_width 2)
			(curved_edges yes)
			(filter_ratio 0.9)
			(enabled yes)
			(allow_two_segments yes)
			(prefer_zone_connections yes)
		)
		(net 1)
	)
	(via
		(at 215.68 130.25)
		(size 0.45)
		(drill 0.1)
		(layers "F.Cu" "B.Cu")
		(remove_unused_layers yes)
		(keep_end_layers yes)
		(zone_layer_connections "In1.Cu" "In4.Cu" "In6.Cu")
		(teardrops
			(best_length_ratio 0.4)
			(max_length 1)
			(best_width_ratio 0.9)
			(max_width 2)
			(curved_edges yes)
			(filter_ratio 0.9)
			(enabled yes)
			(allow_two_segments yes)
			(prefer_zone_connections yes)
		)
		(net 1)
	)
	(via
		(at 195.45 111.31)
		(size 0.45)
		(drill 0.1)
		(layers "F.Cu" "B.Cu")
		(remove_unused_layers yes)
		(keep_end_layers yes)
		(zone_layer_connections "In1.Cu" "In4.Cu" "In6.Cu")
		(teardrops
			(best_length_ratio 0.4)
			(max_length 1)
			(best_width_ratio 0.9)
			(max_width 2)
			(curved_edges yes)
			(filter_ratio 0.9)
			(enabled yes)
			(allow_two_segments yes)
			(prefer_zone_connections yes)
		)
		(net 1)
	)
	(via
		(at 262.949999 170.81)
		(size 0.45)
		(drill 0.1)
		(layers "F.Cu" "B.Cu")
		(remove_unused_layers yes)
		(keep_end_layers yes)
		(zone_layer_connections "In1.Cu" "In4.Cu" "In6.Cu")
		(teardrops
			(best_length_ratio 0.4)
			(max_length 1)
			(best_width_ratio 0.9)
			(max_width 2)
			(curved_edges yes)
			(filter_ratio 0.9)
			(enabled yes)
			(allow_two_segments yes)
			(prefer_zone_connections yes)
		)
		(net 1)
	)
	(via
		(at 152.5685 82.0595)
		(size 0.45)
		(drill 0.1)
		(layers "F.Cu" "B.Cu")
		(remove_unused_layers yes)
		(keep_end_layers yes)
		(zone_layer_connections "In1.Cu" "In4.Cu" "In6.Cu")
		(teardrops
			(best_length_ratio 0.4)
			(max_length 1)
			(best_width_ratio 0.9)
			(max_width 2)
			(curved_edges yes)
			(filter_ratio 0.9)
			(enabled yes)
			(allow_two_segments yes)
			(prefer_zone_connections yes)
		)
		(net 1)
	)
	(via
		(at 187.65 152.5)
		(size 0.45)
		(drill 0.1)
		(layers "F.Cu" "B.Cu")
		(teardrops
			(best_length_ratio 0.4)
			(max_length 1)
			(best_width_ratio 0.9)
			(max_width 2)
			(curved_edges yes)
			(filter_ratio 0.9)
			(enabled yes)
			(allow_two_segments yes)
			(prefer_zone_connections yes)
		)
		(net 1)
	)
	(via
		(at 217.17 127.32)
		(size 0.45)
		(drill 0.1)
		(layers "F.Cu" "B.Cu")
		(remove_unused_layers yes)
		(keep_end_layers yes)
		(zone_layer_connections "In1.Cu" "In4.Cu" "In6.Cu")
		(teardrops
			(best_length_ratio 0.4)
			(max_length 1)
			(best_width_ratio 0.9)
			(max_width 2)
			(curved_edges yes)
			(filter_ratio 0.9)
			(enabled yes)
			(allow_two_segments yes)
			(prefer_zone_connections yes)
		)
		(net 1)
	)
	(via
		(at 129.45 168.31)
		(size 0.45)
		(drill 0.1)
		(layers "F.Cu" "B.Cu")
		(remove_unused_layers yes)
		(keep_end_layers yes)
		(zone_layer_connections "In1.Cu" "In4.Cu" "In6.Cu")
		(teardrops
			(best_length_ratio 0.4)
			(max_length 1)
			(best_width_ratio 0.9)
			(max_width 2)
			(curved_edges yes)
			(filter_ratio 0.9)
			(enabled yes)
			(allow_two_segments yes)
			(prefer_zone_connections yes)
		)
		(net 1)
	)
	(via
		(at 297.95 145.81)
		(size 0.45)
		(drill 0.1)
		(layers "F.Cu" "B.Cu")
		(remove_unused_layers yes)
		(keep_end_layers yes)
		(zone_layer_connections "In1.Cu" "In4.Cu" "In6.Cu")
		(teardrops
			(best_length_ratio 0.4)
			(max_length 1)
			(best_width_ratio 0.9)
			(max_width 2)
			(curved_edges yes)
			(filter_ratio 0.9)
			(enabled yes)
			(allow_two_segments yes)
			(prefer_zone_connections yes)
		)
		(net 1)
	)
	(via
		(at 98.610008 160.601739)
		(size 0.45)
		(drill 0.1)
		(layers "F.Cu" "B.Cu")
		(remove_unused_layers yes)
		(keep_end_layers yes)
		(zone_layer_connections "In1.Cu" "In4.Cu" "In6.Cu")
		(teardrops
			(best_length_ratio 0.4)
			(max_length 1)
			(best_width_ratio 0.9)
			(max_width 2)
			(curved_edges yes)
			(filter_ratio 0.9)
			(enabled yes)
			(allow_two_segments yes)
			(prefer_zone_connections yes)
		)
		(net 1)
	)
	(via
		(at 105.45 126.81)
		(size 0.45)
		(drill 0.1)
		(layers "F.Cu" "B.Cu")
		(remove_unused_layers yes)
		(keep_end_layers yes)
		(zone_layer_connections "In1.Cu" "In4.Cu" "In6.Cu")
		(teardrops
			(best_length_ratio 0.4)
			(max_length 1)
			(best_width_ratio 0.9)
			(max_width 2)
			(curved_edges yes)
			(filter_ratio 0.9)
			(enabled yes)
			(allow_two_segments yes)
			(prefer_zone_connections yes)
		)
		(net 1)
	)
	(via
		(at 312.95 80.31)
		(size 0.45)
		(drill 0.1)
		(layers "F.Cu" "B.Cu")
		(remove_unused_layers yes)
		(keep_end_layers yes)
		(zone_layer_connections "In1.Cu" "In4.Cu" "In6.Cu")
		(teardrops
			(best_length_ratio 0.4)
			(max_length 1)
			(best_width_ratio 0.9)
			(max_width 2)
			(curved_edges yes)
			(filter_ratio 0.9)
			(enabled yes)
			(allow_two_segments yes)
			(prefer_zone_connections yes)
		)
		(net 1)
	)
	(via
		(at 133.28 144.775)
		(size 0.45)
		(drill 0.1)
		(layers "F.Cu" "B.Cu")
		(remove_unused_layers yes)
		(keep_end_layers yes)
		(zone_layer_connections "In1.Cu" "In4.Cu" "In6.Cu")
		(teardrops
			(best_length_ratio 0.4)
			(max_length 1)
			(best_width_ratio 0.9)
			(max_width 2)
			(curved_edges yes)
			(filter_ratio 0.9)
			(enabled yes)
			(allow_two_segments yes)
			(prefer_zone_connections yes)
		)
		(net 1)
	)
	(via
		(at 287.95 147.31)
		(size 0.45)
		(drill 0.1)
		(layers "F.Cu" "B.Cu")
		(remove_unused_layers yes)
		(keep_end_layers yes)
		(zone_layer_connections "In1.Cu" "In4.Cu" "In6.Cu")
		(teardrops
			(best_length_ratio 0.4)
			(max_length 1)
			(best_width_ratio 0.9)
			(max_width 2)
			(curved_edges yes)
			(filter_ratio 0.9)
			(enabled yes)
			(allow_two_segments yes)
			(prefer_zone_connections yes)
		)
		(net 1)
	)
	(via
		(at 268.95 170.81)
		(size 0.45)
		(drill 0.1)
		(layers "F.Cu" "B.Cu")
		(remove_unused_layers yes)
		(keep_end_layers yes)
		(zone_layer_connections "In1.Cu" "In4.Cu" "In6.Cu")
		(teardrops
			(best_length_ratio 0.4)
			(max_length 1)
			(best_width_ratio 0.9)
			(max_width 2)
			(curved_edges yes)
			(filter_ratio 0.9)
			(enabled yes)
			(allow_two_segments yes)
			(prefer_zone_connections yes)
		)
		(net 1)
	)
	(via
		(at 300.95 145.31)
		(size 0.45)
		(drill 0.1)
		(layers "F.Cu" "B.Cu")
		(remove_unused_layers yes)
		(keep_end_layers yes)
		(zone_layer_connections "In1.Cu" "In4.Cu" "In6.Cu")
		(teardrops
			(best_length_ratio 0.4)
			(max_length 1)
			(best_width_ratio 0.9)
			(max_width 2)
			(curved_edges yes)
			(filter_ratio 0.9)
			(enabled yes)
			(allow_two_segments yes)
			(prefer_zone_connections yes)
		)
		(net 1)
	)
	(via
		(at 156.45 132.86)
		(size 0.45)
		(drill 0.1)
		(layers "F.Cu" "B.Cu")
		(remove_unused_layers yes)
		(keep_end_layers yes)
		(zone_layer_connections "In1.Cu" "In4.Cu" "In6.Cu")
		(teardrops
			(best_length_ratio 0.4)
			(max_length 1)
			(best_width_ratio 0.9)
			(max_width 2)
			(curved_edges yes)
			(filter_ratio 0.9)
			(enabled yes)
			(allow_two_segments yes)
			(prefer_zone_connections yes)
		)
		(net 1)
	)
	(via
		(at 165.45 68.81)
		(size 0.45)
		(drill 0.1)
		(layers "F.Cu" "B.Cu")
		(remove_unused_layers yes)
		(keep_end_layers yes)
		(zone_layer_connections "In1.Cu" "In4.Cu" "In6.Cu")
		(teardrops
			(best_length_ratio 0.4)
			(max_length 1)
			(best_width_ratio 0.9)
			(max_width 2)
			(curved_edges yes)
			(filter_ratio 0.9)
			(enabled yes)
			(allow_two_segments yes)
			(prefer_zone_connections yes)
		)
		(net 1)
	)
	(via
		(at 240.95 88.31)
		(size 0.45)
		(drill 0.1)
		(layers "F.Cu" "B.Cu")
		(remove_unused_layers yes)
		(keep_end_layers yes)
		(zone_layer_connections "In1.Cu" "In4.Cu" "In6.Cu")
		(teardrops
			(best_length_ratio 0.4)
			(max_length 1)
			(best_width_ratio 0.9)
			(max_width 2)
			(curved_edges yes)
			(filter_ratio 0.9)
			(enabled yes)
			(allow_two_segments yes)
			(prefer_zone_connections yes)
		)
		(net 1)
	)
	(via
		(at 282.45 110.81)
		(size 0.45)
		(drill 0.1)
		(layers "F.Cu" "B.Cu")
		(remove_unused_layers yes)
		(keep_end_layers yes)
		(zone_layer_connections "In1.Cu" "In4.Cu" "In6.Cu")
		(teardrops
			(best_length_ratio 0.4)
			(max_length 1)
			(best_width_ratio 0.9)
			(max_width 2)
			(curved_edges yes)
			(filter_ratio 0.9)
			(enabled yes)
			(allow_two_segments yes)
			(prefer_zone_connections yes)
		)
		(net 1)
	)
	(via
		(at 121.45 94.31)
		(size 0.45)
		(drill 0.1)
		(layers "F.Cu" "B.Cu")
		(remove_unused_layers yes)
		(keep_end_layers yes)
		(zone_layer_connections "In1.Cu" "In4.Cu" "In6.Cu")
		(teardrops
			(best_length_ratio 0.4)
			(max_length 1)
			(best_width_ratio 0.9)
			(max_width 2)
			(curved_edges yes)
			(filter_ratio 0.9)
			(enabled yes)
			(allow_two_segments yes)
			(prefer_zone_connections yes)
		)
		(net 1)
	)
	(via
		(at 302.575 139.705)
		(size 0.45)
		(drill 0.1)
		(layers "F.Cu" "B.Cu")
		(remove_unused_layers yes)
		(keep_end_layers yes)
		(zone_layer_connections "In1.Cu" "In4.Cu" "In6.Cu")
		(teardrops
			(best_length_ratio 0.4)
			(max_length 1)
			(best_width_ratio 0.9)
			(max_width 2)
			(curved_edges yes)
			(filter_ratio 0.9)
			(enabled yes)
			(allow_two_segments yes)
			(prefer_zone_connections yes)
		)
		(net 1)
	)
	(via
		(at 207.05 161.85)
		(size 0.45)
		(drill 0.1)
		(layers "F.Cu" "B.Cu")
		(teardrops
			(best_length_ratio 0.4)
			(max_length 1)
			(best_width_ratio 0.9)
			(max_width 2)
			(curved_edges yes)
			(filter_ratio 0.9)
			(enabled yes)
			(allow_two_segments yes)
			(prefer_zone_connections yes)
		)
		(net 1)
	)
	(via
		(at 260.95 97.81)
		(size 0.45)
		(drill 0.1)
		(layers "F.Cu" "B.Cu")
		(remove_unused_layers yes)
		(keep_end_layers yes)
		(zone_layer_connections "In1.Cu" "In4.Cu" "In6.Cu")
		(teardrops
			(best_length_ratio 0.4)
			(max_length 1)
			(best_width_ratio 0.9)
			(max_width 2)
			(curved_edges yes)
			(filter_ratio 0.9)
			(enabled yes)
			(allow_two_segments yes)
			(prefer_zone_connections yes)
		)
		(net 1)
	)
	(via
		(at 176.525 149.925)
		(size 0.45)
		(drill 0.1)
		(layers "F.Cu" "B.Cu")
		(teardrops
			(best_length_ratio 0.4)
			(max_length 1)
			(best_width_ratio 0.9)
			(max_width 2)
			(curved_edges yes)
			(filter_ratio 0.9)
			(enabled yes)
			(allow_two_segments yes)
			(prefer_zone_connections yes)
		)
		(net 1)
	)
	(via
		(at 213.55 152.3)
		(size 0.45)
		(drill 0.1)
		(layers "F.Cu" "B.Cu")
		(teardrops
			(best_length_ratio 0.4)
			(max_length 1)
			(best_width_ratio 0.9)
			(max_width 2)
			(curved_edges yes)
			(filter_ratio 0.9)
			(enabled yes)
			(allow_two_segments yes)
			(prefer_zone_connections yes)
		)
		(net 1)
	)
	(via
		(at 96.45 123.81)
		(size 0.45)
		(drill 0.1)
		(layers "F.Cu" "B.Cu")
		(remove_unused_layers yes)
		(keep_end_layers yes)
		(zone_layer_connections "In1.Cu" "In4.Cu" "In6.Cu")
		(teardrops
			(best_length_ratio 0.4)
			(max_length 1)
			(best_width_ratio 0.9)
			(max_width 2)
			(curved_edges yes)
			(filter_ratio 0.9)
			(enabled yes)
			(allow_two_segments yes)
			(prefer_zone_connections yes)
		)
		(net 1)
	)
	(via
		(at 303.95 86.31)
		(size 0.45)
		(drill 0.1)
		(layers "F.Cu" "B.Cu")
		(remove_unused_layers yes)
		(keep_end_layers yes)
		(zone_layer_connections "In1.Cu" "In4.Cu" "In6.Cu")
		(teardrops
			(best_length_ratio 0.4)
			(max_length 1)
			(best_width_ratio 0.9)
			(max_width 2)
			(curved_edges yes)
			(filter_ratio 0.9)
			(enabled yes)
			(allow_two_segments yes)
			(prefer_zone_connections yes)
		)
		(net 1)
	)
	(via
		(at 167.95 80.81)
		(size 0.45)
		(drill 0.1)
		(layers "F.Cu" "B.Cu")
		(remove_unused_layers yes)
		(keep_end_layers yes)
		(free yes)
		(zone_layer_connections "In1.Cu" "In4.Cu" "In6.Cu")
		(teardrops
			(best_length_ratio 0.4)
			(max_length 1)
			(best_width_ratio 0.9)
			(max_width 2)
			(curved_edges yes)
			(filter_ratio 0.9)
			(enabled yes)
			(allow_two_segments yes)
			(prefer_zone_connections yes)
		)
		(net 1)
	)
	(via
		(at 241.950001 166.31)
		(size 0.45)
		(drill 0.1)
		(layers "F.Cu" "B.Cu")
		(remove_unused_layers yes)
		(keep_end_layers yes)
		(zone_layer_connections "In1.Cu" "In4.Cu" "In6.Cu")
		(teardrops
			(best_length_ratio 0.4)
			(max_length 1)
			(best_width_ratio 0.9)
			(max_width 2)
			(curved_edges yes)
			(filter_ratio 0.9)
			(enabled yes)
			(allow_two_segments yes)
			(prefer_zone_connections yes)
		)
		(net 1)
	)
	(via
		(at 112.95 92.66)
		(size 0.45)
		(drill 0.1)
		(layers "F.Cu" "B.Cu")
		(remove_unused_layers yes)
		(keep_end_layers yes)
		(zone_layer_connections "In1.Cu" "In4.Cu" "In6.Cu")
		(teardrops
			(best_length_ratio 0.4)
			(max_length 1)
			(best_width_ratio 0.9)
			(max_width 2)
			(curved_edges yes)
			(filter_ratio 0.9)
			(enabled yes)
			(allow_two_segments yes)
			(prefer_zone_connections yes)
		)
		(net 1)
	)
	(via
		(at 109.125 164.15)
		(size 0.45)
		(drill 0.1)
		(layers "F.Cu" "B.Cu")
		(remove_unused_layers yes)
		(keep_end_layers yes)
		(free yes)
		(zone_layer_connections "In1.Cu" "In4.Cu" "In6.Cu")
		(teardrops
			(best_length_ratio 0.4)
			(max_length 1)
			(best_width_ratio 0.9)
			(max_width 2)
			(curved_edges yes)
			(filter_ratio 0.9)
			(enabled yes)
			(allow_two_segments yes)
			(prefer_zone_connections yes)
		)
		(net 1)
	)
	(via
		(at 283.45 139.81)
		(size 0.45)
		(drill 0.1)
		(layers "F.Cu" "B.Cu")
		(remove_unused_layers yes)
		(keep_end_layers yes)
		(zone_layer_connections "In1.Cu" "In4.Cu" "In6.Cu")
		(teardrops
			(best_length_ratio 0.4)
			(max_length 1)
			(best_width_ratio 0.9)
			(max_width 2)
			(curved_edges yes)
			(filter_ratio 0.9)
			(enabled yes)
			(allow_two_segments yes)
			(prefer_zone_connections yes)
		)
		(net 1)
	)
	(via
		(at 194.45 94.31)
		(size 0.45)
		(drill 0.1)
		(layers "F.Cu" "B.Cu")
		(remove_unused_layers yes)
		(keep_end_layers yes)
		(free yes)
		(zone_layer_connections "In1.Cu" "In4.Cu" "In6.Cu")
		(teardrops
			(best_length_ratio 0.4)
			(max_length 1)
			(best_width_ratio 0.9)
			(max_width 2)
			(curved_edges yes)
			(filter_ratio 0.9)
			(enabled yes)
			(allow_two_segments yes)
			(prefer_zone_connections yes)
		)
		(net 1)
	)
	(via
		(at 177.18 110.36)
		(size 0.45)
		(drill 0.1)
		(layers "F.Cu" "B.Cu")
		(remove_unused_layers yes)
		(keep_end_layers yes)
		(zone_layer_connections "In1.Cu" "In4.Cu" "In6.Cu")
		(teardrops
			(best_length_ratio 0.4)
			(max_length 1)
			(best_width_ratio 0.9)
			(max_width 2)
			(curved_edges yes)
			(filter_ratio 0.9)
			(enabled yes)
			(allow_two_segments yes)
			(prefer_zone_connections yes)
		)
		(net 1)
	)
	(via
		(at 274.95 166.41)
		(size 0.45)
		(drill 0.1)
		(layers "F.Cu" "B.Cu")
		(remove_unused_layers yes)
		(keep_end_layers yes)
		(zone_layer_connections "In1.Cu" "In4.Cu" "In6.Cu")
		(teardrops
			(best_length_ratio 0.4)
			(max_length 1)
			(best_width_ratio 0.9)
			(max_width 2)
			(curved_edges yes)
			(filter_ratio 0.9)
			(enabled yes)
			(allow_two_segments yes)
			(prefer_zone_connections yes)
		)
		(net 1)
	)
	(via
		(at 122.45 164.81)
		(size 0.45)
		(drill 0.1)
		(layers "F.Cu" "B.Cu")
		(remove_unused_layers yes)
		(keep_end_layers yes)
		(zone_layer_connections "In1.Cu" "In4.Cu" "In6.Cu")
		(teardrops
			(best_length_ratio 0.4)
			(max_length 1)
			(best_width_ratio 0.9)
			(max_width 2)
			(curved_edges yes)
			(filter_ratio 0.9)
			(enabled yes)
			(allow_two_segments yes)
			(prefer_zone_connections yes)
		)
		(net 1)
	)
	(via
		(at 225.027208 145.622792)
		(size 0.45)
		(drill 0.1)
		(layers "F.Cu" "B.Cu")
		(teardrops
			(best_length_ratio 0.4)
			(max_length 1)
			(best_width_ratio 0.9)
			(max_width 2)
			(curved_edges yes)
			(filter_ratio 0.9)
			(enabled yes)
			(allow_two_segments yes)
			(prefer_zone_connections yes)
		)
		(net 1)
	)
	(via
		(at 177.18 110.86)
		(size 0.45)
		(drill 0.1)
		(layers "F.Cu" "B.Cu")
		(remove_unused_layers yes)
		(keep_end_layers yes)
		(zone_layer_connections "In1.Cu" "In4.Cu" "In6.Cu")
		(teardrops
			(best_length_ratio 0.4)
			(max_length 1)
			(best_width_ratio 0.9)
			(max_width 2)
			(curved_edges yes)
			(filter_ratio 0.9)
			(enabled yes)
			(allow_two_segments yes)
			(prefer_zone_connections yes)
		)
		(net 1)
	)
	(via
		(at 285.45 166.41)
		(size 0.45)
		(drill 0.1)
		(layers "F.Cu" "B.Cu")
		(remove_unused_layers yes)
		(keep_end_layers yes)
		(zone_layer_connections "In1.Cu" "In4.Cu" "In6.Cu")
		(teardrops
			(best_length_ratio 0.4)
			(max_length 1)
			(best_width_ratio 0.9)
			(max_width 2)
			(curved_edges yes)
			(filter_ratio 0.9)
			(enabled yes)
			(allow_two_segments yes)
			(prefer_zone_connections yes)
		)
		(net 1)
	)
	(via
		(at 231.31 164.63)
		(size 0.45)
		(drill 0.1)
		(layers "F.Cu" "B.Cu")
		(teardrops
			(best_length_ratio 0.4)
			(max_length 1)
			(best_width_ratio 0.9)
			(max_width 2)
			(curved_edges yes)
			(filter_ratio 0.9)
			(enabled yes)
			(allow_two_segments yes)
			(prefer_zone_connections yes)
		)
		(net 1)
	)
	(via
		(at 112.98 132.4)
		(size 0.45)
		(drill 0.1)
		(layers "F.Cu" "B.Cu")
		(remove_unused_layers yes)
		(keep_end_layers yes)
		(zone_layer_connections "In1.Cu" "In4.Cu" "In6.Cu")
		(teardrops
			(best_length_ratio 0.4)
			(max_length 1)
			(best_width_ratio 0.9)
			(max_width 2)
			(curved_edges yes)
			(filter_ratio 0.9)
			(enabled yes)
			(allow_two_segments yes)
			(prefer_zone_connections yes)
		)
		(net 1)
	)
	(via
		(at 174.45 71.81)
		(size 0.45)
		(drill 0.1)
		(layers "F.Cu" "B.Cu")
		(remove_unused_layers yes)
		(keep_end_layers yes)
		(zone_layer_connections "In1.Cu" "In4.Cu" "In6.Cu")
		(teardrops
			(best_length_ratio 0.4)
			(max_length 1)
			(best_width_ratio 0.9)
			(max_width 2)
			(curved_edges yes)
			(filter_ratio 0.9)
			(enabled yes)
			(allow_two_segments yes)
			(prefer_zone_connections yes)
		)
		(net 1)
	)
	(via
		(at 106.08 72.675)
		(size 0.45)
		(drill 0.1)
		(layers "F.Cu" "B.Cu")
		(remove_unused_layers yes)
		(keep_end_layers yes)
		(zone_layer_connections "In1.Cu" "In4.Cu" "In6.Cu")
		(teardrops
			(best_length_ratio 0.4)
			(max_length 1)
			(best_width_ratio 0.9)
			(max_width 2)
			(curved_edges yes)
			(filter_ratio 0.9)
			(enabled yes)
			(allow_two_segments yes)
			(prefer_zone_connections yes)
		)
		(net 1)
	)
	(via
		(at 133.85 147.614044)
		(size 0.45)
		(drill 0.1)
		(layers "F.Cu" "B.Cu")
		(remove_unused_layers yes)
		(keep_end_layers yes)
		(zone_layer_connections "In1.Cu" "In4.Cu" "In6.Cu")
		(teardrops
			(best_length_ratio 0.4)
			(max_length 1)
			(best_width_ratio 0.9)
			(max_width 2)
			(curved_edges yes)
			(filter_ratio 0.9)
			(enabled yes)
			(allow_two_segments yes)
			(prefer_zone_connections yes)
		)
		(net 1)
	)
	(via
		(at 288.45 133.31)
		(size 0.45)
		(drill 0.1)
		(layers "F.Cu" "B.Cu")
		(remove_unused_layers yes)
		(keep_end_layers yes)
		(zone_layer_connections "In1.Cu" "In4.Cu" "In6.Cu")
		(teardrops
			(best_length_ratio 0.4)
			(max_length 1)
			(best_width_ratio 0.9)
			(max_width 2)
			(curved_edges yes)
			(filter_ratio 0.9)
			(enabled yes)
			(allow_two_segments yes)
			(prefer_zone_connections yes)
		)
		(net 1)
	)
	(via
		(at 156.15 156.1)
		(size 0.45)
		(drill 0.1)
		(layers "F.Cu" "B.Cu")
		(remove_unused_layers yes)
		(keep_end_layers yes)
		(zone_layer_connections "In1.Cu" "In4.Cu" "In6.Cu")
		(teardrops
			(best_length_ratio 0.4)
			(max_length 1)
			(best_width_ratio 0.9)
			(max_width 2)
			(curved_edges yes)
			(filter_ratio 0.9)
			(enabled yes)
			(allow_two_segments yes)
			(prefer_zone_connections yes)
		)
		(net 1)
	)
	(via
		(at 189.45 68.81)
		(size 0.45)
		(drill 0.1)
		(layers "F.Cu" "B.Cu")
		(remove_unused_layers yes)
		(keep_end_layers yes)
		(zone_layer_connections "In1.Cu" "In4.Cu" "In6.Cu")
		(teardrops
			(best_length_ratio 0.4)
			(max_length 1)
			(best_width_ratio 0.9)
			(max_width 2)
			(curved_edges yes)
			(filter_ratio 0.9)
			(enabled yes)
			(allow_two_segments yes)
			(prefer_zone_connections yes)
		)
		(net 1)
	)
	(via
		(at 133.45 168.31)
		(size 0.45)
		(drill 0.1)
		(layers "F.Cu" "B.Cu")
		(remove_unused_layers yes)
		(keep_end_layers yes)
		(zone_layer_connections "In1.Cu" "In4.Cu" "In6.Cu")
		(teardrops
			(best_length_ratio 0.4)
			(max_length 1)
			(best_width_ratio 0.9)
			(max_width 2)
			(curved_edges yes)
			(filter_ratio 0.9)
			(enabled yes)
			(allow_two_segments yes)
			(prefer_zone_connections yes)
		)
		(net 1)
	)
	(via
		(at 290.4 78.42)
		(size 0.45)
		(drill 0.1)
		(layers "F.Cu" "B.Cu")
		(remove_unused_layers yes)
		(keep_end_layers yes)
		(free yes)
		(zone_layer_connections "In1.Cu" "In4.Cu" "In6.Cu")
		(teardrops
			(best_length_ratio 0.4)
			(max_length 1)
			(best_width_ratio 0.9)
			(max_width 2)
			(curved_edges yes)
			(filter_ratio 0.9)
			(enabled yes)
			(allow_two_segments yes)
			(prefer_zone_connections yes)
		)
		(net 1)
	)
	(via
		(at 261.950708 75.76)
		(size 0.45)
		(drill 0.1)
		(layers "F.Cu" "B.Cu")
		(remove_unused_layers yes)
		(keep_end_layers yes)
		(zone_layer_connections "In1.Cu" "In4.Cu" "In6.Cu")
		(teardrops
			(best_length_ratio 0.4)
			(max_length 1)
			(best_width_ratio 0.9)
			(max_width 2)
			(curved_edges yes)
			(filter_ratio 0.9)
			(enabled yes)
			(allow_two_segments yes)
			(prefer_zone_connections yes)
		)
		(net 1)
	)
	(via
		(at 96.801 72.96)
		(size 0.45)
		(drill 0.1)
		(layers "F.Cu" "B.Cu")
		(remove_unused_layers yes)
		(keep_end_layers yes)
		(zone_layer_connections "In1.Cu" "In4.Cu" "In6.Cu")
		(teardrops
			(best_length_ratio 0.4)
			(max_length 1)
			(best_width_ratio 0.9)
			(max_width 2)
			(curved_edges yes)
			(filter_ratio 0.9)
			(enabled yes)
			(allow_two_segments yes)
			(prefer_zone_connections yes)
		)
		(net 1)
	)
	(via
		(at 130.29 142.86)
		(size 0.45)
		(drill 0.1)
		(layers "F.Cu" "B.Cu")
		(remove_unused_layers yes)
		(keep_end_layers yes)
		(zone_layer_connections "In1.Cu" "In4.Cu" "In6.Cu")
		(teardrops
			(best_length_ratio 0.4)
			(max_length 1)
			(best_width_ratio 0.9)
			(max_width 2)
			(curved_edges yes)
			(filter_ratio 0.9)
			(enabled yes)
			(allow_two_segments yes)
			(prefer_zone_connections yes)
		)
		(net 1)
	)
	(via
		(at 119.45 170.81)
		(size 0.45)
		(drill 0.1)
		(layers "F.Cu" "B.Cu")
		(remove_unused_layers yes)
		(keep_end_layers yes)
		(zone_layer_connections "In1.Cu" "In4.Cu" "In6.Cu")
		(teardrops
			(best_length_ratio 0.4)
			(max_length 1)
			(best_width_ratio 0.9)
			(max_width 2)
			(curved_edges yes)
			(filter_ratio 0.9)
			(enabled yes)
			(allow_two_segments yes)
			(prefer_zone_connections yes)
		)
		(net 1)
	)
	(via
		(at 317.7 158.51)
		(size 0.45)
		(drill 0.1)
		(layers "F.Cu" "B.Cu")
		(remove_unused_layers yes)
		(keep_end_layers yes)
		(zone_layer_connections "In1.Cu" "In4.Cu" "In6.Cu")
		(teardrops
			(best_length_ratio 0.4)
			(max_length 1)
			(best_width_ratio 0.9)
			(max_width 2)
			(curved_edges yes)
			(filter_ratio 0.9)
			(enabled yes)
			(allow_two_segments yes)
			(prefer_zone_connections yes)
		)
		(net 1)
	)
	(via
		(at 133.29 145.86)
		(size 0.45)
		(drill 0.1)
		(layers "F.Cu" "B.Cu")
		(remove_unused_layers yes)
		(keep_end_layers yes)
		(zone_layer_connections "In1.Cu" "In4.Cu" "In6.Cu")
		(teardrops
			(best_length_ratio 0.4)
			(max_length 1)
			(best_width_ratio 0.9)
			(max_width 2)
			(curved_edges yes)
			(filter_ratio 0.9)
			(enabled yes)
			(allow_two_segments yes)
			(prefer_zone_connections yes)
		)
		(net 1)
	)
	(via
		(at 204 167.5)
		(size 0.45)
		(drill 0.1)
		(layers "F.Cu" "B.Cu")
		(teardrops
			(best_length_ratio 0.4)
			(max_length 1)
			(best_width_ratio 0.9)
			(max_width 2)
			(curved_edges yes)
			(filter_ratio 0.9)
			(enabled yes)
			(allow_two_segments yes)
			(prefer_zone_connections yes)
		)
		(net 1)
	)
	(via
		(at 252.135 81.174999)
		(size 0.45)
		(drill 0.1)
		(layers "F.Cu" "B.Cu")
		(remove_unused_layers yes)
		(keep_end_layers yes)
		(zone_layer_connections "In1.Cu" "In4.Cu" "In6.Cu")
		(teardrops
			(best_length_ratio 0.4)
			(max_length 1)
			(best_width_ratio 0.9)
			(max_width 2)
			(curved_edges yes)
			(filter_ratio 0.9)
			(enabled yes)
			(allow_two_segments yes)
			(prefer_zone_connections yes)
		)
		(net 1)
	)
	(via
		(at 279.45 116.81)
		(size 0.45)
		(drill 0.1)
		(layers "F.Cu" "B.Cu")
		(remove_unused_layers yes)
		(keep_end_layers yes)
		(zone_layer_connections "In1.Cu" "In4.Cu" "In6.Cu")
		(teardrops
			(best_length_ratio 0.4)
			(max_length 1)
			(best_width_ratio 0.9)
			(max_width 2)
			(curved_edges yes)
			(filter_ratio 0.9)
			(enabled yes)
			(allow_two_segments yes)
			(prefer_zone_connections yes)
		)
		(net 1)
	)
	(via
		(at 136.28187 100.19078)
		(size 0.45)
		(drill 0.1)
		(layers "F.Cu" "B.Cu")
		(remove_unused_layers yes)
		(keep_end_layers yes)
		(zone_layer_connections "In1.Cu" "In4.Cu" "In6.Cu")
		(teardrops
			(best_length_ratio 0.4)
			(max_length 1)
			(best_width_ratio 0.9)
			(max_width 2)
			(curved_edges yes)
			(filter_ratio 0.9)
			(enabled yes)
			(allow_two_segments yes)
			(prefer_zone_connections yes)
		)
		(net 1)
	)
	(via
		(at 98.45 96.81)
		(size 0.45)
		(drill 0.1)
		(layers "F.Cu" "B.Cu")
		(remove_unused_layers yes)
		(keep_end_layers yes)
		(zone_layer_connections "In1.Cu" "In4.Cu" "In6.Cu")
		(teardrops
			(best_length_ratio 0.4)
			(max_length 1)
			(best_width_ratio 0.9)
			(max_width 2)
			(curved_edges yes)
			(filter_ratio 0.9)
			(enabled yes)
			(allow_two_segments yes)
			(prefer_zone_connections yes)
		)
		(net 1)
	)
	(via
		(at 95.45 104.81)
		(size 0.45)
		(drill 0.1)
		(layers "F.Cu" "B.Cu")
		(remove_unused_layers yes)
		(keep_end_layers yes)
		(zone_layer_connections "In1.Cu" "In4.Cu" "In6.Cu")
		(teardrops
			(best_length_ratio 0.4)
			(max_length 1)
			(best_width_ratio 0.9)
			(max_width 2)
			(curved_edges yes)
			(filter_ratio 0.9)
			(enabled yes)
			(allow_two_segments yes)
			(prefer_zone_connections yes)
		)
		(net 1)
	)
	(via
		(at 230.5 169.89)
		(size 0.45)
		(drill 0.1)
		(layers "F.Cu" "B.Cu")
		(teardrops
			(best_length_ratio 0.4)
			(max_length 1)
			(best_width_ratio 0.9)
			(max_width 2)
			(curved_edges yes)
			(filter_ratio 0.9)
			(enabled yes)
			(allow_two_segments yes)
			(prefer_zone_connections yes)
		)
		(net 1)
	)
	(via
		(at 297.95 120.31)
		(size 0.45)
		(drill 0.1)
		(layers "F.Cu" "B.Cu")
		(remove_unused_layers yes)
		(keep_end_layers yes)
		(zone_layer_connections "In1.Cu" "In4.Cu" "In6.Cu")
		(teardrops
			(best_length_ratio 0.4)
			(max_length 1)
			(best_width_ratio 0.9)
			(max_width 2)
			(curved_edges yes)
			(filter_ratio 0.9)
			(enabled yes)
			(allow_two_segments yes)
			(prefer_zone_connections yes)
		)
		(net 1)
	)
	(via
		(at 219.45 87.81)
		(size 0.45)
		(drill 0.1)
		(layers "F.Cu" "B.Cu")
		(remove_unused_layers yes)
		(keep_end_layers yes)
		(zone_layer_connections "In1.Cu" "In4.Cu" "In6.Cu")
		(teardrops
			(best_length_ratio 0.4)
			(max_length 1)
			(best_width_ratio 0.9)
			(max_width 2)
			(curved_edges yes)
			(filter_ratio 0.9)
			(enabled yes)
			(allow_two_segments yes)
			(prefer_zone_connections yes)
		)
		(net 1)
	)
	(via
		(at 121.95 155.81)
		(size 0.45)
		(drill 0.1)
		(layers "F.Cu" "B.Cu")
		(remove_unused_layers yes)
		(keep_end_layers yes)
		(zone_layer_connections "In1.Cu" "In4.Cu" "In6.Cu")
		(teardrops
			(best_length_ratio 0.4)
			(max_length 1)
			(best_width_ratio 0.9)
			(max_width 2)
			(curved_edges yes)
			(filter_ratio 0.9)
			(enabled yes)
			(allow_two_segments yes)
			(prefer_zone_connections yes)
		)
		(net 1)
	)
	(via
		(at 96.95 91.81)
		(size 0.45)
		(drill 0.1)
		(layers "F.Cu" "B.Cu")
		(remove_unused_layers yes)
		(keep_end_layers yes)
		(zone_layer_connections "In1.Cu" "In4.Cu" "In6.Cu")
		(teardrops
			(best_length_ratio 0.4)
			(max_length 1)
			(best_width_ratio 0.9)
			(max_width 2)
			(curved_edges yes)
			(filter_ratio 0.9)
			(enabled yes)
			(allow_two_segments yes)
			(prefer_zone_connections yes)
		)
		(net 1)
	)
	(via
		(at 175.95 149.925)
		(size 0.45)
		(drill 0.1)
		(layers "F.Cu" "B.Cu")
		(teardrops
			(best_length_ratio 0.4)
			(max_length 1)
			(best_width_ratio 0.9)
			(max_width 2)
			(curved_edges yes)
			(filter_ratio 0.9)
			(enabled yes)
			(allow_two_segments yes)
			(prefer_zone_connections yes)
		)
		(net 1)
	)
	(via
		(at 290.95 89.81)
		(size 0.45)
		(drill 0.1)
		(layers "F.Cu" "B.Cu")
		(remove_unused_layers yes)
		(keep_end_layers yes)
		(zone_layer_connections "In1.Cu" "In4.Cu" "In6.Cu")
		(teardrops
			(best_length_ratio 0.4)
			(max_length 1)
			(best_width_ratio 0.9)
			(max_width 2)
			(curved_edges yes)
			(filter_ratio 0.9)
			(enabled yes)
			(allow_two_segments yes)
			(prefer_zone_connections yes)
		)
		(net 1)
	)
	(via
		(at 206.984134 129.147033)
		(size 0.45)
		(drill 0.1)
		(layers "F.Cu" "B.Cu")
		(remove_unused_layers yes)
		(keep_end_layers yes)
		(zone_layer_connections "In1.Cu" "In4.Cu" "In6.Cu")
		(teardrops
			(best_length_ratio 0.4)
			(max_length 1)
			(best_width_ratio 0.9)
			(max_width 2)
			(curved_edges yes)
			(filter_ratio 0.9)
			(enabled yes)
			(allow_two_segments yes)
			(prefer_zone_connections yes)
		)
		(net 1)
	)
	(via
		(at 291.45 134.81)
		(size 0.45)
		(drill 0.1)
		(layers "F.Cu" "B.Cu")
		(remove_unused_layers yes)
		(keep_end_layers yes)
		(zone_layer_connections "In1.Cu" "In4.Cu" "In6.Cu")
		(teardrops
			(best_length_ratio 0.4)
			(max_length 1)
			(best_width_ratio 0.9)
			(max_width 2)
			(curved_edges yes)
			(filter_ratio 0.9)
			(enabled yes)
			(allow_two_segments yes)
			(prefer_zone_connections yes)
		)
		(net 1)
	)
	(via
		(at 174.45 90.81)
		(size 0.45)
		(drill 0.1)
		(layers "F.Cu" "B.Cu")
		(remove_unused_layers yes)
		(keep_end_layers yes)
		(zone_layer_connections "In1.Cu" "In4.Cu" "In6.Cu")
		(teardrops
			(best_length_ratio 0.4)
			(max_length 1)
			(best_width_ratio 0.9)
			(max_width 2)
			(curved_edges yes)
			(filter_ratio 0.9)
			(enabled yes)
			(allow_two_segments yes)
			(prefer_zone_connections yes)
		)
		(net 1)
	)
	(via
		(at 129.45 165.81)
		(size 0.45)
		(drill 0.1)
		(layers "F.Cu" "B.Cu")
		(remove_unused_layers yes)
		(keep_end_layers yes)
		(zone_layer_connections "In1.Cu" "In4.Cu" "In6.Cu")
		(teardrops
			(best_length_ratio 0.4)
			(max_length 1)
			(best_width_ratio 0.9)
			(max_width 2)
			(curved_edges yes)
			(filter_ratio 0.9)
			(enabled yes)
			(allow_two_segments yes)
			(prefer_zone_connections yes)
		)
		(net 1)
	)
	(via
		(at 97.5 149.7)
		(size 0.45)
		(drill 0.1)
		(layers "F.Cu" "B.Cu")
		(remove_unused_layers yes)
		(keep_end_layers yes)
		(zone_layer_connections "In1.Cu" "In4.Cu" "In6.Cu")
		(teardrops
			(best_length_ratio 0.4)
			(max_length 1)
			(best_width_ratio 0.9)
			(max_width 2)
			(curved_edges yes)
			(filter_ratio 0.9)
			(enabled yes)
			(allow_two_segments yes)
			(prefer_zone_connections yes)
		)
		(net 1)
	)
	(via
		(at 158.4 153.8)
		(size 0.45)
		(drill 0.1)
		(layers "F.Cu" "B.Cu")
		(remove_unused_layers yes)
		(keep_end_layers yes)
		(zone_layer_connections "In1.Cu" "In4.Cu" "In6.Cu")
		(teardrops
			(best_length_ratio 0.4)
			(max_length 1)
			(best_width_ratio 0.9)
			(max_width 2)
			(curved_edges yes)
			(filter_ratio 0.9)
			(enabled yes)
			(allow_two_segments yes)
			(prefer_zone_connections yes)
		)
		(net 1)
	)
	(via
		(at 199.2 170.1)
		(size 0.45)
		(drill 0.1)
		(layers "F.Cu" "B.Cu")
		(teardrops
			(best_length_ratio 0.4)
			(max_length 1)
			(best_width_ratio 0.9)
			(max_width 2)
			(curved_edges yes)
			(filter_ratio 0.9)
			(enabled yes)
			(allow_two_segments yes)
			(prefer_zone_connections yes)
		)
		(net 1)
	)
	(via
		(at 96.95 97.81)
		(size 0.45)
		(drill 0.1)
		(layers "F.Cu" "B.Cu")
		(remove_unused_layers yes)
		(keep_end_layers yes)
		(zone_layer_connections "In1.Cu" "In4.Cu" "In6.Cu")
		(teardrops
			(best_length_ratio 0.4)
			(max_length 1)
			(best_width_ratio 0.9)
			(max_width 2)
			(curved_edges yes)
			(filter_ratio 0.9)
			(enabled yes)
			(allow_two_segments yes)
			(prefer_zone_connections yes)
		)
		(net 1)
	)
	(via
		(at 283.95 109.31)
		(size 0.45)
		(drill 0.1)
		(layers "F.Cu" "B.Cu")
		(remove_unused_layers yes)
		(keep_end_layers yes)
		(zone_layer_connections "In1.Cu" "In4.Cu" "In6.Cu")
		(teardrops
			(best_length_ratio 0.4)
			(max_length 1)
			(best_width_ratio 0.9)
			(max_width 2)
			(curved_edges yes)
			(filter_ratio 0.9)
			(enabled yes)
			(allow_two_segments yes)
			(prefer_zone_connections yes)
		)
		(net 1)
	)
	(via
		(at 298.3 101.11)
		(size 0.45)
		(drill 0.1)
		(layers "F.Cu" "B.Cu")
		(remove_unused_layers yes)
		(keep_end_layers yes)
		(zone_layer_connections "In1.Cu" "In4.Cu" "In6.Cu")
		(teardrops
			(best_length_ratio 0.4)
			(max_length 1)
			(best_width_ratio 0.9)
			(max_width 2)
			(curved_edges yes)
			(filter_ratio 0.9)
			(enabled yes)
			(allow_two_segments yes)
			(prefer_zone_connections yes)
		)
		(net 1)
	)
	(via
		(at 119.45 165.81)
		(size 0.45)
		(drill 0.1)
		(layers "F.Cu" "B.Cu")
		(remove_unused_layers yes)
		(keep_end_layers yes)
		(zone_layer_connections "In1.Cu" "In4.Cu" "In6.Cu")
		(teardrops
			(best_length_ratio 0.4)
			(max_length 1)
			(best_width_ratio 0.9)
			(max_width 2)
			(curved_edges yes)
			(filter_ratio 0.9)
			(enabled yes)
			(allow_two_segments yes)
			(prefer_zone_connections yes)
		)
		(net 1)
	)
	(via
		(at 95.45 92.81)
		(size 0.45)
		(drill 0.1)
		(layers "F.Cu" "B.Cu")
		(remove_unused_layers yes)
		(keep_end_layers yes)
		(zone_layer_connections "In1.Cu" "In4.Cu" "In6.Cu")
		(teardrops
			(best_length_ratio 0.4)
			(max_length 1)
			(best_width_ratio 0.9)
			(max_width 2)
			(curved_edges yes)
			(filter_ratio 0.9)
			(enabled yes)
			(allow_two_segments yes)
			(prefer_zone_connections yes)
		)
		(net 1)
	)
	(via
		(at 315.95 89.31)
		(size 0.45)
		(drill 0.1)
		(layers "F.Cu" "B.Cu")
		(remove_unused_layers yes)
		(keep_end_layers yes)
		(zone_layer_connections "In1.Cu" "In4.Cu" "In6.Cu")
		(teardrops
			(best_length_ratio 0.4)
			(max_length 1)
			(best_width_ratio 0.9)
			(max_width 2)
			(curved_edges yes)
			(filter_ratio 0.9)
			(enabled yes)
			(allow_two_segments yes)
			(prefer_zone_connections yes)
		)
		(net 1)
	)
	(via
		(at 187.525 167.45)
		(size 0.45)
		(drill 0.1)
		(layers "F.Cu" "B.Cu")
		(teardrops
			(best_length_ratio 0.4)
			(max_length 1)
			(best_width_ratio 0.9)
			(max_width 2)
			(curved_edges yes)
			(filter_ratio 0.9)
			(enabled yes)
			(allow_two_segments yes)
			(prefer_zone_connections yes)
		)
		(net 1)
	)
	(via
		(at 290.89 78.42)
		(size 0.45)
		(drill 0.1)
		(layers "F.Cu" "B.Cu")
		(remove_unused_layers yes)
		(keep_end_layers yes)
		(free yes)
		(zone_layer_connections "In1.Cu" "In4.Cu" "In6.Cu")
		(teardrops
			(best_length_ratio 0.4)
			(max_length 1)
			(best_width_ratio 0.9)
			(max_width 2)
			(curved_edges yes)
			(filter_ratio 0.9)
			(enabled yes)
			(allow_two_segments yes)
			(prefer_zone_connections yes)
		)
		(net 1)
	)
	(via
		(at 98.45 100.81)
		(size 0.45)
		(drill 0.1)
		(layers "F.Cu" "B.Cu")
		(remove_unused_layers yes)
		(keep_end_layers yes)
		(zone_layer_connections "In1.Cu" "In4.Cu" "In6.Cu")
		(teardrops
			(best_length_ratio 0.4)
			(max_length 1)
			(best_width_ratio 0.9)
			(max_width 2)
			(curved_edges yes)
			(filter_ratio 0.9)
			(enabled yes)
			(allow_two_segments yes)
			(prefer_zone_connections yes)
		)
		(net 1)
	)
	(via
		(at 235.95 89.31)
		(size 0.45)
		(drill 0.1)
		(layers "F.Cu" "B.Cu")
		(remove_unused_layers yes)
		(keep_end_layers yes)
		(zone_layer_connections "In1.Cu" "In4.Cu" "In6.Cu")
		(teardrops
			(best_length_ratio 0.4)
			(max_length 1)
			(best_width_ratio 0.9)
			(max_width 2)
			(curved_edges yes)
			(filter_ratio 0.9)
			(enabled yes)
			(allow_two_segments yes)
			(prefer_zone_connections yes)
		)
		(net 1)
	)
	(via
		(at 285.45 116.81)
		(size 0.45)
		(drill 0.1)
		(layers "F.Cu" "B.Cu")
		(remove_unused_layers yes)
		(keep_end_layers yes)
		(zone_layer_connections "In1.Cu" "In4.Cu" "In6.Cu")
		(teardrops
			(best_length_ratio 0.4)
			(max_length 1)
			(best_width_ratio 0.9)
			(max_width 2)
			(curved_edges yes)
			(filter_ratio 0.9)
			(enabled yes)
			(allow_two_segments yes)
			(prefer_zone_connections yes)
		)
		(net 1)
	)
	(via
		(at 245.95 117.31)
		(size 0.45)
		(drill 0.1)
		(layers "F.Cu" "B.Cu")
		(remove_unused_layers yes)
		(keep_end_layers yes)
		(free yes)
		(zone_layer_connections "In1.Cu" "In4.Cu" "In6.Cu")
		(teardrops
			(best_length_ratio 0.4)
			(max_length 1)
			(best_width_ratio 0.9)
			(max_width 2)
			(curved_edges yes)
			(filter_ratio 0.9)
			(enabled yes)
			(allow_two_segments yes)
			(prefer_zone_connections yes)
		)
		(net 1)
	)
	(via
		(at 174.7 94.85)
		(size 0.45)
		(drill 0.1)
		(layers "F.Cu" "B.Cu")
		(remove_unused_layers yes)
		(keep_end_layers yes)
		(zone_layer_connections "In1.Cu" "In4.Cu" "In6.Cu")
		(teardrops
			(best_length_ratio 0.4)
			(max_length 1)
			(best_width_ratio 0.9)
			(max_width 2)
			(curved_edges yes)
			(filter_ratio 0.9)
			(enabled yes)
			(allow_two_segments yes)
			(prefer_zone_connections yes)
		)
		(net 1)
	)
	(via
		(at 283.45 88.81)
		(size 0.45)
		(drill 0.1)
		(layers "F.Cu" "B.Cu")
		(remove_unused_layers yes)
		(keep_end_layers yes)
		(zone_layer_connections "In1.Cu" "In4.Cu" "In6.Cu")
		(teardrops
			(best_length_ratio 0.4)
			(max_length 1)
			(best_width_ratio 0.9)
			(max_width 2)
			(curved_edges yes)
			(filter_ratio 0.9)
			(enabled yes)
			(allow_two_segments yes)
			(prefer_zone_connections yes)
		)
		(net 1)
	)
	(via
		(at 119.75 97.5)
		(size 0.45)
		(drill 0.1)
		(layers "F.Cu" "B.Cu")
		(remove_unused_layers yes)
		(keep_end_layers yes)
		(zone_layer_connections "In1.Cu" "In4.Cu" "In6.Cu")
		(teardrops
			(best_length_ratio 0.4)
			(max_length 1)
			(best_width_ratio 0.9)
			(max_width 2)
			(curved_edges yes)
			(filter_ratio 0.9)
			(enabled yes)
			(allow_two_segments yes)
			(prefer_zone_connections yes)
		)
		(net 1)
	)
	(via
		(at 317.45 84.81)
		(size 0.45)
		(drill 0.1)
		(layers "F.Cu" "B.Cu")
		(remove_unused_layers yes)
		(keep_end_layers yes)
		(zone_layer_connections "In1.Cu" "In4.Cu" "In6.Cu")
		(teardrops
			(best_length_ratio 0.4)
			(max_length 1)
			(best_width_ratio 0.9)
			(max_width 2)
			(curved_edges yes)
			(filter_ratio 0.9)
			(enabled yes)
			(allow_two_segments yes)
			(prefer_zone_connections yes)
		)
		(net 1)
	)
	(via
		(at 209.275 171)
		(size 0.45)
		(drill 0.1)
		(layers "F.Cu" "B.Cu")
		(teardrops
			(best_length_ratio 0.4)
			(max_length 1)
			(best_width_ratio 0.9)
			(max_width 2)
			(curved_edges yes)
			(filter_ratio 0.9)
			(enabled yes)
			(allow_two_segments yes)
			(prefer_zone_connections yes)
		)
		(net 1)
	)
	(via
		(at 146.45 133.86)
		(size 0.45)
		(drill 0.1)
		(layers "F.Cu" "B.Cu")
		(remove_unused_layers yes)
		(keep_end_layers yes)
		(zone_layer_connections "In1.Cu" "In4.Cu" "In6.Cu")
		(teardrops
			(best_length_ratio 0.4)
			(max_length 1)
			(best_width_ratio 0.9)
			(max_width 2)
			(curved_edges yes)
			(filter_ratio 0.9)
			(enabled yes)
			(allow_two_segments yes)
			(prefer_zone_connections yes)
		)
		(net 1)
	)
	(via
		(at 136.29 145.81)
		(size 0.45)
		(drill 0.1)
		(layers "F.Cu" "B.Cu")
		(remove_unused_layers yes)
		(keep_end_layers yes)
		(zone_layer_connections "In1.Cu" "In4.Cu" "In6.Cu")
		(teardrops
			(best_length_ratio 0.4)
			(max_length 1)
			(best_width_ratio 0.9)
			(max_width 2)
			(curved_edges yes)
			(filter_ratio 0.9)
			(enabled yes)
			(allow_two_segments yes)
			(prefer_zone_connections yes)
		)
		(net 1)
	)
	(via
		(at 210.6 158.85)
		(size 0.45)
		(drill 0.1)
		(layers "F.Cu" "B.Cu")
		(remove_unused_layers yes)
		(keep_end_layers yes)
		(zone_layer_connections "In1.Cu" "In3.Cu" "In4.Cu" "In6.Cu")
		(teardrops
			(best_length_ratio 0.4)
			(max_length 1)
			(best_width_ratio 0.9)
			(max_width 2)
			(curved_edges yes)
			(filter_ratio 0.9)
			(enabled yes)
			(allow_two_segments yes)
			(prefer_zone_connections yes)
		)
		(net 1)
	)
	(via
		(at 256.95 170.81)
		(size 0.45)
		(drill 0.1)
		(layers "F.Cu" "B.Cu")
		(remove_unused_layers yes)
		(keep_end_layers yes)
		(zone_layer_connections "In1.Cu" "In4.Cu" "In6.Cu")
		(teardrops
			(best_length_ratio 0.4)
			(max_length 1)
			(best_width_ratio 0.9)
			(max_width 2)
			(curved_edges yes)
			(filter_ratio 0.9)
			(enabled yes)
			(allow_two_segments yes)
			(prefer_zone_connections yes)
		)
		(net 1)
	)
	(via
		(at 260.95 126.31)
		(size 0.45)
		(drill 0.1)
		(layers "F.Cu" "B.Cu")
		(remove_unused_layers yes)
		(keep_end_layers yes)
		(zone_layer_connections "In1.Cu" "In4.Cu" "In6.Cu")
		(teardrops
			(best_length_ratio 0.4)
			(max_length 1)
			(best_width_ratio 0.9)
			(max_width 2)
			(curved_edges yes)
			(filter_ratio 0.9)
			(enabled yes)
			(allow_two_segments yes)
			(prefer_zone_connections yes)
		)
		(net 1)
	)
	(via
		(at 282.45 125.31)
		(size 0.45)
		(drill 0.1)
		(layers "F.Cu" "B.Cu")
		(remove_unused_layers yes)
		(keep_end_layers yes)
		(zone_layer_connections "In1.Cu" "In4.Cu" "In6.Cu")
		(teardrops
			(best_length_ratio 0.4)
			(max_length 1)
			(best_width_ratio 0.9)
			(max_width 2)
			(curved_edges yes)
			(filter_ratio 0.9)
			(enabled yes)
			(allow_two_segments yes)
			(prefer_zone_connections yes)
		)
		(net 1)
	)
	(via
		(at 117.450001 170.81)
		(size 0.45)
		(drill 0.1)
		(layers "F.Cu" "B.Cu")
		(remove_unused_layers yes)
		(keep_end_layers yes)
		(zone_layer_connections "In1.Cu" "In4.Cu" "In6.Cu")
		(teardrops
			(best_length_ratio 0.4)
			(max_length 1)
			(best_width_ratio 0.9)
			(max_width 2)
			(curved_edges yes)
			(filter_ratio 0.9)
			(enabled yes)
			(allow_two_segments yes)
			(prefer_zone_connections yes)
		)
		(net 1)
	)
	(via
		(at 181 157.9)
		(size 0.45)
		(drill 0.1)
		(layers "F.Cu" "B.Cu")
		(teardrops
			(best_length_ratio 0.4)
			(max_length 1)
			(best_width_ratio 0.9)
			(max_width 2)
			(curved_edges yes)
			(filter_ratio 0.9)
			(enabled yes)
			(allow_two_segments yes)
			(prefer_zone_connections yes)
		)
		(net 1)
	)
	(via
		(at 95.45 159.31)
		(size 0.45)
		(drill 0.1)
		(layers "F.Cu" "B.Cu")
		(remove_unused_layers yes)
		(keep_end_layers yes)
		(zone_layer_connections "In1.Cu" "In4.Cu" "In6.Cu")
		(teardrops
			(best_length_ratio 0.4)
			(max_length 1)
			(best_width_ratio 0.9)
			(max_width 2)
			(curved_edges yes)
			(filter_ratio 0.9)
			(enabled yes)
			(allow_two_segments yes)
			(prefer_zone_connections yes)
		)
		(net 1)
	)
	(via
		(at 316.549999 140.759999)
		(size 0.45)
		(drill 0.1)
		(layers "F.Cu" "B.Cu")
		(remove_unused_layers yes)
		(keep_end_layers yes)
		(zone_layer_connections "In1.Cu" "In4.Cu" "In6.Cu")
		(teardrops
			(best_length_ratio 0.4)
			(max_length 1)
			(best_width_ratio 0.9)
			(max_width 2)
			(curved_edges yes)
			(filter_ratio 0.9)
			(enabled yes)
			(allow_two_segments yes)
			(prefer_zone_connections yes)
		)
		(net 1)
	)
	(via
		(at 99.95 91.81)
		(size 0.45)
		(drill 0.1)
		(layers "F.Cu" "B.Cu")
		(remove_unused_layers yes)
		(keep_end_layers yes)
		(zone_layer_connections "In1.Cu" "In4.Cu" "In6.Cu")
		(teardrops
			(best_length_ratio 0.4)
			(max_length 1)
			(best_width_ratio 0.9)
			(max_width 2)
			(curved_edges yes)
			(filter_ratio 0.9)
			(enabled yes)
			(allow_two_segments yes)
			(prefer_zone_connections yes)
		)
		(net 1)
	)
	(via
		(at 131.95 158.81)
		(size 0.45)
		(drill 0.1)
		(layers "F.Cu" "B.Cu")
		(remove_unused_layers yes)
		(keep_end_layers yes)
		(zone_layer_connections "In1.Cu" "In4.Cu" "In6.Cu")
		(teardrops
			(best_length_ratio 0.4)
			(max_length 1)
			(best_width_ratio 0.9)
			(max_width 2)
			(curved_edges yes)
			(filter_ratio 0.9)
			(enabled yes)
			(allow_two_segments yes)
			(prefer_zone_connections yes)
		)
		(net 1)
	)
	(via
		(at 128.29 141.86)
		(size 0.45)
		(drill 0.1)
		(layers "F.Cu" "B.Cu")
		(remove_unused_layers yes)
		(keep_end_layers yes)
		(zone_layer_connections "In1.Cu" "In4.Cu" "In6.Cu")
		(teardrops
			(best_length_ratio 0.4)
			(max_length 1)
			(best_width_ratio 0.9)
			(max_width 2)
			(curved_edges yes)
			(filter_ratio 0.9)
			(enabled yes)
			(allow_two_segments yes)
			(prefer_zone_connections yes)
		)
		(net 1)
	)
	(via
		(at 303.95 71.81)
		(size 0.45)
		(drill 0.1)
		(layers "F.Cu" "B.Cu")
		(remove_unused_layers yes)
		(keep_end_layers yes)
		(zone_layer_connections "In1.Cu" "In4.Cu" "In6.Cu")
		(teardrops
			(best_length_ratio 0.4)
			(max_length 1)
			(best_width_ratio 0.9)
			(max_width 2)
			(curved_edges yes)
			(filter_ratio 0.9)
			(enabled yes)
			(allow_two_segments yes)
			(prefer_zone_connections yes)
		)
		(net 1)
	)
	(via
		(at 289.95 108.31)
		(size 0.45)
		(drill 0.1)
		(layers "F.Cu" "B.Cu")
		(remove_unused_layers yes)
		(keep_end_layers yes)
		(zone_layer_connections "In1.Cu" "In4.Cu" "In6.Cu")
		(teardrops
			(best_length_ratio 0.4)
			(max_length 1)
			(best_width_ratio 0.9)
			(max_width 2)
			(curved_edges yes)
			(filter_ratio 0.9)
			(enabled yes)
			(allow_two_segments yes)
			(prefer_zone_connections yes)
		)
		(net 1)
	)
	(via
		(at 127.45 168.81)
		(size 0.45)
		(drill 0.1)
		(layers "F.Cu" "B.Cu")
		(remove_unused_layers yes)
		(keep_end_layers yes)
		(zone_layer_connections "In1.Cu" "In4.Cu" "In6.Cu")
		(teardrops
			(best_length_ratio 0.4)
			(max_length 1)
			(best_width_ratio 0.9)
			(max_width 2)
			(curved_edges yes)
			(filter_ratio 0.9)
			(enabled yes)
			(allow_two_segments yes)
			(prefer_zone_connections yes)
		)
		(net 1)
	)
	(via
		(at 260.24 137.5)
		(size 0.45)
		(drill 0.1)
		(layers "F.Cu" "B.Cu")
		(remove_unused_layers yes)
		(keep_end_layers yes)
		(zone_layer_connections "In1.Cu" "In4.Cu" "In6.Cu")
		(teardrops
			(best_length_ratio 0.4)
			(max_length 1)
			(best_width_ratio 0.9)
			(max_width 2)
			(curved_edges yes)
			(filter_ratio 0.9)
			(enabled yes)
			(allow_two_segments yes)
			(prefer_zone_connections yes)
		)
		(net 1)
	)
	(via
		(at 128.66233 108.006081)
		(size 0.45)
		(drill 0.1)
		(layers "F.Cu" "B.Cu")
		(remove_unused_layers yes)
		(keep_end_layers yes)
		(zone_layer_connections "In1.Cu" "In4.Cu" "In6.Cu")
		(teardrops
			(best_length_ratio 0.4)
			(max_length 1)
			(best_width_ratio 0.9)
			(max_width 2)
			(curved_edges yes)
			(filter_ratio 0.9)
			(enabled yes)
			(allow_two_segments yes)
			(prefer_zone_connections yes)
		)
		(net 1)
	)
	(via
		(at 317.55 139.759999)
		(size 0.45)
		(drill 0.1)
		(layers "F.Cu" "B.Cu")
		(remove_unused_layers yes)
		(keep_end_layers yes)
		(zone_layer_connections "In1.Cu" "In4.Cu" "In6.Cu")
		(teardrops
			(best_length_ratio 0.4)
			(max_length 1)
			(best_width_ratio 0.9)
			(max_width 2)
			(curved_edges yes)
			(filter_ratio 0.9)
			(enabled yes)
			(allow_two_segments yes)
			(prefer_zone_connections yes)
		)
		(net 1)
	)
	(via
		(at 284.95 147.31)
		(size 0.45)
		(drill 0.1)
		(layers "F.Cu" "B.Cu")
		(remove_unused_layers yes)
		(keep_end_layers yes)
		(zone_layer_connections "In1.Cu" "In4.Cu" "In6.Cu")
		(teardrops
			(best_length_ratio 0.4)
			(max_length 1)
			(best_width_ratio 0.9)
			(max_width 2)
			(curved_edges yes)
			(filter_ratio 0.9)
			(enabled yes)
			(allow_two_segments yes)
			(prefer_zone_connections yes)
		)
		(net 1)
	)
	(via
		(at 168.45 68.81)
		(size 0.45)
		(drill 0.1)
		(layers "F.Cu" "B.Cu")
		(remove_unused_layers yes)
		(keep_end_layers yes)
		(zone_layer_connections "In1.Cu" "In4.Cu" "In6.Cu")
		(teardrops
			(best_length_ratio 0.4)
			(max_length 1)
			(best_width_ratio 0.9)
			(max_width 2)
			(curved_edges yes)
			(filter_ratio 0.9)
			(enabled yes)
			(allow_two_segments yes)
			(prefer_zone_connections yes)
		)
		(net 1)
	)
	(via
		(at 283.95 112.31)
		(size 0.45)
		(drill 0.1)
		(layers "F.Cu" "B.Cu")
		(remove_unused_layers yes)
		(keep_end_layers yes)
		(zone_layer_connections "In1.Cu" "In4.Cu" "In6.Cu")
		(teardrops
			(best_length_ratio 0.4)
			(max_length 1)
			(best_width_ratio 0.9)
			(max_width 2)
			(curved_edges yes)
			(filter_ratio 0.9)
			(enabled yes)
			(allow_two_segments yes)
			(prefer_zone_connections yes)
		)
		(net 1)
	)
	(via
		(at 120.5 74.09)
		(size 0.45)
		(drill 0.1)
		(layers "F.Cu" "B.Cu")
		(remove_unused_layers yes)
		(keep_end_layers yes)
		(zone_layer_connections "In1.Cu" "In4.Cu" "In6.Cu")
		(teardrops
			(best_length_ratio 0.4)
			(max_length 1)
			(best_width_ratio 0.9)
			(max_width 2)
			(curved_edges yes)
			(filter_ratio 0.9)
			(enabled yes)
			(allow_two_segments yes)
			(prefer_zone_connections yes)
		)
		(net 1)
	)
	(via
		(at 98.359414 103.423776)
		(size 0.45)
		(drill 0.1)
		(layers "F.Cu" "B.Cu")
		(remove_unused_layers yes)
		(keep_end_layers yes)
		(zone_layer_connections "In1.Cu" "In4.Cu" "In6.Cu")
		(teardrops
			(best_length_ratio 0.4)
			(max_length 1)
			(best_width_ratio 0.9)
			(max_width 2)
			(curved_edges yes)
			(filter_ratio 0.9)
			(enabled yes)
			(allow_two_segments yes)
			(prefer_zone_connections yes)
		)
		(net 1)
	)
	(via
		(at 99.95 101.81)
		(size 0.45)
		(drill 0.1)
		(layers "F.Cu" "B.Cu")
		(remove_unused_layers yes)
		(keep_end_layers yes)
		(zone_layer_connections "In1.Cu" "In4.Cu" "In6.Cu")
		(teardrops
			(best_length_ratio 0.4)
			(max_length 1)
			(best_width_ratio 0.9)
			(max_width 2)
			(curved_edges yes)
			(filter_ratio 0.9)
			(enabled yes)
			(allow_two_segments yes)
			(prefer_zone_connections yes)
		)
		(net 1)
	)
	(via
		(at 242.95 123.31)
		(size 0.45)
		(drill 0.1)
		(layers "F.Cu" "B.Cu")
		(remove_unused_layers yes)
		(keep_end_layers yes)
		(zone_layer_connections "In1.Cu" "In4.Cu" "In6.Cu")
		(teardrops
			(best_length_ratio 0.4)
			(max_length 1)
			(best_width_ratio 0.9)
			(max_width 2)
			(curved_edges yes)
			(filter_ratio 0.9)
			(enabled yes)
			(allow_two_segments yes)
			(prefer_zone_connections yes)
		)
		(net 1)
	)
	(via
		(at 289.45 145.81)
		(size 0.45)
		(drill 0.1)
		(layers "F.Cu" "B.Cu")
		(remove_unused_layers yes)
		(keep_end_layers yes)
		(zone_layer_connections "In1.Cu" "In4.Cu" "In6.Cu")
		(teardrops
			(best_length_ratio 0.4)
			(max_length 1)
			(best_width_ratio 0.9)
			(max_width 2)
			(curved_edges yes)
			(filter_ratio 0.9)
			(enabled yes)
			(allow_two_segments yes)
			(prefer_zone_connections yes)
		)
		(net 1)
	)
	(via
		(at 144.45 156.31)
		(size 0.45)
		(drill 0.1)
		(layers "F.Cu" "B.Cu")
		(remove_unused_layers yes)
		(keep_end_layers yes)
		(zone_layer_connections "In1.Cu" "In4.Cu" "In6.Cu")
		(teardrops
			(best_length_ratio 0.4)
			(max_length 1)
			(best_width_ratio 0.9)
			(max_width 2)
			(curved_edges yes)
			(filter_ratio 0.9)
			(enabled yes)
			(allow_two_segments yes)
			(prefer_zone_connections yes)
		)
		(net 1)
	)
	(via
		(at 191 169.899)
		(size 0.45)
		(drill 0.1)
		(layers "F.Cu" "B.Cu")
		(teardrops
			(best_length_ratio 0.4)
			(max_length 1)
			(best_width_ratio 0.9)
			(max_width 2)
			(curved_edges yes)
			(filter_ratio 0.9)
			(enabled yes)
			(allow_two_segments yes)
			(prefer_zone_connections yes)
		)
		(net 1)
	)
	(via
		(at 101.45 92.81)
		(size 0.45)
		(drill 0.1)
		(layers "F.Cu" "B.Cu")
		(remove_unused_layers yes)
		(keep_end_layers yes)
		(zone_layer_connections "In1.Cu" "In4.Cu" "In6.Cu")
		(teardrops
			(best_length_ratio 0.4)
			(max_length 1)
			(best_width_ratio 0.9)
			(max_width 2)
			(curved_edges yes)
			(filter_ratio 0.9)
			(enabled yes)
			(allow_two_segments yes)
			(prefer_zone_connections yes)
		)
		(net 1)
	)
	(via
		(at 191 157.9)
		(size 0.45)
		(drill 0.1)
		(layers "F.Cu" "B.Cu")
		(teardrops
			(best_length_ratio 0.4)
			(max_length 1)
			(best_width_ratio 0.9)
			(max_width 2)
			(curved_edges yes)
			(filter_ratio 0.9)
			(enabled yes)
			(allow_two_segments yes)
			(prefer_zone_connections yes)
		)
		(net 1)
	)
	(via
		(at 155.45 133.86)
		(size 0.45)
		(drill 0.1)
		(layers "F.Cu" "B.Cu")
		(remove_unused_layers yes)
		(keep_end_layers yes)
		(zone_layer_connections "In1.Cu" "In4.Cu" "In6.Cu")
		(teardrops
			(best_length_ratio 0.4)
			(max_length 1)
			(best_width_ratio 0.9)
			(max_width 2)
			(curved_edges yes)
			(filter_ratio 0.9)
			(enabled yes)
			(allow_two_segments yes)
			(prefer_zone_connections yes)
		)
		(net 1)
	)
	(via
		(at 118.15 147.901)
		(size 0.45)
		(drill 0.1)
		(layers "F.Cu" "B.Cu")
		(remove_unused_layers yes)
		(keep_end_layers yes)
		(zone_layer_connections "In1.Cu" "In4.Cu" "In6.Cu")
		(teardrops
			(best_length_ratio 0.4)
			(max_length 1)
			(best_width_ratio 0.9)
			(max_width 2)
			(curved_edges yes)
			(filter_ratio 0.9)
			(enabled yes)
			(allow_two_segments yes)
			(prefer_zone_connections yes)
		)
		(net 1)
	)
	(via
		(at 151.6 115.8)
		(size 0.45)
		(drill 0.1)
		(layers "F.Cu" "B.Cu")
		(remove_unused_layers yes)
		(keep_end_layers yes)
		(zone_layer_connections "In1.Cu" "In4.Cu" "In6.Cu")
		(teardrops
			(best_length_ratio 0.4)
			(max_length 1)
			(best_width_ratio 0.9)
			(max_width 2)
			(curved_edges yes)
			(filter_ratio 0.9)
			(enabled yes)
			(allow_two_segments yes)
			(prefer_zone_connections yes)
		)
		(net 1)
	)
	(via
		(at 222.45 84.81)
		(size 0.45)
		(drill 0.1)
		(layers "F.Cu" "B.Cu")
		(remove_unused_layers yes)
		(keep_end_layers yes)
		(free yes)
		(zone_layer_connections "In1.Cu" "In4.Cu" "In6.Cu")
		(teardrops
			(best_length_ratio 0.4)
			(max_length 1)
			(best_width_ratio 0.9)
			(max_width 2)
			(curved_edges yes)
			(filter_ratio 0.9)
			(enabled yes)
			(allow_two_segments yes)
			(prefer_zone_connections yes)
		)
		(net 1)
	)
	(via
		(at 182.55 149.975)
		(size 0.45)
		(drill 0.1)
		(layers "F.Cu" "B.Cu")
		(teardrops
			(best_length_ratio 0.4)
			(max_length 1)
			(best_width_ratio 0.9)
			(max_width 2)
			(curved_edges yes)
			(filter_ratio 0.9)
			(enabled yes)
			(allow_two_segments yes)
			(prefer_zone_connections yes)
		)
		(net 1)
	)
	(via
		(at 221.425 170.075)
		(size 0.45)
		(drill 0.1)
		(layers "F.Cu" "B.Cu")
		(teardrops
			(best_length_ratio 0.4)
			(max_length 1)
			(best_width_ratio 0.9)
			(max_width 2)
			(curved_edges yes)
			(filter_ratio 0.9)
			(enabled yes)
			(allow_two_segments yes)
			(prefer_zone_connections yes)
		)
		(net 1)
	)
	(via
		(at 137.45 85.31)
		(size 0.45)
		(drill 0.1)
		(layers "F.Cu" "B.Cu")
		(remove_unused_layers yes)
		(keep_end_layers yes)
		(zone_layer_connections "In1.Cu" "In4.Cu" "In6.Cu")
		(teardrops
			(best_length_ratio 0.4)
			(max_length 1)
			(best_width_ratio 0.9)
			(max_width 2)
			(curved_edges yes)
			(filter_ratio 0.9)
			(enabled yes)
			(allow_two_segments yes)
			(prefer_zone_connections yes)
		)
		(net 1)
	)
	(via
		(at 262.45 111.31)
		(size 0.45)
		(drill 0.1)
		(layers "F.Cu" "B.Cu")
		(remove_unused_layers yes)
		(keep_end_layers yes)
		(zone_layer_connections "In1.Cu" "In4.Cu" "In6.Cu")
		(teardrops
			(best_length_ratio 0.4)
			(max_length 1)
			(best_width_ratio 0.9)
			(max_width 2)
			(curved_edges yes)
			(filter_ratio 0.9)
			(enabled yes)
			(allow_two_segments yes)
			(prefer_zone_connections yes)
		)
		(net 1)
	)
	(via
		(at 127.29 135.86)
		(size 0.45)
		(drill 0.1)
		(layers "F.Cu" "B.Cu")
		(remove_unused_layers yes)
		(keep_end_layers yes)
		(zone_layer_connections "In1.Cu" "In4.Cu" "In6.Cu")
		(teardrops
			(best_length_ratio 0.4)
			(max_length 1)
			(best_width_ratio 0.9)
			(max_width 2)
			(curved_edges yes)
			(filter_ratio 0.9)
			(enabled yes)
			(allow_two_segments yes)
			(prefer_zone_connections yes)
		)
		(net 1)
	)
	(via
		(at 112.45 79.31)
		(size 0.45)
		(drill 0.1)
		(layers "F.Cu" "B.Cu")
		(remove_unused_layers yes)
		(keep_end_layers yes)
		(zone_layer_connections "In1.Cu" "In4.Cu" "In6.Cu")
		(teardrops
			(best_length_ratio 0.4)
			(max_length 1)
			(best_width_ratio 0.9)
			(max_width 2)
			(curved_edges yes)
			(filter_ratio 0.9)
			(enabled yes)
			(allow_two_segments yes)
			(prefer_zone_connections yes)
		)
		(net 1)
	)
	(via
		(at 201.05 152.2)
		(size 0.45)
		(drill 0.1)
		(layers "F.Cu" "B.Cu")
		(teardrops
			(best_length_ratio 0.4)
			(max_length 1)
			(best_width_ratio 0.9)
			(max_width 2)
			(curved_edges yes)
			(filter_ratio 0.9)
			(enabled yes)
			(allow_two_segments yes)
			(prefer_zone_connections yes)
		)
		(net 1)
	)
	(via
		(at 159.95 89.31)
		(size 0.45)
		(drill 0.1)
		(layers "F.Cu" "B.Cu")
		(remove_unused_layers yes)
		(keep_end_layers yes)
		(free yes)
		(zone_layer_connections "In1.Cu" "In4.Cu" "In6.Cu")
		(teardrops
			(best_length_ratio 0.4)
			(max_length 1)
			(best_width_ratio 0.9)
			(max_width 2)
			(curved_edges yes)
			(filter_ratio 0.9)
			(enabled yes)
			(allow_two_segments yes)
			(prefer_zone_connections yes)
		)
		(net 1)
	)
	(via
		(at 128.45 160.81)
		(size 0.45)
		(drill 0.1)
		(layers "F.Cu" "B.Cu")
		(remove_unused_layers yes)
		(keep_end_layers yes)
		(zone_layer_connections "In1.Cu" "In4.Cu" "In6.Cu")
		(teardrops
			(best_length_ratio 0.4)
			(max_length 1)
			(best_width_ratio 0.9)
			(max_width 2)
			(curved_edges yes)
			(filter_ratio 0.9)
			(enabled yes)
			(allow_two_segments yes)
			(prefer_zone_connections yes)
		)
		(net 1)
	)
	(via
		(at 142.45 80.81)
		(size 0.45)
		(drill 0.1)
		(layers "F.Cu" "B.Cu")
		(remove_unused_layers yes)
		(keep_end_layers yes)
		(zone_layer_connections "In1.Cu" "In4.Cu" "In6.Cu")
		(teardrops
			(best_length_ratio 0.4)
			(max_length 1)
			(best_width_ratio 0.9)
			(max_width 2)
			(curved_edges yes)
			(filter_ratio 0.9)
			(enabled yes)
			(allow_two_segments yes)
			(prefer_zone_connections yes)
		)
		(net 1)
	)
	(via
		(at 241.2 160.8)
		(size 0.45)
		(drill 0.1)
		(layers "F.Cu" "B.Cu")
		(teardrops
			(best_length_ratio 0.4)
			(max_length 1)
			(best_width_ratio 0.9)
			(max_width 2)
			(curved_edges yes)
			(filter_ratio 0.9)
			(enabled yes)
			(allow_two_segments yes)
			(prefer_zone_connections yes)
		)
		(net 1)
	)
	(via
		(at 162.45 68.81)
		(size 0.45)
		(drill 0.1)
		(layers "F.Cu" "B.Cu")
		(remove_unused_layers yes)
		(keep_end_layers yes)
		(zone_layer_connections "In1.Cu" "In4.Cu" "In6.Cu")
		(teardrops
			(best_length_ratio 0.4)
			(max_length 1)
			(best_width_ratio 0.9)
			(max_width 2)
			(curved_edges yes)
			(filter_ratio 0.9)
			(enabled yes)
			(allow_two_segments yes)
			(prefer_zone_connections yes)
		)
		(net 1)
	)
	(via
		(at 131.45 165.81)
		(size 0.45)
		(drill 0.1)
		(layers "F.Cu" "B.Cu")
		(remove_unused_layers yes)
		(keep_end_layers yes)
		(zone_layer_connections "In1.Cu" "In4.Cu" "In6.Cu")
		(teardrops
			(best_length_ratio 0.4)
			(max_length 1)
			(best_width_ratio 0.9)
			(max_width 2)
			(curved_edges yes)
			(filter_ratio 0.9)
			(enabled yes)
			(allow_two_segments yes)
			(prefer_zone_connections yes)
		)
		(net 1)
	)
	(via
		(at 97.5 152.1)
		(size 0.45)
		(drill 0.1)
		(layers "F.Cu" "B.Cu")
		(teardrops
			(best_length_ratio 0.4)
			(max_length 1)
			(best_width_ratio 0.9)
			(max_width 2)
			(curved_edges yes)
			(filter_ratio 0.9)
			(enabled yes)
			(allow_two_segments yes)
			(prefer_zone_connections yes)
		)
		(net 1)
	)
	(via
		(at 100.1 148.6)
		(size 0.45)
		(drill 0.1)
		(layers "F.Cu" "B.Cu")
		(remove_unused_layers yes)
		(keep_end_layers yes)
		(zone_layer_connections "In1.Cu" "In4.Cu" "In6.Cu")
		(teardrops
			(best_length_ratio 0.4)
			(max_length 1)
			(best_width_ratio 0.9)
			(max_width 2)
			(curved_edges yes)
			(filter_ratio 0.9)
			(enabled yes)
			(allow_two_segments yes)
			(prefer_zone_connections yes)
		)
		(net 1)
	)
	(via
		(at 318.4895 135.71)
		(size 0.45)
		(drill 0.1)
		(layers "F.Cu" "B.Cu")
		(remove_unused_layers yes)
		(keep_end_layers yes)
		(zone_layer_connections "In1.Cu" "In4.Cu" "In6.Cu")
		(teardrops
			(best_length_ratio 0.4)
			(max_length 1)
			(best_width_ratio 0.9)
			(max_width 2)
			(curved_edges yes)
			(filter_ratio 0.9)
			(enabled yes)
			(allow_two_segments yes)
			(prefer_zone_connections yes)
		)
		(net 1)
	)
	(via
		(at 173.255 105.375)
		(size 0.45)
		(drill 0.1)
		(layers "F.Cu" "B.Cu")
		(remove_unused_layers yes)
		(keep_end_layers yes)
		(zone_layer_connections "In1.Cu" "In4.Cu" "In6.Cu")
		(teardrops
			(best_length_ratio 0.4)
			(max_length 1)
			(best_width_ratio 0.9)
			(max_width 2)
			(curved_edges yes)
			(filter_ratio 0.9)
			(enabled yes)
			(allow_two_segments yes)
			(prefer_zone_connections yes)
		)
		(net 1)
	)
	(via
		(at 127.305 144.775)
		(size 0.45)
		(drill 0.1)
		(layers "F.Cu" "B.Cu")
		(remove_unused_layers yes)
		(keep_end_layers yes)
		(zone_layer_connections "In1.Cu" "In4.Cu" "In6.Cu")
		(teardrops
			(best_length_ratio 0.4)
			(max_length 1)
			(best_width_ratio 0.9)
			(max_width 2)
			(curved_edges yes)
			(filter_ratio 0.9)
			(enabled yes)
			(allow_two_segments yes)
			(prefer_zone_connections yes)
		)
		(net 1)
	)
	(via
		(at 95.45 78.81)
		(size 0.45)
		(drill 0.1)
		(layers "F.Cu" "B.Cu")
		(remove_unused_layers yes)
		(keep_end_layers yes)
		(zone_layer_connections "In1.Cu" "In4.Cu" "In6.Cu")
		(teardrops
			(best_length_ratio 0.4)
			(max_length 1)
			(best_width_ratio 0.9)
			(max_width 2)
			(curved_edges yes)
			(filter_ratio 0.9)
			(enabled yes)
			(allow_two_segments yes)
			(prefer_zone_connections yes)
		)
		(net 1)
	)
	(via
		(at 205.45 141.85)
		(size 0.45)
		(drill 0.1)
		(layers "F.Cu" "B.Cu")
		(remove_unused_layers yes)
		(keep_end_layers yes)
		(zone_layer_connections "In1.Cu" "In4.Cu" "In6.Cu")
		(teardrops
			(best_length_ratio 0.4)
			(max_length 1)
			(best_width_ratio 0.9)
			(max_width 2)
			(curved_edges yes)
			(filter_ratio 0.9)
			(enabled yes)
			(allow_two_segments yes)
			(prefer_zone_connections yes)
		)
		(net 1)
	)
	(via
		(at 135.54 104.25)
		(size 0.45)
		(drill 0.1)
		(layers "F.Cu" "B.Cu")
		(remove_unused_layers yes)
		(keep_end_layers yes)
		(zone_layer_connections "In1.Cu" "In4.Cu" "In6.Cu")
		(teardrops
			(best_length_ratio 0.4)
			(max_length 1)
			(best_width_ratio 0.9)
			(max_width 2)
			(curved_edges yes)
			(filter_ratio 0.9)
			(enabled yes)
			(allow_two_segments yes)
			(prefer_zone_connections yes)
		)
		(net 1)
	)
	(via
		(at 297.95 117.31)
		(size 0.45)
		(drill 0.1)
		(layers "F.Cu" "B.Cu")
		(remove_unused_layers yes)
		(keep_end_layers yes)
		(zone_layer_connections "In1.Cu" "In4.Cu" "In6.Cu")
		(teardrops
			(best_length_ratio 0.4)
			(max_length 1)
			(best_width_ratio 0.9)
			(max_width 2)
			(curved_edges yes)
			(filter_ratio 0.9)
			(enabled yes)
			(allow_two_segments yes)
			(prefer_zone_connections yes)
		)
		(net 1)
	)
	(via
		(at 196.65 164.8)
		(size 0.45)
		(drill 0.1)
		(layers "F.Cu" "B.Cu")
		(teardrops
			(best_length_ratio 0.4)
			(max_length 1)
			(best_width_ratio 0.9)
			(max_width 2)
			(curved_edges yes)
			(filter_ratio 0.9)
			(enabled yes)
			(allow_two_segments yes)
			(prefer_zone_connections yes)
		)
		(net 1)
	)
	(via
		(at 130.29 143.86)
		(size 0.45)
		(drill 0.1)
		(layers "F.Cu" "B.Cu")
		(remove_unused_layers yes)
		(keep_end_layers yes)
		(zone_layer_connections "In1.Cu" "In4.Cu" "In6.Cu")
		(teardrops
			(best_length_ratio 0.4)
			(max_length 1)
			(best_width_ratio 0.9)
			(max_width 2)
			(curved_edges yes)
			(filter_ratio 0.9)
			(enabled yes)
			(allow_two_segments yes)
			(prefer_zone_connections yes)
		)
		(net 1)
	)
	(via
		(at 142.45 88.31)
		(size 0.45)
		(drill 0.1)
		(layers "F.Cu" "B.Cu")
		(remove_unused_layers yes)
		(keep_end_layers yes)
		(zone_layer_connections "In1.Cu" "In4.Cu" "In6.Cu")
		(teardrops
			(best_length_ratio 0.4)
			(max_length 1)
			(best_width_ratio 0.9)
			(max_width 2)
			(curved_edges yes)
			(filter_ratio 0.9)
			(enabled yes)
			(allow_two_segments yes)
			(prefer_zone_connections yes)
		)
		(net 1)
	)
	(via
		(at 298.95 91.81)
		(size 0.45)
		(drill 0.1)
		(layers "F.Cu" "B.Cu")
		(remove_unused_layers yes)
		(keep_end_layers yes)
		(zone_layer_connections "In1.Cu" "In4.Cu" "In6.Cu")
		(teardrops
			(best_length_ratio 0.4)
			(max_length 1)
			(best_width_ratio 0.9)
			(max_width 2)
			(curved_edges yes)
			(filter_ratio 0.9)
			(enabled yes)
			(allow_two_segments yes)
			(prefer_zone_connections yes)
		)
		(net 1)
	)
	(via
		(at 218.43 133.58)
		(size 0.45)
		(drill 0.1)
		(layers "F.Cu" "B.Cu")
		(remove_unused_layers yes)
		(keep_end_layers yes)
		(zone_layer_connections "In1.Cu" "In4.Cu" "In6.Cu")
		(teardrops
			(best_length_ratio 0.4)
			(max_length 1)
			(best_width_ratio 0.9)
			(max_width 2)
			(curved_edges yes)
			(filter_ratio 0.9)
			(enabled yes)
			(allow_two_segments yes)
			(prefer_zone_connections yes)
		)
		(net 1)
	)
	(via
		(at 297.45 130.31)
		(size 0.45)
		(drill 0.1)
		(layers "F.Cu" "B.Cu")
		(remove_unused_layers yes)
		(keep_end_layers yes)
		(zone_layer_connections "In1.Cu" "In4.Cu" "In6.Cu")
		(teardrops
			(best_length_ratio 0.4)
			(max_length 1)
			(best_width_ratio 0.9)
			(max_width 2)
			(curved_edges yes)
			(filter_ratio 0.9)
			(enabled yes)
			(allow_two_segments yes)
			(prefer_zone_connections yes)
		)
		(net 1)
	)
	(via
		(at 266.449 93.51)
		(size 0.45)
		(drill 0.1)
		(layers "F.Cu" "B.Cu")
		(remove_unused_layers yes)
		(keep_end_layers yes)
		(zone_layer_connections "In1.Cu" "In4.Cu" "In6.Cu")
		(teardrops
			(best_length_ratio 0.4)
			(max_length 1)
			(best_width_ratio 0.9)
			(max_width 2)
			(curved_edges yes)
			(filter_ratio 0.9)
			(enabled yes)
			(allow_two_segments yes)
			(prefer_zone_connections yes)
		)
		(net 1)
	)
	(via
		(at 129.29 136.86)
		(size 0.45)
		(drill 0.1)
		(layers "F.Cu" "B.Cu")
		(remove_unused_layers yes)
		(keep_end_layers yes)
		(zone_layer_connections "In1.Cu" "In4.Cu" "In6.Cu")
		(teardrops
			(best_length_ratio 0.4)
			(max_length 1)
			(best_width_ratio 0.9)
			(max_width 2)
			(curved_edges yes)
			(filter_ratio 0.9)
			(enabled yes)
			(allow_two_segments yes)
			(prefer_zone_connections yes)
		)
		(net 1)
	)
	(via
		(at 125.45 161.81)
		(size 0.45)
		(drill 0.1)
		(layers "F.Cu" "B.Cu")
		(remove_unused_layers yes)
		(keep_end_layers yes)
		(zone_layer_connections "In1.Cu" "In4.Cu" "In6.Cu")
		(teardrops
			(best_length_ratio 0.4)
			(max_length 1)
			(best_width_ratio 0.9)
			(max_width 2)
			(curved_edges yes)
			(filter_ratio 0.9)
			(enabled yes)
			(allow_two_segments yes)
			(prefer_zone_connections yes)
		)
		(net 1)
	)
	(via
		(at 147.55 170.31)
		(size 0.45)
		(drill 0.1)
		(layers "F.Cu" "B.Cu")
		(remove_unused_layers yes)
		(keep_end_layers yes)
		(zone_layer_connections "In1.Cu" "In4.Cu" "In6.Cu")
		(teardrops
			(best_length_ratio 0.4)
			(max_length 1)
			(best_width_ratio 0.9)
			(max_width 2)
			(curved_edges yes)
			(filter_ratio 0.9)
			(enabled yes)
			(allow_two_segments yes)
			(prefer_zone_connections yes)
		)
		(net 1)
	)
	(via
		(at 284.45 82.31)
		(size 0.45)
		(drill 0.1)
		(layers "F.Cu" "B.Cu")
		(remove_unused_layers yes)
		(keep_end_layers yes)
		(zone_layer_connections "In1.Cu" "In4.Cu" "In6.Cu")
		(teardrops
			(best_length_ratio 0.4)
			(max_length 1)
			(best_width_ratio 0.9)
			(max_width 2)
			(curved_edges yes)
			(filter_ratio 0.9)
			(enabled yes)
			(allow_two_segments yes)
			(prefer_zone_connections yes)
		)
		(net 1)
	)
	(via
		(at 195.95 101.81)
		(size 0.45)
		(drill 0.1)
		(layers "F.Cu" "B.Cu")
		(remove_unused_layers yes)
		(keep_end_layers yes)
		(zone_layer_connections "In1.Cu" "In4.Cu" "In6.Cu")
		(teardrops
			(best_length_ratio 0.4)
			(max_length 1)
			(best_width_ratio 0.9)
			(max_width 2)
			(curved_edges yes)
			(filter_ratio 0.9)
			(enabled yes)
			(allow_two_segments yes)
			(prefer_zone_connections yes)
		)
		(net 1)
	)
	(via
		(at 174.45 92.31)
		(size 0.45)
		(drill 0.1)
		(layers "F.Cu" "B.Cu")
		(remove_unused_layers yes)
		(keep_end_layers yes)
		(zone_layer_connections "In1.Cu" "In4.Cu" "In6.Cu")
		(teardrops
			(best_length_ratio 0.4)
			(max_length 1)
			(best_width_ratio 0.9)
			(max_width 2)
			(curved_edges yes)
			(filter_ratio 0.9)
			(enabled yes)
			(allow_two_segments yes)
			(prefer_zone_connections yes)
		)
		(net 1)
	)
	(via
		(at 250.95 90.81)
		(size 0.45)
		(drill 0.1)
		(layers "F.Cu" "B.Cu")
		(remove_unused_layers yes)
		(keep_end_layers yes)
		(zone_layer_connections "In1.Cu" "In4.Cu" "In6.Cu")
		(teardrops
			(best_length_ratio 0.4)
			(max_length 1)
			(best_width_ratio 0.9)
			(max_width 2)
			(curved_edges yes)
			(filter_ratio 0.9)
			(enabled yes)
			(allow_two_segments yes)
			(prefer_zone_connections yes)
		)
		(net 1)
	)
	(via
		(at 115.45 165.81)
		(size 0.45)
		(drill 0.1)
		(layers "F.Cu" "B.Cu")
		(remove_unused_layers yes)
		(keep_end_layers yes)
		(zone_layer_connections "In1.Cu" "In4.Cu" "In6.Cu")
		(teardrops
			(best_length_ratio 0.4)
			(max_length 1)
			(best_width_ratio 0.9)
			(max_width 2)
			(curved_edges yes)
			(filter_ratio 0.9)
			(enabled yes)
			(allow_two_segments yes)
			(prefer_zone_connections yes)
		)
		(net 1)
	)
	(via
		(at 98.45 133.81)
		(size 0.45)
		(drill 0.1)
		(layers "F.Cu" "B.Cu")
		(remove_unused_layers yes)
		(keep_end_layers yes)
		(zone_layer_connections "In1.Cu" "In4.Cu" "In6.Cu")
		(teardrops
			(best_length_ratio 0.4)
			(max_length 1)
			(best_width_ratio 0.9)
			(max_width 2)
			(curved_edges yes)
			(filter_ratio 0.9)
			(enabled yes)
			(allow_two_segments yes)
			(prefer_zone_connections yes)
		)
		(net 1)
	)
	(via
		(at 103.19 161.11)
		(size 0.45)
		(drill 0.1)
		(layers "F.Cu" "B.Cu")
		(remove_unused_layers yes)
		(keep_end_layers yes)
		(zone_layer_connections "In1.Cu" "In4.Cu" "In6.Cu")
		(teardrops
			(best_length_ratio 0.4)
			(max_length 1)
			(best_width_ratio 0.9)
			(max_width 2)
			(curved_edges yes)
			(filter_ratio 0.9)
			(enabled yes)
			(allow_two_segments yes)
			(prefer_zone_connections yes)
		)
		(net 1)
	)
	(via
		(at 203.8 141.85)
		(size 0.45)
		(drill 0.1)
		(layers "F.Cu" "B.Cu")
		(remove_unused_layers yes)
		(keep_end_layers yes)
		(zone_layer_connections "In1.Cu" "In4.Cu" "In6.Cu")
		(teardrops
			(best_length_ratio 0.4)
			(max_length 1)
			(best_width_ratio 0.9)
			(max_width 2)
			(curved_edges yes)
			(filter_ratio 0.9)
			(enabled yes)
			(allow_two_segments yes)
			(prefer_zone_connections yes)
		)
		(net 1)
	)
	(via
		(at 99.77 96.56)
		(size 0.45)
		(drill 0.1)
		(layers "F.Cu" "B.Cu")
		(remove_unused_layers yes)
		(keep_end_layers yes)
		(zone_layer_connections "In1.Cu" "In4.Cu" "In6.Cu")
		(teardrops
			(best_length_ratio 0.4)
			(max_length 1)
			(best_width_ratio 0.9)
			(max_width 2)
			(curved_edges yes)
			(filter_ratio 0.9)
			(enabled yes)
			(allow_two_segments yes)
			(prefer_zone_connections yes)
		)
		(net 1)
	)
	(via
		(at 129.72 147.63)
		(size 0.45)
		(drill 0.1)
		(layers "F.Cu" "B.Cu")
		(remove_unused_layers yes)
		(keep_end_layers yes)
		(zone_layer_connections "In1.Cu" "In4.Cu" "In6.Cu")
		(teardrops
			(best_length_ratio 0.4)
			(max_length 1)
			(best_width_ratio 0.9)
			(max_width 2)
			(curved_edges yes)
			(filter_ratio 0.9)
			(enabled yes)
			(allow_two_segments yes)
			(prefer_zone_connections yes)
		)
		(net 1)
	)
	(via
		(at 104.37 100.82)
		(size 0.45)
		(drill 0.1)
		(layers "F.Cu" "B.Cu")
		(remove_unused_layers yes)
		(keep_end_layers yes)
		(zone_layer_connections "In1.Cu" "In4.Cu" "In6.Cu")
		(teardrops
			(best_length_ratio 0.4)
			(max_length 1)
			(best_width_ratio 0.9)
			(max_width 2)
			(curved_edges yes)
			(filter_ratio 0.9)
			(enabled yes)
			(allow_two_segments yes)
			(prefer_zone_connections yes)
		)
		(net 1)
	)
	(via
		(at 230.46 73.3)
		(size 0.45)
		(drill 0.1)
		(layers "F.Cu" "B.Cu")
		(remove_unused_layers yes)
		(keep_end_layers yes)
		(zone_layer_connections "In1.Cu" "In4.Cu" "In6.Cu")
		(teardrops
			(best_length_ratio 0.4)
			(max_length 1)
			(best_width_ratio 0.9)
			(max_width 2)
			(curved_edges yes)
			(filter_ratio 0.9)
			(enabled yes)
			(allow_two_segments yes)
			(prefer_zone_connections yes)
		)
		(net 1)
	)
	(via
		(at 97.45 128.81)
		(size 0.45)
		(drill 0.1)
		(layers "F.Cu" "B.Cu")
		(remove_unused_layers yes)
		(keep_end_layers yes)
		(zone_layer_connections "In1.Cu" "In4.Cu" "In6.Cu")
		(teardrops
			(best_length_ratio 0.4)
			(max_length 1)
			(best_width_ratio 0.9)
			(max_width 2)
			(curved_edges yes)
			(filter_ratio 0.9)
			(enabled yes)
			(allow_two_segments yes)
			(prefer_zone_connections yes)
		)
		(net 1)
	)
	(via
		(at 96.45 141.81)
		(size 0.45)
		(drill 0.1)
		(layers "F.Cu" "B.Cu")
		(remove_unused_layers yes)
		(keep_end_layers yes)
		(zone_layer_connections "In1.Cu" "In4.Cu" "In6.Cu")
		(teardrops
			(best_length_ratio 0.4)
			(max_length 1)
			(best_width_ratio 0.9)
			(max_width 2)
			(curved_edges yes)
			(filter_ratio 0.9)
			(enabled yes)
			(allow_two_segments yes)
			(prefer_zone_connections yes)
		)
		(net 1)
	)
	(via
		(at 152.5685 72.5595)
		(size 0.45)
		(drill 0.1)
		(layers "F.Cu" "B.Cu")
		(remove_unused_layers yes)
		(keep_end_layers yes)
		(zone_layer_connections "In1.Cu" "In4.Cu" "In6.Cu")
		(teardrops
			(best_length_ratio 0.4)
			(max_length 1)
			(best_width_ratio 0.9)
			(max_width 2)
			(curved_edges yes)
			(filter_ratio 0.9)
			(enabled yes)
			(allow_two_segments yes)
			(prefer_zone_connections yes)
		)
		(net 1)
	)
	(via
		(at 300.55 118.84)
		(size 0.45)
		(drill 0.1)
		(layers "F.Cu" "B.Cu")
		(remove_unused_layers yes)
		(keep_end_layers yes)
		(zone_layer_connections "In1.Cu" "In4.Cu" "In6.Cu")
		(teardrops
			(best_length_ratio 0.4)
			(max_length 1)
			(best_width_ratio 0.9)
			(max_width 2)
			(curved_edges yes)
			(filter_ratio 0.9)
			(enabled yes)
			(allow_two_segments yes)
			(prefer_zone_connections yes)
		)
		(net 1)
	)
	(via
		(at 248.95 117.31)
		(size 0.45)
		(drill 0.1)
		(layers "F.Cu" "B.Cu")
		(remove_unused_layers yes)
		(keep_end_layers yes)
		(zone_layer_connections "In1.Cu" "In4.Cu" "In6.Cu")
		(teardrops
			(best_length_ratio 0.4)
			(max_length 1)
			(best_width_ratio 0.9)
			(max_width 2)
			(curved_edges yes)
			(filter_ratio 0.9)
			(enabled yes)
			(allow_two_segments yes)
			(prefer_zone_connections yes)
		)
		(net 1)
	)
	(via
		(at 103.19 167.11)
		(size 0.45)
		(drill 0.1)
		(layers "F.Cu" "B.Cu")
		(remove_unused_layers yes)
		(keep_end_layers yes)
		(zone_layer_connections "In1.Cu" "In4.Cu" "In6.Cu")
		(teardrops
			(best_length_ratio 0.4)
			(max_length 1)
			(best_width_ratio 0.9)
			(max_width 2)
			(curved_edges yes)
			(filter_ratio 0.9)
			(enabled yes)
			(allow_two_segments yes)
			(prefer_zone_connections yes)
		)
		(net 1)
	)
	(via
		(at 285.45 130.31)
		(size 0.45)
		(drill 0.1)
		(layers "F.Cu" "B.Cu")
		(remove_unused_layers yes)
		(keep_end_layers yes)
		(zone_layer_connections "In1.Cu" "In4.Cu" "In6.Cu")
		(teardrops
			(best_length_ratio 0.4)
			(max_length 1)
			(best_width_ratio 0.9)
			(max_width 2)
			(curved_edges yes)
			(filter_ratio 0.9)
			(enabled yes)
			(allow_two_segments yes)
			(prefer_zone_connections yes)
		)
		(net 1)
	)
	(via
		(at 270.7 160.7)
		(size 0.45)
		(drill 0.1)
		(layers "F.Cu" "B.Cu")
		(remove_unused_layers yes)
		(keep_end_layers yes)
		(zone_layer_connections "In1.Cu" "In4.Cu" "In6.Cu")
		(teardrops
			(best_length_ratio 0.4)
			(max_length 1)
			(best_width_ratio 0.9)
			(max_width 2)
			(curved_edges yes)
			(filter_ratio 0.9)
			(enabled yes)
			(allow_two_segments yes)
			(prefer_zone_connections yes)
		)
		(net 1)
	)
	(via
		(at 137.45 82.31)
		(size 0.45)
		(drill 0.1)
		(layers "F.Cu" "B.Cu")
		(remove_unused_layers yes)
		(keep_end_layers yes)
		(zone_layer_connections "In1.Cu" "In4.Cu" "In6.Cu")
		(teardrops
			(best_length_ratio 0.4)
			(max_length 1)
			(best_width_ratio 0.9)
			(max_width 2)
			(curved_edges yes)
			(filter_ratio 0.9)
			(enabled yes)
			(allow_two_segments yes)
			(prefer_zone_connections yes)
		)
		(net 1)
	)
	(via
		(at 195.95 82.06)
		(size 0.45)
		(drill 0.1)
		(layers "F.Cu" "B.Cu")
		(remove_unused_layers yes)
		(keep_end_layers yes)
		(zone_layer_connections "In1.Cu" "In4.Cu" "In6.Cu")
		(teardrops
			(best_length_ratio 0.4)
			(max_length 1)
			(best_width_ratio 0.9)
			(max_width 2)
			(curved_edges yes)
			(filter_ratio 0.9)
			(enabled yes)
			(allow_two_segments yes)
			(prefer_zone_connections yes)
		)
		(net 1)
	)
	(via
		(at 234.45 87.81)
		(size 0.45)
		(drill 0.1)
		(layers "F.Cu" "B.Cu")
		(remove_unused_layers yes)
		(keep_end_layers yes)
		(zone_layer_connections "In1.Cu" "In4.Cu" "In6.Cu")
		(teardrops
			(best_length_ratio 0.4)
			(max_length 1)
			(best_width_ratio 0.9)
			(max_width 2)
			(curved_edges yes)
			(filter_ratio 0.9)
			(enabled yes)
			(allow_two_segments yes)
			(prefer_zone_connections yes)
		)
		(net 1)
	)
	(via
		(at 95.45 80.81)
		(size 0.45)
		(drill 0.1)
		(layers "F.Cu" "B.Cu")
		(remove_unused_layers yes)
		(keep_end_layers yes)
		(zone_layer_connections "In1.Cu" "In4.Cu" "In6.Cu")
		(teardrops
			(best_length_ratio 0.4)
			(max_length 1)
			(best_width_ratio 0.9)
			(max_width 2)
			(curved_edges yes)
			(filter_ratio 0.9)
			(enabled yes)
			(allow_two_segments yes)
			(prefer_zone_connections yes)
		)
		(net 1)
	)
	(via
		(at 99.46 157.6)
		(size 0.45)
		(drill 0.1)
		(layers "F.Cu" "B.Cu")
		(remove_unused_layers yes)
		(keep_end_layers yes)
		(zone_layer_connections "In1.Cu" "In4.Cu" "In6.Cu")
		(teardrops
			(best_length_ratio 0.4)
			(max_length 1)
			(best_width_ratio 0.9)
			(max_width 2)
			(curved_edges yes)
			(filter_ratio 0.9)
			(enabled yes)
			(allow_two_segments yes)
			(prefer_zone_connections yes)
		)
		(net 1)
	)
	(via
		(at 159.95 92.31)
		(size 0.45)
		(drill 0.1)
		(layers "F.Cu" "B.Cu")
		(remove_unused_layers yes)
		(keep_end_layers yes)
		(free yes)
		(zone_layer_connections "In1.Cu" "In4.Cu" "In6.Cu")
		(teardrops
			(best_length_ratio 0.4)
			(max_length 1)
			(best_width_ratio 0.9)
			(max_width 2)
			(curved_edges yes)
			(filter_ratio 0.9)
			(enabled yes)
			(allow_two_segments yes)
			(prefer_zone_connections yes)
		)
		(net 1)
	)
	(via
		(at 107.45 83.81)
		(size 0.45)
		(drill 0.1)
		(layers "F.Cu" "B.Cu")
		(remove_unused_layers yes)
		(keep_end_layers yes)
		(zone_layer_connections "In1.Cu" "In4.Cu" "In6.Cu")
		(teardrops
			(best_length_ratio 0.4)
			(max_length 1)
			(best_width_ratio 0.9)
			(max_width 2)
			(curved_edges yes)
			(filter_ratio 0.9)
			(enabled yes)
			(allow_two_segments yes)
			(prefer_zone_connections yes)
		)
		(net 1)
	)
	(via
		(at 240.95 170.81)
		(size 0.45)
		(drill 0.1)
		(layers "F.Cu" "B.Cu")
		(remove_unused_layers yes)
		(keep_end_layers yes)
		(zone_layer_connections "In1.Cu" "In4.Cu" "In6.Cu")
		(teardrops
			(best_length_ratio 0.4)
			(max_length 1)
			(best_width_ratio 0.9)
			(max_width 2)
			(curved_edges yes)
			(filter_ratio 0.9)
			(enabled yes)
			(allow_two_segments yes)
			(prefer_zone_connections yes)
		)
		(net 1)
	)
	(via
		(at 115.9 147.361)
		(size 0.45)
		(drill 0.1)
		(layers "F.Cu" "B.Cu")
		(remove_unused_layers yes)
		(keep_end_layers yes)
		(zone_layer_connections "In1.Cu" "In4.Cu" "In6.Cu")
		(teardrops
			(best_length_ratio 0.4)
			(max_length 1)
			(best_width_ratio 0.9)
			(max_width 2)
			(curved_edges yes)
			(filter_ratio 0.9)
			(enabled yes)
			(allow_two_segments yes)
			(prefer_zone_connections yes)
		)
		(net 1)
	)
	(via
		(at 234.490708 75.76)
		(size 0.45)
		(drill 0.1)
		(layers "F.Cu" "B.Cu")
		(remove_unused_layers yes)
		(keep_end_layers yes)
		(zone_layer_connections "In1.Cu" "In4.Cu" "In6.Cu")
		(teardrops
			(best_length_ratio 0.4)
			(max_length 1)
			(best_width_ratio 0.9)
			(max_width 2)
			(curved_edges yes)
			(filter_ratio 0.9)
			(enabled yes)
			(allow_two_segments yes)
			(prefer_zone_connections yes)
		)
		(net 1)
	)
	(via
		(at 283.95 118.31)
		(size 0.45)
		(drill 0.1)
		(layers "F.Cu" "B.Cu")
		(remove_unused_layers yes)
		(keep_end_layers yes)
		(zone_layer_connections "In1.Cu" "In4.Cu" "In6.Cu")
		(teardrops
			(best_length_ratio 0.4)
			(max_length 1)
			(best_width_ratio 0.9)
			(max_width 2)
			(curved_edges yes)
			(filter_ratio 0.9)
			(enabled yes)
			(allow_two_segments yes)
			(prefer_zone_connections yes)
		)
		(net 1)
	)
	(via
		(at 96.45 133.81)
		(size 0.45)
		(drill 0.1)
		(layers "F.Cu" "B.Cu")
		(remove_unused_layers yes)
		(keep_end_layers yes)
		(zone_layer_connections "In1.Cu" "In4.Cu" "In6.Cu")
		(teardrops
			(best_length_ratio 0.4)
			(max_length 1)
			(best_width_ratio 0.9)
			(max_width 2)
			(curved_edges yes)
			(filter_ratio 0.9)
			(enabled yes)
			(allow_two_segments yes)
			(prefer_zone_connections yes)
		)
		(net 1)
	)
	(via
		(at 311.4005 96.0365)
		(size 0.45)
		(drill 0.1)
		(layers "F.Cu" "B.Cu")
		(remove_unused_layers yes)
		(keep_end_layers yes)
		(zone_layer_connections "In1.Cu" "In4.Cu" "In6.Cu")
		(teardrops
			(best_length_ratio 0.4)
			(max_length 1)
			(best_width_ratio 0.9)
			(max_width 2)
			(curved_edges yes)
			(filter_ratio 0.9)
			(enabled yes)
			(allow_two_segments yes)
			(prefer_zone_connections yes)
		)
		(net 1)
	)
	(via
		(at 102.45 131.81)
		(size 0.45)
		(drill 0.1)
		(layers "F.Cu" "B.Cu")
		(remove_unused_layers yes)
		(keep_end_layers yes)
		(zone_layer_connections "In1.Cu" "In4.Cu" "In6.Cu")
		(teardrops
			(best_length_ratio 0.4)
			(max_length 1)
			(best_width_ratio 0.9)
			(max_width 2)
			(curved_edges yes)
			(filter_ratio 0.9)
			(enabled yes)
			(allow_two_segments yes)
			(prefer_zone_connections yes)
		)
		(net 1)
	)
	(via
		(at 231.45 90.81)
		(size 0.45)
		(drill 0.1)
		(layers "F.Cu" "B.Cu")
		(remove_unused_layers yes)
		(keep_end_layers yes)
		(free yes)
		(zone_layer_connections "In1.Cu" "In4.Cu" "In6.Cu")
		(teardrops
			(best_length_ratio 0.4)
			(max_length 1)
			(best_width_ratio 0.9)
			(max_width 2)
			(curved_edges yes)
			(filter_ratio 0.9)
			(enabled yes)
			(allow_two_segments yes)
			(prefer_zone_connections yes)
		)
		(net 1)
	)
	(via
		(at 262.45 108.31)
		(size 0.45)
		(drill 0.1)
		(layers "F.Cu" "B.Cu")
		(remove_unused_layers yes)
		(keep_end_layers yes)
		(free yes)
		(zone_layer_connections "In1.Cu" "In4.Cu" "In6.Cu")
		(teardrops
			(best_length_ratio 0.4)
			(max_length 1)
			(best_width_ratio 0.9)
			(max_width 2)
			(curved_edges yes)
			(filter_ratio 0.9)
			(enabled yes)
			(allow_two_segments yes)
			(prefer_zone_connections yes)
		)
		(net 1)
	)
	(via
		(at 158.45 87.81)
		(size 0.45)
		(drill 0.1)
		(layers "F.Cu" "B.Cu")
		(remove_unused_layers yes)
		(keep_end_layers yes)
		(free yes)
		(zone_layer_connections "In1.Cu" "In4.Cu" "In6.Cu")
		(teardrops
			(best_length_ratio 0.4)
			(max_length 1)
			(best_width_ratio 0.9)
			(max_width 2)
			(curved_edges yes)
			(filter_ratio 0.9)
			(enabled yes)
			(allow_two_segments yes)
			(prefer_zone_connections yes)
		)
		(net 1)
	)
	(via
		(at 143.377 148.778)
		(size 0.45)
		(drill 0.1)
		(layers "F.Cu" "B.Cu")
		(remove_unused_layers yes)
		(keep_end_layers yes)
		(zone_layer_connections "In1.Cu" "In4.Cu" "In6.Cu")
		(teardrops
			(best_length_ratio 0.4)
			(max_length 1)
			(best_width_ratio 0.9)
			(max_width 2)
			(curved_edges yes)
			(filter_ratio 0.9)
			(enabled yes)
			(allow_two_segments yes)
			(prefer_zone_connections yes)
		)
		(net 1)
	)
	(via
		(at 137.29 133.86)
		(size 0.45)
		(drill 0.1)
		(layers "F.Cu" "B.Cu")
		(remove_unused_layers yes)
		(keep_end_layers yes)
		(zone_layer_connections "In1.Cu" "In4.Cu" "In6.Cu")
		(teardrops
			(best_length_ratio 0.4)
			(max_length 1)
			(best_width_ratio 0.9)
			(max_width 2)
			(curved_edges yes)
			(filter_ratio 0.9)
			(enabled yes)
			(allow_two_segments yes)
			(prefer_zone_connections yes)
		)
		(net 1)
	)
	(via
		(at 111.45 80.81)
		(size 0.45)
		(drill 0.1)
		(layers "F.Cu" "B.Cu")
		(remove_unused_layers yes)
		(keep_end_layers yes)
		(zone_layer_connections "In1.Cu" "In4.Cu" "In6.Cu")
		(teardrops
			(best_length_ratio 0.4)
			(max_length 1)
			(best_width_ratio 0.9)
			(max_width 2)
			(curved_edges yes)
			(filter_ratio 0.9)
			(enabled yes)
			(allow_two_segments yes)
			(prefer_zone_connections yes)
		)
		(net 1)
	)
	(via
		(at 114.95 72.31)
		(size 0.45)
		(drill 0.1)
		(layers "F.Cu" "B.Cu")
		(remove_unused_layers yes)
		(keep_end_layers yes)
		(zone_layer_connections "In1.Cu" "In4.Cu" "In6.Cu")
		(teardrops
			(best_length_ratio 0.4)
			(max_length 1)
			(best_width_ratio 0.9)
			(max_width 2)
			(curved_edges yes)
			(filter_ratio 0.9)
			(enabled yes)
			(allow_two_segments yes)
			(prefer_zone_connections yes)
		)
		(net 1)
	)
	(via
		(at 195.85 154.025)
		(size 0.45)
		(drill 0.1)
		(layers "F.Cu" "B.Cu")
		(teardrops
			(best_length_ratio 0.4)
			(max_length 1)
			(best_width_ratio 0.9)
			(max_width 2)
			(curved_edges yes)
			(filter_ratio 0.9)
			(enabled yes)
			(allow_two_segments yes)
			(prefer_zone_connections yes)
		)
		(net 1)
	)
	(via
		(at 133.65 115.7)
		(size 0.45)
		(drill 0.1)
		(layers "F.Cu" "B.Cu")
		(remove_unused_layers yes)
		(keep_end_layers yes)
		(zone_layer_connections "In1.Cu" "In4.Cu" "In6.Cu")
		(teardrops
			(best_length_ratio 0.4)
			(max_length 1)
			(best_width_ratio 0.9)
			(max_width 2)
			(curved_edges yes)
			(filter_ratio 0.9)
			(enabled yes)
			(allow_two_segments yes)
			(prefer_zone_connections yes)
		)
		(net 1)
	)
	(via
		(at 136.52 163.76)
		(size 0.45)
		(drill 0.1)
		(layers "F.Cu" "B.Cu")
		(remove_unused_layers yes)
		(keep_end_layers yes)
		(zone_layer_connections "In1.Cu" "In4.Cu" "In6.Cu")
		(teardrops
			(best_length_ratio 0.4)
			(max_length 1)
			(best_width_ratio 0.9)
			(max_width 2)
			(curved_edges yes)
			(filter_ratio 0.9)
			(enabled yes)
			(allow_two_segments yes)
			(prefer_zone_connections yes)
		)
		(net 1)
	)
	(via
		(at 109.756999 74.396)
		(size 0.45)
		(drill 0.1)
		(layers "F.Cu" "B.Cu")
		(remove_unused_layers yes)
		(keep_end_layers yes)
		(zone_layer_connections "In1.Cu" "In4.Cu" "In6.Cu")
		(teardrops
			(best_length_ratio 0.4)
			(max_length 1)
			(best_width_ratio 0.9)
			(max_width 2)
			(curved_edges yes)
			(filter_ratio 0.9)
			(enabled yes)
			(allow_two_segments yes)
			(prefer_zone_connections yes)
		)
		(net 1)
	)
	(via
		(at 292.45 148.81)
		(size 0.45)
		(drill 0.1)
		(layers "F.Cu" "B.Cu")
		(remove_unused_layers yes)
		(keep_end_layers yes)
		(zone_layer_connections "In1.Cu" "In4.Cu" "In6.Cu")
		(teardrops
			(best_length_ratio 0.4)
			(max_length 1)
			(best_width_ratio 0.9)
			(max_width 2)
			(curved_edges yes)
			(filter_ratio 0.9)
			(enabled yes)
			(allow_two_segments yes)
			(prefer_zone_connections yes)
		)
		(net 1)
	)
	(via
		(at 100.95 112.81)
		(size 0.45)
		(drill 0.1)
		(layers "F.Cu" "B.Cu")
		(remove_unused_layers yes)
		(keep_end_layers yes)
		(zone_layer_connections "In1.Cu" "In4.Cu" "In6.Cu")
		(teardrops
			(best_length_ratio 0.4)
			(max_length 1)
			(best_width_ratio 0.9)
			(max_width 2)
			(curved_edges yes)
			(filter_ratio 0.9)
			(enabled yes)
			(allow_two_segments yes)
			(prefer_zone_connections yes)
		)
		(net 1)
	)
	(via
		(at 135.95 87.31)
		(size 0.45)
		(drill 0.1)
		(layers "F.Cu" "B.Cu")
		(remove_unused_layers yes)
		(keep_end_layers yes)
		(free yes)
		(zone_layer_connections "In1.Cu" "In4.Cu" "In6.Cu")
		(teardrops
			(best_length_ratio 0.4)
			(max_length 1)
			(best_width_ratio 0.9)
			(max_width 2)
			(curved_edges yes)
			(filter_ratio 0.9)
			(enabled yes)
			(allow_two_segments yes)
			(prefer_zone_connections yes)
		)
		(net 1)
	)
	(via
		(at 153.45 135.86)
		(size 0.45)
		(drill 0.1)
		(layers "F.Cu" "B.Cu")
		(remove_unused_layers yes)
		(keep_end_layers yes)
		(zone_layer_connections "In1.Cu" "In4.Cu" "In6.Cu")
		(teardrops
			(best_length_ratio 0.4)
			(max_length 1)
			(best_width_ratio 0.9)
			(max_width 2)
			(curved_edges yes)
			(filter_ratio 0.9)
			(enabled yes)
			(allow_two_segments yes)
			(prefer_zone_connections yes)
		)
		(net 1)
	)
	(via
		(at 111.125 165.45)
		(size 0.45)
		(drill 0.1)
		(layers "F.Cu" "B.Cu")
		(remove_unused_layers yes)
		(keep_end_layers yes)
		(free yes)
		(zone_layer_connections "In1.Cu" "In4.Cu" "In6.Cu")
		(teardrops
			(best_length_ratio 0.4)
			(max_length 1)
			(best_width_ratio 0.9)
			(max_width 2)
			(curved_edges yes)
			(filter_ratio 0.9)
			(enabled yes)
			(allow_two_segments yes)
			(prefer_zone_connections yes)
		)
		(net 1)
	)
	(via
		(at 117.45 94.31)
		(size 0.45)
		(drill 0.1)
		(layers "F.Cu" "B.Cu")
		(remove_unused_layers yes)
		(keep_end_layers yes)
		(zone_layer_connections "In1.Cu" "In4.Cu" "In6.Cu")
		(teardrops
			(best_length_ratio 0.4)
			(max_length 1)
			(best_width_ratio 0.9)
			(max_width 2)
			(curved_edges yes)
			(filter_ratio 0.9)
			(enabled yes)
			(allow_two_segments yes)
			(prefer_zone_connections yes)
		)
		(net 1)
	)
	(via
		(at 222.45 78.11)
		(size 0.45)
		(drill 0.1)
		(layers "F.Cu" "B.Cu")
		(remove_unused_layers yes)
		(keep_end_layers yes)
		(zone_layer_connections "In1.Cu" "In4.Cu" "In6.Cu")
		(teardrops
			(best_length_ratio 0.4)
			(max_length 1)
			(best_width_ratio 0.9)
			(max_width 2)
			(curved_edges yes)
			(filter_ratio 0.9)
			(enabled yes)
			(allow_two_segments yes)
			(prefer_zone_connections yes)
		)
		(net 1)
	)
	(via
		(at 143.95 157.31)
		(size 0.45)
		(drill 0.1)
		(layers "F.Cu" "B.Cu")
		(remove_unused_layers yes)
		(keep_end_layers yes)
		(zone_layer_connections "In1.Cu" "In4.Cu" "In6.Cu")
		(teardrops
			(best_length_ratio 0.4)
			(max_length 1)
			(best_width_ratio 0.9)
			(max_width 2)
			(curved_edges yes)
			(filter_ratio 0.9)
			(enabled yes)
			(allow_two_segments yes)
			(prefer_zone_connections yes)
		)
		(net 1)
	)
	(via
		(at 284.45 99.31)
		(size 0.45)
		(drill 0.1)
		(layers "F.Cu" "B.Cu")
		(remove_unused_layers yes)
		(keep_end_layers yes)
		(zone_layer_connections "In1.Cu" "In4.Cu" "In6.Cu")
		(teardrops
			(best_length_ratio 0.4)
			(max_length 1)
			(best_width_ratio 0.9)
			(max_width 2)
			(curved_edges yes)
			(filter_ratio 0.9)
			(enabled yes)
			(allow_two_segments yes)
			(prefer_zone_connections yes)
		)
		(net 1)
	)
	(via
		(at 289.45 91.31)
		(size 0.45)
		(drill 0.1)
		(layers "F.Cu" "B.Cu")
		(remove_unused_layers yes)
		(keep_end_layers yes)
		(zone_layer_connections "In1.Cu" "In4.Cu" "In6.Cu")
		(teardrops
			(best_length_ratio 0.4)
			(max_length 1)
			(best_width_ratio 0.9)
			(max_width 2)
			(curved_edges yes)
			(filter_ratio 0.9)
			(enabled yes)
			(allow_two_segments yes)
			(prefer_zone_connections yes)
		)
		(net 1)
	)
	(via
		(at 229.95 75.31)
		(size 0.45)
		(drill 0.1)
		(layers "F.Cu" "B.Cu")
		(remove_unused_layers yes)
		(keep_end_layers yes)
		(zone_layer_connections "In1.Cu" "In4.Cu" "In6.Cu")
		(teardrops
			(best_length_ratio 0.4)
			(max_length 1)
			(best_width_ratio 0.9)
			(max_width 2)
			(curved_edges yes)
			(filter_ratio 0.9)
			(enabled yes)
			(allow_two_segments yes)
			(prefer_zone_connections yes)
		)
		(net 1)
	)
	(via
		(at 178.1 166.9)
		(size 0.45)
		(drill 0.1)
		(layers "F.Cu" "B.Cu")
		(teardrops
			(best_length_ratio 0.4)
			(max_length 1)
			(best_width_ratio 0.9)
			(max_width 2)
			(curved_edges yes)
			(filter_ratio 0.9)
			(enabled yes)
			(allow_two_segments yes)
			(prefer_zone_connections yes)
		)
		(net 1)
	)
	(via
		(at 106.05 159.65)
		(size 0.45)
		(drill 0.1)
		(layers "F.Cu" "B.Cu")
		(remove_unused_layers yes)
		(keep_end_layers yes)
		(free yes)
		(zone_layer_connections "In1.Cu" "In4.Cu" "In6.Cu")
		(teardrops
			(best_length_ratio 0.4)
			(max_length 1)
			(best_width_ratio 0.9)
			(max_width 2)
			(curved_edges yes)
			(filter_ratio 0.9)
			(enabled yes)
			(allow_two_segments yes)
			(prefer_zone_connections yes)
		)
		(net 1)
	)
	(via
		(at 192.530489 137.005053)
		(size 0.45)
		(drill 0.1)
		(layers "F.Cu" "B.Cu")
		(remove_unused_layers yes)
		(keep_end_layers yes)
		(zone_layer_connections "In1.Cu" "In4.Cu" "In6.Cu")
		(teardrops
			(best_length_ratio 0.4)
			(max_length 1)
			(best_width_ratio 0.9)
			(max_width 2)
			(curved_edges yes)
			(filter_ratio 0.9)
			(enabled yes)
			(allow_two_segments yes)
			(prefer_zone_connections yes)
		)
		(net 1)
	)
	(via
		(at 171.45 68.81)
		(size 0.45)
		(drill 0.1)
		(layers "F.Cu" "B.Cu")
		(remove_unused_layers yes)
		(keep_end_layers yes)
		(zone_layer_connections "In1.Cu" "In4.Cu" "In6.Cu")
		(teardrops
			(best_length_ratio 0.4)
			(max_length 1)
			(best_width_ratio 0.9)
			(max_width 2)
			(curved_edges yes)
			(filter_ratio 0.9)
			(enabled yes)
			(allow_two_segments yes)
			(prefer_zone_connections yes)
		)
		(net 1)
	)
	(via
		(at 95.45 100.81)
		(size 0.45)
		(drill 0.1)
		(layers "F.Cu" "B.Cu")
		(remove_unused_layers yes)
		(keep_end_layers yes)
		(zone_layer_connections "In1.Cu" "In4.Cu" "In6.Cu")
		(teardrops
			(best_length_ratio 0.4)
			(max_length 1)
			(best_width_ratio 0.9)
			(max_width 2)
			(curved_edges yes)
			(filter_ratio 0.9)
			(enabled yes)
			(allow_two_segments yes)
			(prefer_zone_connections yes)
		)
		(net 1)
	)
	(via
		(at 133.29 131.86)
		(size 0.45)
		(drill 0.1)
		(layers "F.Cu" "B.Cu")
		(remove_unused_layers yes)
		(keep_end_layers yes)
		(zone_layer_connections "In1.Cu" "In4.Cu" "In6.Cu")
		(teardrops
			(best_length_ratio 0.4)
			(max_length 1)
			(best_width_ratio 0.9)
			(max_width 2)
			(curved_edges yes)
			(filter_ratio 0.9)
			(enabled yes)
			(allow_two_segments yes)
			(prefer_zone_connections yes)
		)
		(net 1)
	)
	(via
		(at 133.29 140.86)
		(size 0.45)
		(drill 0.1)
		(layers "F.Cu" "B.Cu")
		(remove_unused_layers yes)
		(keep_end_layers yes)
		(zone_layer_connections "In1.Cu" "In4.Cu" "In6.Cu")
		(teardrops
			(best_length_ratio 0.4)
			(max_length 1)
			(best_width_ratio 0.9)
			(max_width 2)
			(curved_edges yes)
			(filter_ratio 0.9)
			(enabled yes)
			(allow_two_segments yes)
			(prefer_zone_connections yes)
		)
		(net 1)
	)
	(via
		(at 108.95 71.31)
		(size 0.45)
		(drill 0.1)
		(layers "F.Cu" "B.Cu")
		(remove_unused_layers yes)
		(keep_end_layers yes)
		(zone_layer_connections "In1.Cu" "In4.Cu" "In6.Cu")
		(teardrops
			(best_length_ratio 0.4)
			(max_length 1)
			(best_width_ratio 0.9)
			(max_width 2)
			(curved_edges yes)
			(filter_ratio 0.9)
			(enabled yes)
			(allow_two_segments yes)
			(prefer_zone_connections yes)
		)
		(net 1)
	)
	(via
		(at 150.175 73.485)
		(size 0.45)
		(drill 0.1)
		(layers "F.Cu" "B.Cu")
		(remove_unused_layers yes)
		(keep_end_layers yes)
		(free yes)
		(zone_layer_connections "In1.Cu" "In4.Cu" "In6.Cu")
		(teardrops
			(best_length_ratio 0.4)
			(max_length 1)
			(best_width_ratio 0.9)
			(max_width 2)
			(curved_edges yes)
			(filter_ratio 0.9)
			(enabled yes)
			(allow_two_segments yes)
			(prefer_zone_connections yes)
		)
		(net 1)
	)
	(via
		(at 296.45 121.81)
		(size 0.45)
		(drill 0.1)
		(layers "F.Cu" "B.Cu")
		(remove_unused_layers yes)
		(keep_end_layers yes)
		(zone_layer_connections "In1.Cu" "In4.Cu" "In6.Cu")
		(teardrops
			(best_length_ratio 0.4)
			(max_length 1)
			(best_width_ratio 0.9)
			(max_width 2)
			(curved_edges yes)
			(filter_ratio 0.9)
			(enabled yes)
			(allow_two_segments yes)
			(prefer_zone_connections yes)
		)
		(net 1)
	)
	(via
		(at 219.5 166.8)
		(size 0.45)
		(drill 0.1)
		(layers "F.Cu" "B.Cu")
		(teardrops
			(best_length_ratio 0.4)
			(max_length 1)
			(best_width_ratio 0.9)
			(max_width 2)
			(curved_edges yes)
			(filter_ratio 0.9)
			(enabled yes)
			(allow_two_segments yes)
			(prefer_zone_connections yes)
		)
		(net 1)
	)
	(via
		(at 125 153.81)
		(size 0.45)
		(drill 0.1)
		(layers "F.Cu" "B.Cu")
		(remove_unused_layers yes)
		(keep_end_layers yes)
		(zone_layer_connections "In1.Cu" "In4.Cu" "In6.Cu")
		(teardrops
			(best_length_ratio 0.4)
			(max_length 1)
			(best_width_ratio 0.9)
			(max_width 2)
			(curved_edges yes)
			(filter_ratio 0.9)
			(enabled yes)
			(allow_two_segments yes)
			(prefer_zone_connections yes)
		)
		(net 1)
	)
	(via
		(at 118.45 97.31)
		(size 0.45)
		(drill 0.1)
		(layers "F.Cu" "B.Cu")
		(remove_unused_layers yes)
		(keep_end_layers yes)
		(zone_layer_connections "In1.Cu" "In4.Cu" "In6.Cu")
		(teardrops
			(best_length_ratio 0.4)
			(max_length 1)
			(best_width_ratio 0.9)
			(max_width 2)
			(curved_edges yes)
			(filter_ratio 0.9)
			(enabled yes)
			(allow_two_segments yes)
			(prefer_zone_connections yes)
		)
		(net 1)
	)
	(via
		(at 228.45 84.81)
		(size 0.45)
		(drill 0.1)
		(layers "F.Cu" "B.Cu")
		(remove_unused_layers yes)
		(keep_end_layers yes)
		(zone_layer_connections "In1.Cu" "In4.Cu" "In6.Cu")
		(teardrops
			(best_length_ratio 0.4)
			(max_length 1)
			(best_width_ratio 0.9)
			(max_width 2)
			(curved_edges yes)
			(filter_ratio 0.9)
			(enabled yes)
			(allow_two_segments yes)
			(prefer_zone_connections yes)
		)
		(net 1)
	)
	(via
		(at 302.98 103.61)
		(size 0.45)
		(drill 0.1)
		(layers "F.Cu" "B.Cu")
		(remove_unused_layers yes)
		(keep_end_layers yes)
		(zone_layer_connections "In1.Cu" "In4.Cu" "In6.Cu")
		(teardrops
			(best_length_ratio 0.4)
			(max_length 1)
			(best_width_ratio 0.9)
			(max_width 2)
			(curved_edges yes)
			(filter_ratio 0.9)
			(enabled yes)
			(allow_two_segments yes)
			(prefer_zone_connections yes)
		)
		(net 1)
	)
	(via
		(at 190.45 167.1)
		(size 0.45)
		(drill 0.1)
		(layers "F.Cu" "B.Cu")
		(teardrops
			(best_length_ratio 0.4)
			(max_length 1)
			(best_width_ratio 0.9)
			(max_width 2)
			(curved_edges yes)
			(filter_ratio 0.9)
			(enabled yes)
			(allow_two_segments yes)
			(prefer_zone_connections yes)
		)
		(net 1)
	)
	(via
		(at 137.55 170.31)
		(size 0.45)
		(drill 0.1)
		(layers "F.Cu" "B.Cu")
		(remove_unused_layers yes)
		(keep_end_layers yes)
		(zone_layer_connections "In1.Cu" "In4.Cu" "In6.Cu")
		(teardrops
			(best_length_ratio 0.4)
			(max_length 1)
			(best_width_ratio 0.9)
			(max_width 2)
			(curved_edges yes)
			(filter_ratio 0.9)
			(enabled yes)
			(allow_two_segments yes)
			(prefer_zone_connections yes)
		)
		(net 1)
	)
	(via
		(at 155.45 90.81)
		(size 0.45)
		(drill 0.1)
		(layers "F.Cu" "B.Cu")
		(remove_unused_layers yes)
		(keep_end_layers yes)
		(zone_layer_connections "In1.Cu" "In4.Cu" "In6.Cu")
		(teardrops
			(best_length_ratio 0.4)
			(max_length 1)
			(best_width_ratio 0.9)
			(max_width 2)
			(curved_edges yes)
			(filter_ratio 0.9)
			(enabled yes)
			(allow_two_segments yes)
			(prefer_zone_connections yes)
		)
		(net 1)
	)
	(via
		(at 318.95 70.81)
		(size 0.45)
		(drill 0.1)
		(layers "F.Cu" "B.Cu")
		(remove_unused_layers yes)
		(keep_end_layers yes)
		(zone_layer_connections "In1.Cu" "In4.Cu" "In6.Cu")
		(teardrops
			(best_length_ratio 0.4)
			(max_length 1)
			(best_width_ratio 0.9)
			(max_width 2)
			(curved_edges yes)
			(filter_ratio 0.9)
			(enabled yes)
			(allow_two_segments yes)
			(prefer_zone_connections yes)
		)
		(net 1)
	)
	(via
		(at 118.96 168.91)
		(size 0.45)
		(drill 0.1)
		(layers "F.Cu" "B.Cu")
		(remove_unused_layers yes)
		(keep_end_layers yes)
		(zone_layer_connections "In1.Cu" "In4.Cu" "In6.Cu")
		(teardrops
			(best_length_ratio 0.4)
			(max_length 1)
			(best_width_ratio 0.9)
			(max_width 2)
			(curved_edges yes)
			(filter_ratio 0.9)
			(enabled yes)
			(allow_two_segments yes)
			(prefer_zone_connections yes)
		)
		(net 1)
	)
	(via
		(at 181.1 161.7)
		(size 0.45)
		(drill 0.1)
		(layers "F.Cu" "B.Cu")
		(teardrops
			(best_length_ratio 0.4)
			(max_length 1)
			(best_width_ratio 0.9)
			(max_width 2)
			(curved_edges yes)
			(filter_ratio 0.9)
			(enabled yes)
			(allow_two_segments yes)
			(prefer_zone_connections yes)
		)
		(net 1)
	)
	(via
		(at 300.45 109.81)
		(size 0.45)
		(drill 0.1)
		(layers "F.Cu" "B.Cu")
		(remove_unused_layers yes)
		(keep_end_layers yes)
		(zone_layer_connections "In1.Cu" "In4.Cu" "In6.Cu")
		(teardrops
			(best_length_ratio 0.4)
			(max_length 1)
			(best_width_ratio 0.9)
			(max_width 2)
			(curved_edges yes)
			(filter_ratio 0.9)
			(enabled yes)
			(allow_two_segments yes)
			(prefer_zone_connections yes)
		)
		(net 1)
	)
	(via
		(at 289.525 78.41)
		(size 0.45)
		(drill 0.1)
		(layers "F.Cu" "B.Cu")
		(remove_unused_layers yes)
		(keep_end_layers yes)
		(free yes)
		(zone_layer_connections "In1.Cu" "In4.Cu" "In6.Cu")
		(teardrops
			(best_length_ratio 0.4)
			(max_length 1)
			(best_width_ratio 0.9)
			(max_width 2)
			(curved_edges yes)
			(filter_ratio 0.9)
			(enabled yes)
			(allow_two_segments yes)
			(prefer_zone_connections yes)
		)
		(net 1)
	)
	(via
		(at 200.95 85.56)
		(size 0.45)
		(drill 0.1)
		(layers "F.Cu" "B.Cu")
		(remove_unused_layers yes)
		(keep_end_layers yes)
		(zone_layer_connections "In1.Cu" "In4.Cu" "In6.Cu")
		(teardrops
			(best_length_ratio 0.4)
			(max_length 1)
			(best_width_ratio 0.9)
			(max_width 2)
			(curved_edges yes)
			(filter_ratio 0.9)
			(enabled yes)
			(allow_two_segments yes)
			(prefer_zone_connections yes)
		)
		(net 1)
	)
	(via
		(at 129.29 141.86)
		(size 0.45)
		(drill 0.1)
		(layers "F.Cu" "B.Cu")
		(remove_unused_layers yes)
		(keep_end_layers yes)
		(zone_layer_connections "In1.Cu" "In4.Cu" "In6.Cu")
		(teardrops
			(best_length_ratio 0.4)
			(max_length 1)
			(best_width_ratio 0.9)
			(max_width 2)
			(curved_edges yes)
			(filter_ratio 0.9)
			(enabled yes)
			(allow_two_segments yes)
			(prefer_zone_connections yes)
		)
		(net 1)
	)
	(via
		(at 248.95 120.31)
		(size 0.45)
		(drill 0.1)
		(layers "F.Cu" "B.Cu")
		(remove_unused_layers yes)
		(keep_end_layers yes)
		(zone_layer_connections "In1.Cu" "In4.Cu" "In6.Cu")
		(teardrops
			(best_length_ratio 0.4)
			(max_length 1)
			(best_width_ratio 0.9)
			(max_width 2)
			(curved_edges yes)
			(filter_ratio 0.9)
			(enabled yes)
			(allow_two_segments yes)
			(prefer_zone_connections yes)
		)
		(net 1)
	)
	(via
		(at 118.96 169.96)
		(size 0.45)
		(drill 0.1)
		(layers "F.Cu" "B.Cu")
		(remove_unused_layers yes)
		(keep_end_layers yes)
		(zone_layer_connections "In1.Cu" "In4.Cu" "In6.Cu")
		(teardrops
			(best_length_ratio 0.4)
			(max_length 1)
			(best_width_ratio 0.9)
			(max_width 2)
			(curved_edges yes)
			(filter_ratio 0.9)
			(enabled yes)
			(allow_two_segments yes)
			(prefer_zone_connections yes)
		)
		(net 1)
	)
	(via
		(at 204.1 164.7)
		(size 0.45)
		(drill 0.1)
		(layers "F.Cu" "B.Cu")
		(teardrops
			(best_length_ratio 0.4)
			(max_length 1)
			(best_width_ratio 0.9)
			(max_width 2)
			(curved_edges yes)
			(filter_ratio 0.9)
			(enabled yes)
			(allow_two_segments yes)
			(prefer_zone_connections yes)
		)
		(net 1)
	)
	(via
		(at 187.3 122.1)
		(size 0.45)
		(drill 0.1)
		(layers "F.Cu" "B.Cu")
		(remove_unused_layers yes)
		(keep_end_layers yes)
		(zone_layer_connections "In1.Cu" "In4.Cu" "In6.Cu")
		(teardrops
			(best_length_ratio 0.4)
			(max_length 1)
			(best_width_ratio 0.9)
			(max_width 2)
			(curved_edges yes)
			(filter_ratio 0.9)
			(enabled yes)
			(allow_two_segments yes)
			(prefer_zone_connections yes)
		)
		(net 1)
	)
	(via
		(at 124.22 149.74)
		(size 0.45)
		(drill 0.1)
		(layers "F.Cu" "B.Cu")
		(remove_unused_layers yes)
		(keep_end_layers yes)
		(zone_layer_connections "In1.Cu" "In4.Cu" "In6.Cu")
		(teardrops
			(best_length_ratio 0.4)
			(max_length 1)
			(best_width_ratio 0.9)
			(max_width 2)
			(curved_edges yes)
			(filter_ratio 0.9)
			(enabled yes)
			(allow_two_segments yes)
			(prefer_zone_connections yes)
		)
		(net 1)
	)
	(via
		(at 132.29 131.86)
		(size 0.45)
		(drill 0.1)
		(layers "F.Cu" "B.Cu")
		(remove_unused_layers yes)
		(keep_end_layers yes)
		(zone_layer_connections "In1.Cu" "In4.Cu" "In6.Cu")
		(teardrops
			(best_length_ratio 0.4)
			(max_length 1)
			(best_width_ratio 0.9)
			(max_width 2)
			(curved_edges yes)
			(filter_ratio 0.9)
			(enabled yes)
			(allow_two_segments yes)
			(prefer_zone_connections yes)
		)
		(net 1)
	)
	(via
		(at 123.45 170.81)
		(size 0.45)
		(drill 0.1)
		(layers "F.Cu" "B.Cu")
		(remove_unused_layers yes)
		(keep_end_layers yes)
		(zone_layer_connections "In1.Cu" "In4.Cu" "In6.Cu")
		(teardrops
			(best_length_ratio 0.4)
			(max_length 1)
			(best_width_ratio 0.9)
			(max_width 2)
			(curved_edges yes)
			(filter_ratio 0.9)
			(enabled yes)
			(allow_two_segments yes)
			(prefer_zone_connections yes)
		)
		(net 1)
	)
	(via
		(at 123.45 152.81)
		(size 0.45)
		(drill 0.1)
		(layers "F.Cu" "B.Cu")
		(remove_unused_layers yes)
		(keep_end_layers yes)
		(zone_layer_connections "In1.Cu" "In4.Cu" "In6.Cu")
		(teardrops
			(best_length_ratio 0.4)
			(max_length 1)
			(best_width_ratio 0.9)
			(max_width 2)
			(curved_edges yes)
			(filter_ratio 0.9)
			(enabled yes)
			(allow_two_segments yes)
			(prefer_zone_connections yes)
		)
		(net 1)
	)
	(via
		(at 289.025 78.42)
		(size 0.45)
		(drill 0.1)
		(layers "F.Cu" "B.Cu")
		(remove_unused_layers yes)
		(keep_end_layers yes)
		(free yes)
		(zone_layer_connections "In1.Cu" "In4.Cu" "In6.Cu")
		(teardrops
			(best_length_ratio 0.4)
			(max_length 1)
			(best_width_ratio 0.9)
			(max_width 2)
			(curved_edges yes)
			(filter_ratio 0.9)
			(enabled yes)
			(allow_two_segments yes)
			(prefer_zone_connections yes)
		)
		(net 1)
	)
	(via
		(at 105.45 116.31)
		(size 0.45)
		(drill 0.1)
		(layers "F.Cu" "B.Cu")
		(remove_unused_layers yes)
		(keep_end_layers yes)
		(zone_layer_connections "In1.Cu" "In4.Cu" "In6.Cu")
		(teardrops
			(best_length_ratio 0.4)
			(max_length 1)
			(best_width_ratio 0.9)
			(max_width 2)
			(curved_edges yes)
			(filter_ratio 0.9)
			(enabled yes)
			(allow_two_segments yes)
			(prefer_zone_connections yes)
		)
		(net 1)
	)
	(via
		(at 177.18 105.36)
		(size 0.45)
		(drill 0.1)
		(layers "F.Cu" "B.Cu")
		(remove_unused_layers yes)
		(keep_end_layers yes)
		(zone_layer_connections "In1.Cu" "In4.Cu" "In6.Cu")
		(teardrops
			(best_length_ratio 0.4)
			(max_length 1)
			(best_width_ratio 0.9)
			(max_width 2)
			(curved_edges yes)
			(filter_ratio 0.9)
			(enabled yes)
			(allow_two_segments yes)
			(prefer_zone_connections yes)
		)
		(net 1)
	)
	(via
		(at 109.757 77.256)
		(size 0.45)
		(drill 0.1)
		(layers "F.Cu" "B.Cu")
		(remove_unused_layers yes)
		(keep_end_layers yes)
		(zone_layer_connections "In1.Cu" "In4.Cu" "In6.Cu")
		(teardrops
			(best_length_ratio 0.4)
			(max_length 1)
			(best_width_ratio 0.9)
			(max_width 2)
			(curved_edges yes)
			(filter_ratio 0.9)
			(enabled yes)
			(allow_two_segments yes)
			(prefer_zone_connections yes)
		)
		(net 1)
	)
	(via
		(at 132.95 90.31)
		(size 0.45)
		(drill 0.1)
		(layers "F.Cu" "B.Cu")
		(remove_unused_layers yes)
		(keep_end_layers yes)
		(zone_layer_connections "In1.Cu" "In4.Cu" "In6.Cu")
		(teardrops
			(best_length_ratio 0.4)
			(max_length 1)
			(best_width_ratio 0.9)
			(max_width 2)
			(curved_edges yes)
			(filter_ratio 0.9)
			(enabled yes)
			(allow_two_segments yes)
			(prefer_zone_connections yes)
		)
		(net 1)
	)
	(via
		(at 132.95 159.81)
		(size 0.45)
		(drill 0.1)
		(layers "F.Cu" "B.Cu")
		(remove_unused_layers yes)
		(keep_end_layers yes)
		(zone_layer_connections "In1.Cu" "In4.Cu" "In6.Cu")
		(teardrops
			(best_length_ratio 0.4)
			(max_length 1)
			(best_width_ratio 0.9)
			(max_width 2)
			(curved_edges yes)
			(filter_ratio 0.9)
			(enabled yes)
			(allow_two_segments yes)
			(prefer_zone_connections yes)
		)
		(net 1)
	)
	(via
		(at 99.6 83.81)
		(size 0.45)
		(drill 0.1)
		(layers "F.Cu" "B.Cu")
		(remove_unused_layers yes)
		(keep_end_layers yes)
		(zone_layer_connections "In1.Cu" "In4.Cu" "In6.Cu")
		(teardrops
			(best_length_ratio 0.4)
			(max_length 1)
			(best_width_ratio 0.9)
			(max_width 2)
			(curved_edges yes)
			(filter_ratio 0.9)
			(enabled yes)
			(allow_two_segments yes)
			(prefer_zone_connections yes)
		)
		(net 1)
	)
	(via
		(at 231.45 87.81)
		(size 0.45)
		(drill 0.1)
		(layers "F.Cu" "B.Cu")
		(remove_unused_layers yes)
		(keep_end_layers yes)
		(free yes)
		(zone_layer_connections "In1.Cu" "In4.Cu" "In6.Cu")
		(teardrops
			(best_length_ratio 0.4)
			(max_length 1)
			(best_width_ratio 0.9)
			(max_width 2)
			(curved_edges yes)
			(filter_ratio 0.9)
			(enabled yes)
			(allow_two_segments yes)
			(prefer_zone_connections yes)
		)
		(net 1)
	)
	(via
		(at 98.45 98.81)
		(size 0.45)
		(drill 0.1)
		(layers "F.Cu" "B.Cu")
		(remove_unused_layers yes)
		(keep_end_layers yes)
		(zone_layer_connections "In1.Cu" "In4.Cu" "In6.Cu")
		(teardrops
			(best_length_ratio 0.4)
			(max_length 1)
			(best_width_ratio 0.9)
			(max_width 2)
			(curved_edges yes)
			(filter_ratio 0.9)
			(enabled yes)
			(allow_two_segments yes)
			(prefer_zone_connections yes)
		)
		(net 1)
	)
	(via
		(at 300.55 103.29)
		(size 0.45)
		(drill 0.1)
		(layers "F.Cu" "B.Cu")
		(remove_unused_layers yes)
		(keep_end_layers yes)
		(zone_layer_connections "In1.Cu" "In4.Cu" "In6.Cu")
		(teardrops
			(best_length_ratio 0.4)
			(max_length 1)
			(best_width_ratio 0.9)
			(max_width 2)
			(curved_edges yes)
			(filter_ratio 0.9)
			(enabled yes)
			(allow_two_segments yes)
			(prefer_zone_connections yes)
		)
		(net 1)
	)
	(via
		(at 230.05 146.6)
		(size 0.45)
		(drill 0.1)
		(layers "F.Cu" "B.Cu")
		(teardrops
			(best_length_ratio 0.4)
			(max_length 1)
			(best_width_ratio 0.9)
			(max_width 2)
			(curved_edges yes)
			(filter_ratio 0.9)
			(enabled yes)
			(allow_two_segments yes)
			(prefer_zone_connections yes)
		)
		(net 1)
	)
	(via
		(at 292.95 108.31)
		(size 0.45)
		(drill 0.1)
		(layers "F.Cu" "B.Cu")
		(remove_unused_layers yes)
		(keep_end_layers yes)
		(zone_layer_connections "In1.Cu" "In4.Cu" "In6.Cu")
		(teardrops
			(best_length_ratio 0.4)
			(max_length 1)
			(best_width_ratio 0.9)
			(max_width 2)
			(curved_edges yes)
			(filter_ratio 0.9)
			(enabled yes)
			(allow_two_segments yes)
			(prefer_zone_connections yes)
		)
		(net 1)
	)
	(via
		(at 190.95 80.81)
		(size 0.45)
		(drill 0.1)
		(layers "F.Cu" "B.Cu")
		(remove_unused_layers yes)
		(keep_end_layers yes)
		(zone_layer_connections "In1.Cu" "In4.Cu" "In6.Cu")
		(teardrops
			(best_length_ratio 0.4)
			(max_length 1)
			(best_width_ratio 0.9)
			(max_width 2)
			(curved_edges yes)
			(filter_ratio 0.9)
			(enabled yes)
			(allow_two_segments yes)
			(prefer_zone_connections yes)
		)
		(net 1)
	)
	(via
		(at 241.2 159)
		(size 0.45)
		(drill 0.1)
		(layers "F.Cu" "B.Cu")
		(teardrops
			(best_length_ratio 0.4)
			(max_length 1)
			(best_width_ratio 0.9)
			(max_width 2)
			(curved_edges yes)
			(filter_ratio 0.9)
			(enabled yes)
			(allow_two_segments yes)
			(prefer_zone_connections yes)
		)
		(net 1)
	)
	(via
		(at 300.55 137.89)
		(size 0.45)
		(drill 0.1)
		(layers "F.Cu" "B.Cu")
		(remove_unused_layers yes)
		(keep_end_layers yes)
		(zone_layer_connections "In1.Cu" "In4.Cu" "In6.Cu")
		(teardrops
			(best_length_ratio 0.4)
			(max_length 1)
			(best_width_ratio 0.9)
			(max_width 2)
			(curved_edges yes)
			(filter_ratio 0.9)
			(enabled yes)
			(allow_two_segments yes)
			(prefer_zone_connections yes)
		)
		(net 1)
	)
	(via
		(at 315.4645 117.446501)
		(size 0.45)
		(drill 0.1)
		(layers "F.Cu" "B.Cu")
		(remove_unused_layers yes)
		(keep_end_layers yes)
		(free yes)
		(zone_layer_connections "In1.Cu" "In4.Cu" "In6.Cu")
		(teardrops
			(best_length_ratio 0.4)
			(max_length 1)
			(best_width_ratio 0.9)
			(max_width 2)
			(curved_edges yes)
			(filter_ratio 0.9)
			(enabled yes)
			(allow_two_segments yes)
			(prefer_zone_connections yes)
		)
		(net 1)
	)
	(via
		(at 137.45 91.81)
		(size 0.45)
		(drill 0.1)
		(layers "F.Cu" "B.Cu")
		(remove_unused_layers yes)
		(keep_end_layers yes)
		(free yes)
		(zone_layer_connections "In1.Cu" "In4.Cu" "In6.Cu")
		(teardrops
			(best_length_ratio 0.4)
			(max_length 1)
			(best_width_ratio 0.9)
			(max_width 2)
			(curved_edges yes)
			(filter_ratio 0.9)
			(enabled yes)
			(allow_two_segments yes)
			(prefer_zone_connections yes)
		)
		(net 1)
	)
	(via
		(at 95.45 72.81)
		(size 0.45)
		(drill 0.1)
		(layers "F.Cu" "B.Cu")
		(remove_unused_layers yes)
		(keep_end_layers yes)
		(zone_layer_connections "In1.Cu" "In4.Cu" "In6.Cu")
		(teardrops
			(best_length_ratio 0.4)
			(max_length 1)
			(best_width_ratio 0.9)
			(max_width 2)
			(curved_edges yes)
			(filter_ratio 0.9)
			(enabled yes)
			(allow_two_segments yes)
			(prefer_zone_connections yes)
		)
		(net 1)
	)
	(via
		(at 136.29 131.86)
		(size 0.45)
		(drill 0.1)
		(layers "F.Cu" "B.Cu")
		(remove_unused_layers yes)
		(keep_end_layers yes)
		(zone_layer_connections "In1.Cu" "In4.Cu" "In6.Cu")
		(teardrops
			(best_length_ratio 0.4)
			(max_length 1)
			(best_width_ratio 0.9)
			(max_width 2)
			(curved_edges yes)
			(filter_ratio 0.9)
			(enabled yes)
			(allow_two_segments yes)
			(prefer_zone_connections yes)
		)
		(net 1)
	)
	(via
		(at 95.45 134.81)
		(size 0.45)
		(drill 0.1)
		(layers "F.Cu" "B.Cu")
		(remove_unused_layers yes)
		(keep_end_layers yes)
		(zone_layer_connections "In1.Cu" "In4.Cu" "In6.Cu")
		(teardrops
			(best_length_ratio 0.4)
			(max_length 1)
			(best_width_ratio 0.9)
			(max_width 2)
			(curved_edges yes)
			(filter_ratio 0.9)
			(enabled yes)
			(allow_two_segments yes)
			(prefer_zone_connections yes)
		)
		(net 1)
	)
	(via
		(at 300.55 94.83)
		(size 0.45)
		(drill 0.1)
		(layers "F.Cu" "B.Cu")
		(remove_unused_layers yes)
		(keep_end_layers yes)
		(zone_layer_connections "In1.Cu" "In4.Cu" "In6.Cu")
		(teardrops
			(best_length_ratio 0.4)
			(max_length 1)
			(best_width_ratio 0.9)
			(max_width 2)
			(curved_edges yes)
			(filter_ratio 0.9)
			(enabled yes)
			(allow_two_segments yes)
			(prefer_zone_connections yes)
		)
		(net 1)
	)
	(via
		(at 294.95 113.31)
		(size 0.45)
		(drill 0.1)
		(layers "F.Cu" "B.Cu")
		(remove_unused_layers yes)
		(keep_end_layers yes)
		(zone_layer_connections "In1.Cu" "In4.Cu" "In6.Cu")
		(teardrops
			(best_length_ratio 0.4)
			(max_length 1)
			(best_width_ratio 0.9)
			(max_width 2)
			(curved_edges yes)
			(filter_ratio 0.9)
			(enabled yes)
			(allow_two_segments yes)
			(prefer_zone_connections yes)
		)
		(net 1)
	)
	(via
		(at 214.45 73.21)
		(size 0.45)
		(drill 0.1)
		(layers "F.Cu" "B.Cu")
		(remove_unused_layers yes)
		(keep_end_layers yes)
		(zone_layer_connections "In1.Cu" "In4.Cu" "In6.Cu")
		(teardrops
			(best_length_ratio 0.4)
			(max_length 1)
			(best_width_ratio 0.9)
			(max_width 2)
			(curved_edges yes)
			(filter_ratio 0.9)
			(enabled yes)
			(allow_two_segments yes)
			(prefer_zone_connections yes)
		)
		(net 1)
	)
	(via
		(at 192.3 160)
		(size 0.45)
		(drill 0.1)
		(layers "F.Cu" "B.Cu")
		(teardrops
			(best_length_ratio 0.4)
			(max_length 1)
			(best_width_ratio 0.9)
			(max_width 2)
			(curved_edges yes)
			(filter_ratio 0.9)
			(enabled yes)
			(allow_two_segments yes)
			(prefer_zone_connections yes)
		)
		(net 1)
	)
	(via
		(at 103.45 124.81)
		(size 0.45)
		(drill 0.1)
		(layers "F.Cu" "B.Cu")
		(remove_unused_layers yes)
		(keep_end_layers yes)
		(zone_layer_connections "In1.Cu" "In4.Cu" "In6.Cu")
		(teardrops
			(best_length_ratio 0.4)
			(max_length 1)
			(best_width_ratio 0.9)
			(max_width 2)
			(curved_edges yes)
			(filter_ratio 0.9)
			(enabled yes)
			(allow_two_segments yes)
			(prefer_zone_connections yes)
		)
		(net 1)
	)
	(via
		(at 318.464501 96.6365)
		(size 0.45)
		(drill 0.1)
		(layers "F.Cu" "B.Cu")
		(remove_unused_layers yes)
		(keep_end_layers yes)
		(zone_layer_connections "In1.Cu" "In4.Cu" "In6.Cu")
		(teardrops
			(best_length_ratio 0.4)
			(max_length 1)
			(best_width_ratio 0.9)
			(max_width 2)
			(curved_edges yes)
			(filter_ratio 0.9)
			(enabled yes)
			(allow_two_segments yes)
			(prefer_zone_connections yes)
		)
		(net 1)
	)
	(via
		(at 318.95 73.81)
		(size 0.45)
		(drill 0.1)
		(layers "F.Cu" "B.Cu")
		(remove_unused_layers yes)
		(keep_end_layers yes)
		(zone_layer_connections "In1.Cu" "In4.Cu" "In6.Cu")
		(teardrops
			(best_length_ratio 0.4)
			(max_length 1)
			(best_width_ratio 0.9)
			(max_width 2)
			(curved_edges yes)
			(filter_ratio 0.9)
			(enabled yes)
			(allow_two_segments yes)
			(prefer_zone_connections yes)
		)
		(net 1)
	)
	(via
		(at 140.95 156.31)
		(size 0.45)
		(drill 0.1)
		(layers "F.Cu" "B.Cu")
		(remove_unused_layers yes)
		(keep_end_layers yes)
		(zone_layer_connections "In1.Cu" "In4.Cu" "In6.Cu")
		(teardrops
			(best_length_ratio 0.4)
			(max_length 1)
			(best_width_ratio 0.9)
			(max_width 2)
			(curved_edges yes)
			(filter_ratio 0.9)
			(enabled yes)
			(allow_two_segments yes)
			(prefer_zone_connections yes)
		)
		(net 1)
	)
	(via
		(at 156.584421 74.842914)
		(size 0.45)
		(drill 0.1)
		(layers "F.Cu" "B.Cu")
		(remove_unused_layers yes)
		(keep_end_layers yes)
		(zone_layer_connections "In1.Cu" "In4.Cu" "In6.Cu")
		(teardrops
			(best_length_ratio 0.4)
			(max_length 1)
			(best_width_ratio 0.9)
			(max_width 2)
			(curved_edges yes)
			(filter_ratio 0.9)
			(enabled yes)
			(allow_two_segments yes)
			(prefer_zone_connections yes)
		)
		(net 1)
	)
	(via
		(at 121.45 165.81)
		(size 0.45)
		(drill 0.1)
		(layers "F.Cu" "B.Cu")
		(remove_unused_layers yes)
		(keep_end_layers yes)
		(zone_layer_connections "In1.Cu" "In4.Cu" "In6.Cu")
		(teardrops
			(best_length_ratio 0.4)
			(max_length 1)
			(best_width_ratio 0.9)
			(max_width 2)
			(curved_edges yes)
			(filter_ratio 0.9)
			(enabled yes)
			(allow_two_segments yes)
			(prefer_zone_connections yes)
		)
		(net 1)
	)
	(via
		(at 317.45 87.81)
		(size 0.45)
		(drill 0.1)
		(layers "F.Cu" "B.Cu")
		(remove_unused_layers yes)
		(keep_end_layers yes)
		(zone_layer_connections "In1.Cu" "In4.Cu" "In6.Cu")
		(teardrops
			(best_length_ratio 0.4)
			(max_length 1)
			(best_width_ratio 0.9)
			(max_width 2)
			(curved_edges yes)
			(filter_ratio 0.9)
			(enabled yes)
			(allow_two_segments yes)
			(prefer_zone_connections yes)
		)
		(net 1)
	)
	(via
		(at 207 127.5)
		(size 0.45)
		(drill 0.1)
		(layers "F.Cu" "B.Cu")
		(remove_unused_layers yes)
		(keep_end_layers yes)
		(zone_layer_connections "In1.Cu" "In4.Cu" "In6.Cu")
		(teardrops
			(best_length_ratio 0.4)
			(max_length 1)
			(best_width_ratio 0.9)
			(max_width 2)
			(curved_edges yes)
			(filter_ratio 0.9)
			(enabled yes)
			(allow_two_segments yes)
			(prefer_zone_connections yes)
		)
		(net 1)
	)
	(via
		(at 156.95 92.31)
		(size 0.45)
		(drill 0.1)
		(layers "F.Cu" "B.Cu")
		(remove_unused_layers yes)
		(keep_end_layers yes)
		(zone_layer_connections "In1.Cu" "In4.Cu" "In6.Cu")
		(teardrops
			(best_length_ratio 0.4)
			(max_length 1)
			(best_width_ratio 0.9)
			(max_width 2)
			(curved_edges yes)
			(filter_ratio 0.9)
			(enabled yes)
			(allow_two_segments yes)
			(prefer_zone_connections yes)
		)
		(net 1)
	)
	(via
		(at 259.074 132.61)
		(size 0.45)
		(drill 0.1)
		(layers "F.Cu" "B.Cu")
		(remove_unused_layers yes)
		(keep_end_layers yes)
		(zone_layer_connections "In1.Cu" "In4.Cu" "In6.Cu")
		(teardrops
			(best_length_ratio 0.4)
			(max_length 1)
			(best_width_ratio 0.9)
			(max_width 2)
			(curved_edges yes)
			(filter_ratio 0.9)
			(enabled yes)
			(allow_two_segments yes)
			(prefer_zone_connections yes)
		)
		(net 1)
	)
	(via
		(at 290.95 128.31)
		(size 0.45)
		(drill 0.1)
		(layers "F.Cu" "B.Cu")
		(remove_unused_layers yes)
		(keep_end_layers yes)
		(zone_layer_connections "In1.Cu" "In4.Cu" "In6.Cu")
		(teardrops
			(best_length_ratio 0.4)
			(max_length 1)
			(best_width_ratio 0.9)
			(max_width 2)
			(curved_edges yes)
			(filter_ratio 0.9)
			(enabled yes)
			(allow_two_segments yes)
			(prefer_zone_connections yes)
		)
		(net 1)
	)
	(via
		(at 247.45 115.81)
		(size 0.45)
		(drill 0.1)
		(layers "F.Cu" "B.Cu")
		(remove_unused_layers yes)
		(keep_end_layers yes)
		(zone_layer_connections "In1.Cu" "In4.Cu" "In6.Cu")
		(teardrops
			(best_length_ratio 0.4)
			(max_length 1)
			(best_width_ratio 0.9)
			(max_width 2)
			(curved_edges yes)
			(filter_ratio 0.9)
			(enabled yes)
			(allow_two_segments yes)
			(prefer_zone_connections yes)
		)
		(net 1)
	)
	(via
		(at 317.45 69.31)
		(size 0.45)
		(drill 0.1)
		(layers "F.Cu" "B.Cu")
		(remove_unused_layers yes)
		(keep_end_layers yes)
		(zone_layer_connections "In1.Cu" "In4.Cu" "In6.Cu")
		(teardrops
			(best_length_ratio 0.4)
			(max_length 1)
			(best_width_ratio 0.9)
			(max_width 2)
			(curved_edges yes)
			(filter_ratio 0.9)
			(enabled yes)
			(allow_two_segments yes)
			(prefer_zone_connections yes)
		)
		(net 1)
	)
	(via
		(at 95.45 165.31)
		(size 0.45)
		(drill 0.1)
		(layers "F.Cu" "B.Cu")
		(remove_unused_layers yes)
		(keep_end_layers yes)
		(zone_layer_connections "In1.Cu" "In4.Cu" "In6.Cu")
		(teardrops
			(best_length_ratio 0.4)
			(max_length 1)
			(best_width_ratio 0.9)
			(max_width 2)
			(curved_edges yes)
			(filter_ratio 0.9)
			(enabled yes)
			(allow_two_segments yes)
			(prefer_zone_connections yes)
		)
		(net 1)
	)
	(via
		(at 101.35 165.1)
		(size 0.45)
		(drill 0.1)
		(layers "F.Cu" "B.Cu")
		(remove_unused_layers yes)
		(keep_end_layers yes)
		(zone_layer_connections "In1.Cu" "In4.Cu" "In6.Cu")
		(teardrops
			(best_length_ratio 0.4)
			(max_length 1)
			(best_width_ratio 0.9)
			(max_width 2)
			(curved_edges yes)
			(filter_ratio 0.9)
			(enabled yes)
			(allow_two_segments yes)
			(prefer_zone_connections yes)
		)
		(net 1)
	)
	(via
		(at 123.88 95.86)
		(size 0.45)
		(drill 0.1)
		(layers "F.Cu" "B.Cu")
		(remove_unused_layers yes)
		(keep_end_layers yes)
		(zone_layer_connections "In1.Cu" "In4.Cu" "In6.Cu")
		(teardrops
			(best_length_ratio 0.4)
			(max_length 1)
			(best_width_ratio 0.9)
			(max_width 2)
			(curved_edges yes)
			(filter_ratio 0.9)
			(enabled yes)
			(allow_two_segments yes)
			(prefer_zone_connections yes)
		)
		(net 1)
	)
	(via
		(at 302.950001 170.81)
		(size 0.45)
		(drill 0.1)
		(layers "F.Cu" "B.Cu")
		(remove_unused_layers yes)
		(keep_end_layers yes)
		(zone_layer_connections "In1.Cu" "In4.Cu" "In6.Cu")
		(teardrops
			(best_length_ratio 0.4)
			(max_length 1)
			(best_width_ratio 0.9)
			(max_width 2)
			(curved_edges yes)
			(filter_ratio 0.9)
			(enabled yes)
			(allow_two_segments yes)
			(prefer_zone_connections yes)
		)
		(net 1)
	)
	(via
		(at 173.205 102.275)
		(size 0.45)
		(drill 0.1)
		(layers "F.Cu" "B.Cu")
		(remove_unused_layers yes)
		(keep_end_layers yes)
		(zone_layer_connections "In1.Cu" "In4.Cu" "In6.Cu")
		(teardrops
			(best_length_ratio 0.4)
			(max_length 1)
			(best_width_ratio 0.9)
			(max_width 2)
			(curved_edges yes)
			(filter_ratio 0.9)
			(enabled yes)
			(allow_two_segments yes)
			(prefer_zone_connections yes)
		)
		(net 1)
	)
	(via
		(at 183.45 68.81)
		(size 0.45)
		(drill 0.1)
		(layers "F.Cu" "B.Cu")
		(remove_unused_layers yes)
		(keep_end_layers yes)
		(zone_layer_connections "In1.Cu" "In4.Cu" "In6.Cu")
		(teardrops
			(best_length_ratio 0.4)
			(max_length 1)
			(best_width_ratio 0.9)
			(max_width 2)
			(curved_edges yes)
			(filter_ratio 0.9)
			(enabled yes)
			(allow_two_segments yes)
			(prefer_zone_connections yes)
		)
		(net 1)
	)
	(via
		(at 258.39 90.849999)
		(size 0.45)
		(drill 0.1)
		(layers "F.Cu" "B.Cu")
		(remove_unused_layers yes)
		(keep_end_layers yes)
		(zone_layer_connections "In1.Cu" "In4.Cu" "In6.Cu")
		(teardrops
			(best_length_ratio 0.4)
			(max_length 1)
			(best_width_ratio 0.9)
			(max_width 2)
			(curved_edges yes)
			(filter_ratio 0.9)
			(enabled yes)
			(allow_two_segments yes)
			(prefer_zone_connections yes)
		)
		(net 1)
	)
	(via
		(at 302.95 70.31)
		(size 0.45)
		(drill 0.1)
		(layers "F.Cu" "B.Cu")
		(remove_unused_layers yes)
		(keep_end_layers yes)
		(zone_layer_connections "In1.Cu" "In4.Cu" "In6.Cu")
		(teardrops
			(best_length_ratio 0.4)
			(max_length 1)
			(best_width_ratio 0.9)
			(max_width 2)
			(curved_edges yes)
			(filter_ratio 0.9)
			(enabled yes)
			(allow_two_segments yes)
			(prefer_zone_connections yes)
		)
		(net 1)
	)
	(via
		(at 286.2 74.96)
		(size 0.45)
		(drill 0.1)
		(layers "F.Cu" "B.Cu")
		(remove_unused_layers yes)
		(keep_end_layers yes)
		(free yes)
		(zone_layer_connections "In1.Cu" "In4.Cu" "In6.Cu")
		(teardrops
			(best_length_ratio 0.4)
			(max_length 1)
			(best_width_ratio 0.9)
			(max_width 2)
			(curved_edges yes)
			(filter_ratio 0.9)
			(enabled yes)
			(allow_two_segments yes)
			(prefer_zone_connections yes)
		)
		(net 1)
	)
	(via
		(at 95.45 169.31)
		(size 0.45)
		(drill 0.1)
		(layers "F.Cu" "B.Cu")
		(remove_unused_layers yes)
		(keep_end_layers yes)
		(zone_layer_connections "In1.Cu" "In4.Cu" "In6.Cu")
		(teardrops
			(best_length_ratio 0.4)
			(max_length 1)
			(best_width_ratio 0.9)
			(max_width 2)
			(curved_edges yes)
			(filter_ratio 0.9)
			(enabled yes)
			(allow_two_segments yes)
			(prefer_zone_connections yes)
		)
		(net 1)
	)
	(via
		(at 132.29 135.86)
		(size 0.45)
		(drill 0.1)
		(layers "F.Cu" "B.Cu")
		(remove_unused_layers yes)
		(keep_end_layers yes)
		(zone_layer_connections "In1.Cu" "In4.Cu" "In6.Cu")
		(teardrops
			(best_length_ratio 0.4)
			(max_length 1)
			(best_width_ratio 0.9)
			(max_width 2)
			(curved_edges yes)
			(filter_ratio 0.9)
			(enabled yes)
			(allow_two_segments yes)
			(prefer_zone_connections yes)
		)
		(net 1)
	)
	(via
		(at 301.45 88.31)
		(size 0.45)
		(drill 0.1)
		(layers "F.Cu" "B.Cu")
		(remove_unused_layers yes)
		(keep_end_layers yes)
		(zone_layer_connections "In1.Cu" "In4.Cu" "In6.Cu")
		(teardrops
			(best_length_ratio 0.4)
			(max_length 1)
			(best_width_ratio 0.9)
			(max_width 2)
			(curved_edges yes)
			(filter_ratio 0.9)
			(enabled yes)
			(allow_two_segments yes)
			(prefer_zone_connections yes)
		)
		(net 1)
	)
	(via
		(at 183.64 90.69)
		(size 0.45)
		(drill 0.1)
		(layers "F.Cu" "B.Cu")
		(remove_unused_layers yes)
		(keep_end_layers yes)
		(zone_layer_connections "In1.Cu" "In4.Cu" "In6.Cu")
		(teardrops
			(best_length_ratio 0.4)
			(max_length 1)
			(best_width_ratio 0.9)
			(max_width 2)
			(curved_edges yes)
			(filter_ratio 0.9)
			(enabled yes)
			(allow_two_segments yes)
			(prefer_zone_connections yes)
		)
		(net 1)
	)
	(via
		(at 113.8 87.76)
		(size 0.45)
		(drill 0.1)
		(layers "F.Cu" "B.Cu")
		(remove_unused_layers yes)
		(keep_end_layers yes)
		(zone_layer_connections "In1.Cu" "In4.Cu" "In6.Cu")
		(teardrops
			(best_length_ratio 0.4)
			(max_length 1)
			(best_width_ratio 0.9)
			(max_width 2)
			(curved_edges yes)
			(filter_ratio 0.9)
			(enabled yes)
			(allow_two_segments yes)
			(prefer_zone_connections yes)
		)
		(net 1)
	)
	(via
		(at 127.45 159.81)
		(size 0.45)
		(drill 0.1)
		(layers "F.Cu" "B.Cu")
		(remove_unused_layers yes)
		(keep_end_layers yes)
		(zone_layer_connections "In1.Cu" "In4.Cu" "In6.Cu")
		(teardrops
			(best_length_ratio 0.4)
			(max_length 1)
			(best_width_ratio 0.9)
			(max_width 2)
			(curved_edges yes)
			(filter_ratio 0.9)
			(enabled yes)
			(allow_two_segments yes)
			(prefer_zone_connections yes)
		)
		(net 1)
	)
	(via
		(at 181.025 149.975)
		(size 0.45)
		(drill 0.1)
		(layers "F.Cu" "B.Cu")
		(teardrops
			(best_length_ratio 0.4)
			(max_length 1)
			(best_width_ratio 0.9)
			(max_width 2)
			(curved_edges yes)
			(filter_ratio 0.9)
			(enabled yes)
			(allow_two_segments yes)
			(prefer_zone_connections yes)
		)
		(net 1)
	)
	(via
		(at 145.45 142.86)
		(size 0.45)
		(drill 0.1)
		(layers "F.Cu" "B.Cu")
		(remove_unused_layers yes)
		(keep_end_layers yes)
		(zone_layer_connections "In1.Cu" "In4.Cu" "In6.Cu")
		(teardrops
			(best_length_ratio 0.4)
			(max_length 1)
			(best_width_ratio 0.9)
			(max_width 2)
			(curved_edges yes)
			(filter_ratio 0.9)
			(enabled yes)
			(allow_two_segments yes)
			(prefer_zone_connections yes)
		)
		(net 1)
	)
	(via
		(at 97.45 170.81)
		(size 0.45)
		(drill 0.1)
		(layers "F.Cu" "B.Cu")
		(remove_unused_layers yes)
		(keep_end_layers yes)
		(zone_layer_connections "In1.Cu" "In4.Cu" "In6.Cu")
		(teardrops
			(best_length_ratio 0.4)
			(max_length 1)
			(best_width_ratio 0.9)
			(max_width 2)
			(curved_edges yes)
			(filter_ratio 0.9)
			(enabled yes)
			(allow_two_segments yes)
			(prefer_zone_connections yes)
		)
		(net 1)
	)
	(via
		(at 244.949999 170.81)
		(size 0.45)
		(drill 0.1)
		(layers "F.Cu" "B.Cu")
		(remove_unused_layers yes)
		(keep_end_layers yes)
		(zone_layer_connections "In1.Cu" "In4.Cu" "In6.Cu")
		(teardrops
			(best_length_ratio 0.4)
			(max_length 1)
			(best_width_ratio 0.9)
			(max_width 2)
			(curved_edges yes)
			(filter_ratio 0.9)
			(enabled yes)
			(allow_two_segments yes)
			(prefer_zone_connections yes)
		)
		(net 1)
	)
	(via
		(at 150.45 135.86)
		(size 0.45)
		(drill 0.1)
		(layers "F.Cu" "B.Cu")
		(remove_unused_layers yes)
		(keep_end_layers yes)
		(zone_layer_connections "In1.Cu" "In4.Cu" "In6.Cu")
		(teardrops
			(best_length_ratio 0.4)
			(max_length 1)
			(best_width_ratio 0.9)
			(max_width 2)
			(curved_edges yes)
			(filter_ratio 0.9)
			(enabled yes)
			(allow_two_segments yes)
			(prefer_zone_connections yes)
		)
		(net 1)
	)
	(via
		(at 95.45 84.81)
		(size 0.45)
		(drill 0.1)
		(layers "F.Cu" "B.Cu")
		(remove_unused_layers yes)
		(keep_end_layers yes)
		(zone_layer_connections "In1.Cu" "In4.Cu" "In6.Cu")
		(teardrops
			(best_length_ratio 0.4)
			(max_length 1)
			(best_width_ratio 0.9)
			(max_width 2)
			(curved_edges yes)
			(filter_ratio 0.9)
			(enabled yes)
			(allow_two_segments yes)
			(prefer_zone_connections yes)
		)
		(net 1)
	)
	(via
		(at 106.95 76.31)
		(size 0.45)
		(drill 0.1)
		(layers "F.Cu" "B.Cu")
		(remove_unused_layers yes)
		(keep_end_layers yes)
		(zone_layer_connections "In1.Cu" "In4.Cu" "In6.Cu")
		(teardrops
			(best_length_ratio 0.4)
			(max_length 1)
			(best_width_ratio 0.9)
			(max_width 2)
			(curved_edges yes)
			(filter_ratio 0.9)
			(enabled yes)
			(allow_two_segments yes)
			(prefer_zone_connections yes)
		)
		(net 1)
	)
	(via
		(at 220.21 122.9)
		(size 0.45)
		(drill 0.1)
		(layers "F.Cu" "B.Cu")
		(remove_unused_layers yes)
		(keep_end_layers yes)
		(zone_layer_connections "In1.Cu" "In4.Cu" "In6.Cu")
		(teardrops
			(best_length_ratio 0.4)
			(max_length 1)
			(best_width_ratio 0.9)
			(max_width 2)
			(curved_edges yes)
			(filter_ratio 0.9)
			(enabled yes)
			(allow_two_segments yes)
			(prefer_zone_connections yes)
		)
		(net 1)
	)
	(via
		(at 217.2 130.25)
		(size 0.45)
		(drill 0.1)
		(layers "F.Cu" "B.Cu")
		(remove_unused_layers yes)
		(keep_end_layers yes)
		(zone_layer_connections "In1.Cu" "In4.Cu" "In6.Cu")
		(teardrops
			(best_length_ratio 0.4)
			(max_length 1)
			(best_width_ratio 0.9)
			(max_width 2)
			(curved_edges yes)
			(filter_ratio 0.9)
			(enabled yes)
			(allow_two_segments yes)
			(prefer_zone_connections yes)
		)
		(net 1)
	)
	(via
		(at 305.799 74.81)
		(size 0.45)
		(drill 0.1)
		(layers "F.Cu" "B.Cu")
		(remove_unused_layers yes)
		(keep_end_layers yes)
		(zone_layer_connections "In1.Cu" "In4.Cu" "In6.Cu")
		(teardrops
			(best_length_ratio 0.4)
			(max_length 1)
			(best_width_ratio 0.9)
			(max_width 2)
			(curved_edges yes)
			(filter_ratio 0.9)
			(enabled yes)
			(allow_two_segments yes)
			(prefer_zone_connections yes)
		)
		(net 1)
	)
	(via
		(at 177.45 68.81)
		(size 0.45)
		(drill 0.1)
		(layers "F.Cu" "B.Cu")
		(remove_unused_layers yes)
		(keep_end_layers yes)
		(free yes)
		(zone_layer_connections "In1.Cu" "In4.Cu" "In6.Cu")
		(teardrops
			(best_length_ratio 0.4)
			(max_length 1)
			(best_width_ratio 0.9)
			(max_width 2)
			(curved_edges yes)
			(filter_ratio 0.9)
			(enabled yes)
			(allow_two_segments yes)
			(prefer_zone_connections yes)
		)
		(net 1)
	)
	(via
		(at 236.96 155.77)
		(size 0.45)
		(drill 0.1)
		(layers "F.Cu" "B.Cu")
		(teardrops
			(best_length_ratio 0.4)
			(max_length 1)
			(best_width_ratio 0.9)
			(max_width 2)
			(curved_edges yes)
			(filter_ratio 0.9)
			(enabled yes)
			(allow_two_segments yes)
			(prefer_zone_connections yes)
		)
		(net 1)
	)
	(via
		(at 216.45 84.81)
		(size 0.45)
		(drill 0.1)
		(layers "F.Cu" "B.Cu")
		(remove_unused_layers yes)
		(keep_end_layers yes)
		(zone_layer_connections "In1.Cu" "In4.Cu" "In6.Cu")
		(teardrops
			(best_length_ratio 0.4)
			(max_length 1)
			(best_width_ratio 0.9)
			(max_width 2)
			(curved_edges yes)
			(filter_ratio 0.9)
			(enabled yes)
			(allow_two_segments yes)
			(prefer_zone_connections yes)
		)
		(net 1)
	)
	(via
		(at 290.95 141.31)
		(size 0.45)
		(drill 0.1)
		(layers "F.Cu" "B.Cu")
		(remove_unused_layers yes)
		(keep_end_layers yes)
		(zone_layer_connections "In1.Cu" "In4.Cu" "In6.Cu")
		(teardrops
			(best_length_ratio 0.4)
			(max_length 1)
			(best_width_ratio 0.9)
			(max_width 2)
			(curved_edges yes)
			(filter_ratio 0.9)
			(enabled yes)
			(allow_two_segments yes)
			(prefer_zone_connections yes)
		)
		(net 1)
	)
	(via
		(at 212.05 148.65)
		(size 0.45)
		(drill 0.1)
		(layers "F.Cu" "B.Cu")
		(teardrops
			(best_length_ratio 0.4)
			(max_length 1)
			(best_width_ratio 0.9)
			(max_width 2)
			(curved_edges yes)
			(filter_ratio 0.9)
			(enabled yes)
			(allow_two_segments yes)
			(prefer_zone_connections yes)
		)
		(net 1)
	)
	(via
		(at 290.95 170.81)
		(size 0.45)
		(drill 0.1)
		(layers "F.Cu" "B.Cu")
		(remove_unused_layers yes)
		(keep_end_layers yes)
		(zone_layer_connections "In1.Cu" "In4.Cu" "In6.Cu")
		(teardrops
			(best_length_ratio 0.4)
			(max_length 1)
			(best_width_ratio 0.9)
			(max_width 2)
			(curved_edges yes)
			(filter_ratio 0.9)
			(enabled yes)
			(allow_two_segments yes)
			(prefer_zone_connections yes)
		)
		(net 1)
	)
	(via
		(at 172.45 79.31)
		(size 0.45)
		(drill 0.1)
		(layers "F.Cu" "B.Cu")
		(remove_unused_layers yes)
		(keep_end_layers yes)
		(free yes)
		(zone_layer_connections "In1.Cu" "In4.Cu" "In6.Cu")
		(teardrops
			(best_length_ratio 0.4)
			(max_length 1)
			(best_width_ratio 0.9)
			(max_width 2)
			(curved_edges yes)
			(filter_ratio 0.9)
			(enabled yes)
			(allow_two_segments yes)
			(prefer_zone_connections yes)
		)
		(net 1)
	)
	(via
		(at 130.95 154.31)
		(size 0.45)
		(drill 0.1)
		(layers "F.Cu" "B.Cu")
		(remove_unused_layers yes)
		(keep_end_layers yes)
		(zone_layer_connections "In1.Cu" "In4.Cu" "In6.Cu")
		(teardrops
			(best_length_ratio 0.4)
			(max_length 1)
			(best_width_ratio 0.9)
			(max_width 2)
			(curved_edges yes)
			(filter_ratio 0.9)
			(enabled yes)
			(allow_two_segments yes)
			(prefer_zone_connections yes)
		)
		(net 1)
	)
	(via
		(at 312.064501 95.1365)
		(size 0.45)
		(drill 0.1)
		(layers "F.Cu" "B.Cu")
		(remove_unused_layers yes)
		(keep_end_layers yes)
		(zone_layer_connections "In1.Cu" "In4.Cu" "In6.Cu")
		(teardrops
			(best_length_ratio 0.4)
			(max_length 1)
			(best_width_ratio 0.9)
			(max_width 2)
			(curved_edges yes)
			(filter_ratio 0.9)
			(enabled yes)
			(allow_two_segments yes)
			(prefer_zone_connections yes)
		)
		(net 1)
	)
	(via
		(at 271.3 157.5)
		(size 0.45)
		(drill 0.1)
		(layers "F.Cu" "B.Cu")
		(remove_unused_layers yes)
		(keep_end_layers yes)
		(zone_layer_connections "In1.Cu" "In4.Cu" "In6.Cu")
		(teardrops
			(best_length_ratio 0.4)
			(max_length 1)
			(best_width_ratio 0.9)
			(max_width 2)
			(curved_edges yes)
			(filter_ratio 0.9)
			(enabled yes)
			(allow_two_segments yes)
			(prefer_zone_connections yes)
		)
		(net 1)
	)
	(via
		(at 194.55 161.921)
		(size 0.45)
		(drill 0.1)
		(layers "F.Cu" "B.Cu")
		(teardrops
			(best_length_ratio 0.4)
			(max_length 1)
			(best_width_ratio 0.9)
			(max_width 2)
			(curved_edges yes)
			(filter_ratio 0.9)
			(enabled yes)
			(allow_two_segments yes)
			(prefer_zone_connections yes)
		)
		(net 1)
	)
	(via
		(at 210.6 161.8)
		(size 0.45)
		(drill 0.1)
		(layers "F.Cu" "B.Cu")
		(teardrops
			(best_length_ratio 0.4)
			(max_length 1)
			(best_width_ratio 0.9)
			(max_width 2)
			(curved_edges yes)
			(filter_ratio 0.9)
			(enabled yes)
			(allow_two_segments yes)
			(prefer_zone_connections yes)
		)
		(net 1)
	)
	(via
		(at 107.8 157.32)
		(size 0.45)
		(drill 0.1)
		(layers "F.Cu" "B.Cu")
		(remove_unused_layers yes)
		(keep_end_layers yes)
		(zone_layer_connections "In1.Cu" "In4.Cu" "In6.Cu")
		(teardrops
			(best_length_ratio 0.4)
			(max_length 1)
			(best_width_ratio 0.9)
			(max_width 2)
			(curved_edges yes)
			(filter_ratio 0.9)
			(enabled yes)
			(allow_two_segments yes)
			(prefer_zone_connections yes)
		)
		(net 1)
	)
	(via
		(at 201.025 157.95)
		(size 0.45)
		(drill 0.1)
		(layers "F.Cu" "B.Cu")
		(teardrops
			(best_length_ratio 0.4)
			(max_length 1)
			(best_width_ratio 0.9)
			(max_width 2)
			(curved_edges yes)
			(filter_ratio 0.9)
			(enabled yes)
			(allow_two_segments yes)
			(prefer_zone_connections yes)
		)
		(net 1)
	)
	(via
		(at 136.29 142.86)
		(size 0.45)
		(drill 0.1)
		(layers "F.Cu" "B.Cu")
		(remove_unused_layers yes)
		(keep_end_layers yes)
		(zone_layer_connections "In1.Cu" "In4.Cu" "In6.Cu")
		(teardrops
			(best_length_ratio 0.4)
			(max_length 1)
			(best_width_ratio 0.9)
			(max_width 2)
			(curved_edges yes)
			(filter_ratio 0.9)
			(enabled yes)
			(allow_two_segments yes)
			(prefer_zone_connections yes)
		)
		(net 1)
	)
	(via
		(at 125.45 170.81)
		(size 0.45)
		(drill 0.1)
		(layers "F.Cu" "B.Cu")
		(remove_unused_layers yes)
		(keep_end_layers yes)
		(zone_layer_connections "In1.Cu" "In4.Cu" "In6.Cu")
		(teardrops
			(best_length_ratio 0.4)
			(max_length 1)
			(best_width_ratio 0.9)
			(max_width 2)
			(curved_edges yes)
			(filter_ratio 0.9)
			(enabled yes)
			(allow_two_segments yes)
			(prefer_zone_connections yes)
		)
		(net 1)
	)
	(via
		(at 217.5 157.8)
		(size 0.45)
		(drill 0.1)
		(layers "F.Cu" "B.Cu")
		(teardrops
			(best_length_ratio 0.4)
			(max_length 1)
			(best_width_ratio 0.9)
			(max_width 2)
			(curved_edges yes)
			(filter_ratio 0.9)
			(enabled yes)
			(allow_two_segments yes)
			(prefer_zone_connections yes)
		)
		(net 1)
	)
	(via
		(at 247.45 121.81)
		(size 0.45)
		(drill 0.1)
		(layers "F.Cu" "B.Cu")
		(remove_unused_layers yes)
		(keep_end_layers yes)
		(zone_layer_connections "In1.Cu" "In4.Cu" "In6.Cu")
		(teardrops
			(best_length_ratio 0.4)
			(max_length 1)
			(best_width_ratio 0.9)
			(max_width 2)
			(curved_edges yes)
			(filter_ratio 0.9)
			(enabled yes)
			(allow_two_segments yes)
			(prefer_zone_connections yes)
		)
		(net 1)
	)
	(via
		(at 107.45 170.81)
		(size 0.45)
		(drill 0.1)
		(layers "F.Cu" "B.Cu")
		(remove_unused_layers yes)
		(keep_end_layers yes)
		(zone_layer_connections "In1.Cu" "In4.Cu" "In6.Cu")
		(teardrops
			(best_length_ratio 0.4)
			(max_length 1)
			(best_width_ratio 0.9)
			(max_width 2)
			(curved_edges yes)
			(filter_ratio 0.9)
			(enabled yes)
			(allow_two_segments yes)
			(prefer_zone_connections yes)
		)
		(net 1)
	)
	(via
		(at 203.95 85.81)
		(size 0.45)
		(drill 0.1)
		(layers "F.Cu" "B.Cu")
		(remove_unused_layers yes)
		(keep_end_layers yes)
		(zone_layer_connections "In1.Cu" "In4.Cu" "In6.Cu")
		(teardrops
			(best_length_ratio 0.4)
			(max_length 1)
			(best_width_ratio 0.9)
			(max_width 2)
			(curved_edges yes)
			(filter_ratio 0.9)
			(enabled yes)
			(allow_two_segments yes)
			(prefer_zone_connections yes)
		)
		(net 1)
	)
	(via
		(at 287.95 141.31)
		(size 0.45)
		(drill 0.1)
		(layers "F.Cu" "B.Cu")
		(remove_unused_layers yes)
		(keep_end_layers yes)
		(zone_layer_connections "In1.Cu" "In4.Cu" "In6.Cu")
		(teardrops
			(best_length_ratio 0.4)
			(max_length 1)
			(best_width_ratio 0.9)
			(max_width 2)
			(curved_edges yes)
			(filter_ratio 0.9)
			(enabled yes)
			(allow_two_segments yes)
			(prefer_zone_connections yes)
		)
		(net 1)
	)
	(via
		(at 194.45 110.31)
		(size 0.45)
		(drill 0.1)
		(layers "F.Cu" "B.Cu")
		(remove_unused_layers yes)
		(keep_end_layers yes)
		(zone_layer_connections "In1.Cu" "In4.Cu" "In6.Cu")
		(teardrops
			(best_length_ratio 0.4)
			(max_length 1)
			(best_width_ratio 0.9)
			(max_width 2)
			(curved_edges yes)
			(filter_ratio 0.9)
			(enabled yes)
			(allow_two_segments yes)
			(prefer_zone_connections yes)
		)
		(net 1)
	)
	(via
		(at 150.45 90.81)
		(size 0.45)
		(drill 0.1)
		(layers "F.Cu" "B.Cu")
		(remove_unused_layers yes)
		(keep_end_layers yes)
		(zone_layer_connections "In1.Cu" "In4.Cu" "In6.Cu")
		(teardrops
			(best_length_ratio 0.4)
			(max_length 1)
			(best_width_ratio 0.9)
			(max_width 2)
			(curved_edges yes)
			(filter_ratio 0.9)
			(enabled yes)
			(allow_two_segments yes)
			(prefer_zone_connections yes)
		)
		(net 1)
	)
	(via
		(at 118.45 111.31)
		(size 0.45)
		(drill 0.1)
		(layers "F.Cu" "B.Cu")
		(remove_unused_layers yes)
		(keep_end_layers yes)
		(zone_layer_connections "In1.Cu" "In4.Cu" "In6.Cu")
		(teardrops
			(best_length_ratio 0.4)
			(max_length 1)
			(best_width_ratio 0.9)
			(max_width 2)
			(curved_edges yes)
			(filter_ratio 0.9)
			(enabled yes)
			(allow_two_segments yes)
			(prefer_zone_connections yes)
		)
		(net 1)
	)
	(via
		(at 112.95 93.51)
		(size 0.45)
		(drill 0.1)
		(layers "F.Cu" "B.Cu")
		(remove_unused_layers yes)
		(keep_end_layers yes)
		(zone_layer_connections "In1.Cu" "In4.Cu" "In6.Cu")
		(teardrops
			(best_length_ratio 0.4)
			(max_length 1)
			(best_width_ratio 0.9)
			(max_width 2)
			(curved_edges yes)
			(filter_ratio 0.9)
			(enabled yes)
			(allow_two_segments yes)
			(prefer_zone_connections yes)
		)
		(net 1)
	)
	(via
		(at 264.95 170.81)
		(size 0.45)
		(drill 0.1)
		(layers "F.Cu" "B.Cu")
		(remove_unused_layers yes)
		(keep_end_layers yes)
		(zone_layer_connections "In1.Cu" "In4.Cu" "In6.Cu")
		(teardrops
			(best_length_ratio 0.4)
			(max_length 1)
			(best_width_ratio 0.9)
			(max_width 2)
			(curved_edges yes)
			(filter_ratio 0.9)
			(enabled yes)
			(allow_two_segments yes)
			(prefer_zone_connections yes)
		)
		(net 1)
	)
	(via
		(at 152.8255 90.6605)
		(size 0.45)
		(drill 0.1)
		(layers "F.Cu" "B.Cu")
		(remove_unused_layers yes)
		(keep_end_layers yes)
		(zone_layer_connections "In1.Cu" "In4.Cu" "In6.Cu")
		(teardrops
			(best_length_ratio 0.4)
			(max_length 1)
			(best_width_ratio 0.9)
			(max_width 2)
			(curved_edges yes)
			(filter_ratio 0.9)
			(enabled yes)
			(allow_two_segments yes)
			(prefer_zone_connections yes)
		)
		(net 1)
	)
	(via
		(at 112.95 87.76)
		(size 0.45)
		(drill 0.1)
		(layers "F.Cu" "B.Cu")
		(remove_unused_layers yes)
		(keep_end_layers yes)
		(zone_layer_connections "In1.Cu" "In4.Cu" "In6.Cu")
		(teardrops
			(best_length_ratio 0.4)
			(max_length 1)
			(best_width_ratio 0.9)
			(max_width 2)
			(curved_edges yes)
			(filter_ratio 0.9)
			(enabled yes)
			(allow_two_segments yes)
			(prefer_zone_connections yes)
		)
		(net 1)
	)
	(via
		(at 173.2 155.2)
		(size 0.45)
		(drill 0.1)
		(layers "F.Cu" "B.Cu")
		(teardrops
			(best_length_ratio 0.4)
			(max_length 1)
			(best_width_ratio 0.9)
			(max_width 2)
			(curved_edges yes)
			(filter_ratio 0.9)
			(enabled yes)
			(allow_two_segments yes)
			(prefer_zone_connections yes)
		)
		(net 1)
	)
	(via
		(at 276.45 113.81)
		(size 0.45)
		(drill 0.1)
		(layers "F.Cu" "B.Cu")
		(remove_unused_layers yes)
		(keep_end_layers yes)
		(zone_layer_connections "In1.Cu" "In4.Cu" "In6.Cu")
		(teardrops
			(best_length_ratio 0.4)
			(max_length 1)
			(best_width_ratio 0.9)
			(max_width 2)
			(curved_edges yes)
			(filter_ratio 0.9)
			(enabled yes)
			(allow_two_segments yes)
			(prefer_zone_connections yes)
		)
		(net 1)
	)
	(via
		(at 262.45 114.31)
		(size 0.45)
		(drill 0.1)
		(layers "F.Cu" "B.Cu")
		(remove_unused_layers yes)
		(keep_end_layers yes)
		(zone_layer_connections "In1.Cu" "In4.Cu" "In6.Cu")
		(teardrops
			(best_length_ratio 0.4)
			(max_length 1)
			(best_width_ratio 0.9)
			(max_width 2)
			(curved_edges yes)
			(filter_ratio 0.9)
			(enabled yes)
			(allow_two_segments yes)
			(prefer_zone_connections yes)
		)
		(net 1)
	)
	(via
		(at 108.45 167.2)
		(size 0.45)
		(drill 0.1)
		(layers "F.Cu" "B.Cu")
		(remove_unused_layers yes)
		(keep_end_layers yes)
		(free yes)
		(zone_layer_connections "In1.Cu" "In4.Cu" "In6.Cu")
		(teardrops
			(best_length_ratio 0.4)
			(max_length 1)
			(best_width_ratio 0.9)
			(max_width 2)
			(curved_edges yes)
			(filter_ratio 0.9)
			(enabled yes)
			(allow_two_segments yes)
			(prefer_zone_connections yes)
		)
		(net 1)
	)
	(via
		(at 119.45 163.81)
		(size 0.45)
		(drill 0.1)
		(layers "F.Cu" "B.Cu")
		(remove_unused_layers yes)
		(keep_end_layers yes)
		(zone_layer_connections "In1.Cu" "In4.Cu" "In6.Cu")
		(teardrops
			(best_length_ratio 0.4)
			(max_length 1)
			(best_width_ratio 0.9)
			(max_width 2)
			(curved_edges yes)
			(filter_ratio 0.9)
			(enabled yes)
			(allow_two_segments yes)
			(prefer_zone_connections yes)
		)
		(net 1)
	)
	(via
		(at 110.45 79.31)
		(size 0.45)
		(drill 0.1)
		(layers "F.Cu" "B.Cu")
		(remove_unused_layers yes)
		(keep_end_layers yes)
		(zone_layer_connections "In1.Cu" "In4.Cu" "In6.Cu")
		(teardrops
			(best_length_ratio 0.4)
			(max_length 1)
			(best_width_ratio 0.9)
			(max_width 2)
			(curved_edges yes)
			(filter_ratio 0.9)
			(enabled yes)
			(allow_two_segments yes)
			(prefer_zone_connections yes)
		)
		(net 1)
	)
	(via
		(at 292.45 145.81)
		(size 0.45)
		(drill 0.1)
		(layers "F.Cu" "B.Cu")
		(remove_unused_layers yes)
		(keep_end_layers yes)
		(zone_layer_connections "In1.Cu" "In4.Cu" "In6.Cu")
		(teardrops
			(best_length_ratio 0.4)
			(max_length 1)
			(best_width_ratio 0.9)
			(max_width 2)
			(curved_edges yes)
			(filter_ratio 0.9)
			(enabled yes)
			(allow_two_segments yes)
			(prefer_zone_connections yes)
		)
		(net 1)
	)
	(via
		(at 274.95 170.81)
		(size 0.45)
		(drill 0.1)
		(layers "F.Cu" "B.Cu")
		(remove_unused_layers yes)
		(keep_end_layers yes)
		(zone_layer_connections "In1.Cu" "In4.Cu" "In6.Cu")
		(teardrops
			(best_length_ratio 0.4)
			(max_length 1)
			(best_width_ratio 0.9)
			(max_width 2)
			(curved_edges yes)
			(filter_ratio 0.9)
			(enabled yes)
			(allow_two_segments yes)
			(prefer_zone_connections yes)
		)
		(net 1)
	)
	(via
		(at 165.45 71.81)
		(size 0.45)
		(drill 0.1)
		(layers "F.Cu" "B.Cu")
		(remove_unused_layers yes)
		(keep_end_layers yes)
		(zone_layer_connections "In1.Cu" "In4.Cu" "In6.Cu")
		(teardrops
			(best_length_ratio 0.4)
			(max_length 1)
			(best_width_ratio 0.9)
			(max_width 2)
			(curved_edges yes)
			(filter_ratio 0.9)
			(enabled yes)
			(allow_two_segments yes)
			(prefer_zone_connections yes)
		)
		(net 1)
	)
	(via
		(at 305.95 92.81)
		(size 0.45)
		(drill 0.1)
		(layers "F.Cu" "B.Cu")
		(remove_unused_layers yes)
		(keep_end_layers yes)
		(zone_layer_connections "In1.Cu" "In4.Cu" "In6.Cu")
		(teardrops
			(best_length_ratio 0.4)
			(max_length 1)
			(best_width_ratio 0.9)
			(max_width 2)
			(curved_edges yes)
			(filter_ratio 0.9)
			(enabled yes)
			(allow_two_segments yes)
			(prefer_zone_connections yes)
		)
		(net 1)
	)
	(via
		(at 104.45 125.81)
		(size 0.45)
		(drill 0.1)
		(layers "F.Cu" "B.Cu")
		(remove_unused_layers yes)
		(keep_end_layers yes)
		(zone_layer_connections "In1.Cu" "In4.Cu" "In6.Cu")
		(teardrops
			(best_length_ratio 0.4)
			(max_length 1)
			(best_width_ratio 0.9)
			(max_width 2)
			(curved_edges yes)
			(filter_ratio 0.9)
			(enabled yes)
			(allow_two_segments yes)
			(prefer_zone_connections yes)
		)
		(net 1)
	)
	(via
		(at 96.95 99.81)
		(size 0.45)
		(drill 0.1)
		(layers "F.Cu" "B.Cu")
		(remove_unused_layers yes)
		(keep_end_layers yes)
		(zone_layer_connections "In1.Cu" "In4.Cu" "In6.Cu")
		(teardrops
			(best_length_ratio 0.4)
			(max_length 1)
			(best_width_ratio 0.9)
			(max_width 2)
			(curved_edges yes)
			(filter_ratio 0.9)
			(enabled yes)
			(allow_two_segments yes)
			(prefer_zone_connections yes)
		)
		(net 1)
	)
	(via
		(at 171.45 71.81)
		(size 0.45)
		(drill 0.1)
		(layers "F.Cu" "B.Cu")
		(remove_unused_layers yes)
		(keep_end_layers yes)
		(zone_layer_connections "In1.Cu" "In4.Cu" "In6.Cu")
		(teardrops
			(best_length_ratio 0.4)
			(max_length 1)
			(best_width_ratio 0.9)
			(max_width 2)
			(curved_edges yes)
			(filter_ratio 0.9)
			(enabled yes)
			(allow_two_segments yes)
			(prefer_zone_connections yes)
		)
		(net 1)
	)
	(via
		(at 312.95 86.31)
		(size 0.45)
		(drill 0.1)
		(layers "F.Cu" "B.Cu")
		(remove_unused_layers yes)
		(keep_end_layers yes)
		(zone_layer_connections "In1.Cu" "In4.Cu" "In6.Cu")
		(teardrops
			(best_length_ratio 0.4)
			(max_length 1)
			(best_width_ratio 0.9)
			(max_width 2)
			(curved_edges yes)
			(filter_ratio 0.9)
			(enabled yes)
			(allow_two_segments yes)
			(prefer_zone_connections yes)
		)
		(net 1)
	)
	(via
		(at 250.45 115.81)
		(size 0.45)
		(drill 0.1)
		(layers "F.Cu" "B.Cu")
		(remove_unused_layers yes)
		(keep_end_layers yes)
		(zone_layer_connections "In1.Cu" "In4.Cu" "In6.Cu")
		(teardrops
			(best_length_ratio 0.4)
			(max_length 1)
			(best_width_ratio 0.9)
			(max_width 2)
			(curved_edges yes)
			(filter_ratio 0.9)
			(enabled yes)
			(allow_two_segments yes)
			(prefer_zone_connections yes)
		)
		(net 1)
	)
	(via
		(at 265.45 114.31)
		(size 0.45)
		(drill 0.1)
		(layers "F.Cu" "B.Cu")
		(remove_unused_layers yes)
		(keep_end_layers yes)
		(zone_layer_connections "In1.Cu" "In4.Cu" "In6.Cu")
		(teardrops
			(best_length_ratio 0.4)
			(max_length 1)
			(best_width_ratio 0.9)
			(max_width 2)
			(curved_edges yes)
			(filter_ratio 0.9)
			(enabled yes)
			(allow_two_segments yes)
			(prefer_zone_connections yes)
		)
		(net 1)
	)
	(via
		(at 120.2 85.88)
		(size 0.45)
		(drill 0.1)
		(layers "F.Cu" "B.Cu")
		(remove_unused_layers yes)
		(keep_end_layers yes)
		(zone_layer_connections "In1.Cu" "In4.Cu" "In6.Cu")
		(teardrops
			(best_length_ratio 0.4)
			(max_length 1)
			(best_width_ratio 0.9)
			(max_width 2)
			(curved_edges yes)
			(filter_ratio 0.9)
			(enabled yes)
			(allow_two_segments yes)
			(prefer_zone_connections yes)
		)
		(net 1)
	)
	(via
		(at 265.45 117.31)
		(size 0.45)
		(drill 0.1)
		(layers "F.Cu" "B.Cu")
		(remove_unused_layers yes)
		(keep_end_layers yes)
		(zone_layer_connections "In1.Cu" "In4.Cu" "In6.Cu")
		(teardrops
			(best_length_ratio 0.4)
			(max_length 1)
			(best_width_ratio 0.9)
			(max_width 2)
			(curved_edges yes)
			(filter_ratio 0.9)
			(enabled yes)
			(allow_two_segments yes)
			(prefer_zone_connections yes)
		)
		(net 1)
	)
	(via
		(at 293.45 121.81)
		(size 0.45)
		(drill 0.1)
		(layers "F.Cu" "B.Cu")
		(remove_unused_layers yes)
		(keep_end_layers yes)
		(zone_layer_connections "In1.Cu" "In4.Cu" "In6.Cu")
		(teardrops
			(best_length_ratio 0.4)
			(max_length 1)
			(best_width_ratio 0.9)
			(max_width 2)
			(curved_edges yes)
			(filter_ratio 0.9)
			(enabled yes)
			(allow_two_segments yes)
			(prefer_zone_connections yes)
		)
		(net 1)
	)
	(via
		(at 155.45 141.86)
		(size 0.45)
		(drill 0.1)
		(layers "F.Cu" "B.Cu")
		(remove_unused_layers yes)
		(keep_end_layers yes)
		(zone_layer_connections "In1.Cu" "In4.Cu" "In6.Cu")
		(teardrops
			(best_length_ratio 0.4)
			(max_length 1)
			(best_width_ratio 0.9)
			(max_width 2)
			(curved_edges yes)
			(filter_ratio 0.9)
			(enabled yes)
			(allow_two_segments yes)
			(prefer_zone_connections yes)
		)
		(net 1)
	)
	(via
		(at 194.95 85.06)
		(size 0.45)
		(drill 0.1)
		(layers "F.Cu" "B.Cu")
		(remove_unused_layers yes)
		(keep_end_layers yes)
		(zone_layer_connections "In1.Cu" "In4.Cu" "In6.Cu")
		(teardrops
			(best_length_ratio 0.4)
			(max_length 1)
			(best_width_ratio 0.9)
			(max_width 2)
			(curved_edges yes)
			(filter_ratio 0.9)
			(enabled yes)
			(allow_two_segments yes)
			(prefer_zone_connections yes)
		)
		(net 1)
	)
	(via
		(at 138.3 71.51)
		(size 0.45)
		(drill 0.1)
		(layers "F.Cu" "B.Cu")
		(remove_unused_layers yes)
		(keep_end_layers yes)
		(zone_layer_connections "In1.Cu" "In4.Cu" "In6.Cu")
		(teardrops
			(best_length_ratio 0.4)
			(max_length 1)
			(best_width_ratio 0.9)
			(max_width 2)
			(curved_edges yes)
			(filter_ratio 0.9)
			(enabled yes)
			(allow_two_segments yes)
			(prefer_zone_connections yes)
		)
		(net 1)
	)
	(via
		(at 150.475 113.025)
		(size 0.45)
		(drill 0.1)
		(layers "F.Cu" "B.Cu")
		(remove_unused_layers yes)
		(keep_end_layers yes)
		(zone_layer_connections "In1.Cu" "In4.Cu" "In6.Cu")
		(teardrops
			(best_length_ratio 0.4)
			(max_length 1)
			(best_width_ratio 0.9)
			(max_width 2)
			(curved_edges yes)
			(filter_ratio 0.9)
			(enabled yes)
			(allow_two_segments yes)
			(prefer_zone_connections yes)
		)
		(net 1)
	)
	(via
		(at 311.474999 120.21)
		(size 0.45)
		(drill 0.1)
		(layers "F.Cu" "B.Cu")
		(remove_unused_layers yes)
		(keep_end_layers yes)
		(zone_layer_connections "In1.Cu" "In4.Cu" "In6.Cu")
		(teardrops
			(best_length_ratio 0.4)
			(max_length 1)
			(best_width_ratio 0.9)
			(max_width 2)
			(curved_edges yes)
			(filter_ratio 0.9)
			(enabled yes)
			(allow_two_segments yes)
			(prefer_zone_connections yes)
		)
		(net 1)
	)
	(via
		(at 200.95 160.975)
		(size 0.45)
		(drill 0.1)
		(layers "F.Cu" "B.Cu")
		(teardrops
			(best_length_ratio 0.4)
			(max_length 1)
			(best_width_ratio 0.9)
			(max_width 2)
			(curved_edges yes)
			(filter_ratio 0.9)
			(enabled yes)
			(allow_two_segments yes)
			(prefer_zone_connections yes)
		)
		(net 1)
	)
	(via
		(at 206.95 139.81)
		(size 0.45)
		(drill 0.1)
		(layers "F.Cu" "B.Cu")
		(remove_unused_layers yes)
		(keep_end_layers yes)
		(zone_layer_connections "In1.Cu" "In4.Cu" "In6.Cu")
		(teardrops
			(best_length_ratio 0.4)
			(max_length 1)
			(best_width_ratio 0.9)
			(max_width 2)
			(curved_edges yes)
			(filter_ratio 0.9)
			(enabled yes)
			(allow_two_segments yes)
			(prefer_zone_connections yes)
		)
		(net 1)
	)
	(via
		(at 196.025 167.475)
		(size 0.45)
		(drill 0.1)
		(layers "F.Cu" "B.Cu")
		(teardrops
			(best_length_ratio 0.4)
			(max_length 1)
			(best_width_ratio 0.9)
			(max_width 2)
			(curved_edges yes)
			(filter_ratio 0.9)
			(enabled yes)
			(allow_two_segments yes)
			(prefer_zone_connections yes)
		)
		(net 1)
	)
	(via
		(at 110.7 153.3)
		(size 0.45)
		(drill 0.1)
		(layers "F.Cu" "B.Cu")
		(remove_unused_layers yes)
		(keep_end_layers yes)
		(zone_layer_connections "In1.Cu" "In4.Cu" "In6.Cu")
		(teardrops
			(best_length_ratio 0.4)
			(max_length 1)
			(best_width_ratio 0.9)
			(max_width 2)
			(curved_edges yes)
			(filter_ratio 0.9)
			(enabled yes)
			(allow_two_segments yes)
			(prefer_zone_connections yes)
		)
		(net 1)
	)
	(via
		(at 104.114493 104.572724)
		(size 0.45)
		(drill 0.1)
		(layers "F.Cu" "B.Cu")
		(remove_unused_layers yes)
		(keep_end_layers yes)
		(zone_layer_connections "In1.Cu" "In4.Cu" "In6.Cu")
		(teardrops
			(best_length_ratio 0.4)
			(max_length 1)
			(best_width_ratio 0.9)
			(max_width 2)
			(curved_edges yes)
			(filter_ratio 0.9)
			(enabled yes)
			(allow_two_segments yes)
			(prefer_zone_connections yes)
		)
		(net 1)
	)
	(via
		(at 108.05 133.81)
		(size 0.45)
		(drill 0.1)
		(layers "F.Cu" "B.Cu")
		(remove_unused_layers yes)
		(keep_end_layers yes)
		(zone_layer_connections "In1.Cu" "In4.Cu" "In6.Cu")
		(teardrops
			(best_length_ratio 0.4)
			(max_length 1)
			(best_width_ratio 0.9)
			(max_width 2)
			(curved_edges yes)
			(filter_ratio 0.9)
			(enabled yes)
			(allow_two_segments yes)
			(prefer_zone_connections yes)
		)
		(net 1)
	)
	(via
		(at 173.2 93.35)
		(size 0.45)
		(drill 0.1)
		(layers "F.Cu" "B.Cu")
		(remove_unused_layers yes)
		(keep_end_layers yes)
		(zone_layer_connections "In1.Cu" "In4.Cu" "In6.Cu")
		(teardrops
			(best_length_ratio 0.4)
			(max_length 1)
			(best_width_ratio 0.9)
			(max_width 2)
			(curved_edges yes)
			(filter_ratio 0.9)
			(enabled yes)
			(allow_two_segments yes)
			(prefer_zone_connections yes)
		)
		(net 1)
	)
	(via
		(at 113.45 70.81)
		(size 0.45)
		(drill 0.1)
		(layers "F.Cu" "B.Cu")
		(remove_unused_layers yes)
		(keep_end_layers yes)
		(zone_layer_connections "In1.Cu" "In4.Cu" "In6.Cu")
		(teardrops
			(best_length_ratio 0.4)
			(max_length 1)
			(best_width_ratio 0.9)
			(max_width 2)
			(curved_edges yes)
			(filter_ratio 0.9)
			(enabled yes)
			(allow_two_segments yes)
			(prefer_zone_connections yes)
		)
		(net 1)
	)
	(via
		(at 174.7 100.85)
		(size 0.45)
		(drill 0.1)
		(layers "F.Cu" "B.Cu")
		(remove_unused_layers yes)
		(keep_end_layers yes)
		(zone_layer_connections "In1.Cu" "In4.Cu" "In6.Cu")
		(teardrops
			(best_length_ratio 0.4)
			(max_length 1)
			(best_width_ratio 0.9)
			(max_width 2)
			(curved_edges yes)
			(filter_ratio 0.9)
			(enabled yes)
			(allow_two_segments yes)
			(prefer_zone_connections yes)
		)
		(net 1)
	)
	(via
		(at 220.45 131.81)
		(size 0.45)
		(drill 0.1)
		(layers "F.Cu" "B.Cu")
		(remove_unused_layers yes)
		(keep_end_layers yes)
		(zone_layer_connections "In1.Cu" "In4.Cu" "In6.Cu")
		(teardrops
			(best_length_ratio 0.4)
			(max_length 1)
			(best_width_ratio 0.9)
			(max_width 2)
			(curved_edges yes)
			(filter_ratio 0.9)
			(enabled yes)
			(allow_two_segments yes)
			(prefer_zone_connections yes)
		)
		(net 1)
	)
	(via
		(at 186.45 71.81)
		(size 0.45)
		(drill 0.1)
		(layers "F.Cu" "B.Cu")
		(remove_unused_layers yes)
		(keep_end_layers yes)
		(zone_layer_connections "In1.Cu" "In4.Cu" "In6.Cu")
		(teardrops
			(best_length_ratio 0.4)
			(max_length 1)
			(best_width_ratio 0.9)
			(max_width 2)
			(curved_edges yes)
			(filter_ratio 0.9)
			(enabled yes)
			(allow_two_segments yes)
			(prefer_zone_connections yes)
		)
		(net 1)
	)
	(via
		(at 169.95 70.31)
		(size 0.45)
		(drill 0.1)
		(layers "F.Cu" "B.Cu")
		(remove_unused_layers yes)
		(keep_end_layers yes)
		(free yes)
		(zone_layer_connections "In1.Cu" "In4.Cu" "In6.Cu")
		(teardrops
			(best_length_ratio 0.4)
			(max_length 1)
			(best_width_ratio 0.9)
			(max_width 2)
			(curved_edges yes)
			(filter_ratio 0.9)
			(enabled yes)
			(allow_two_segments yes)
			(prefer_zone_connections yes)
		)
		(net 1)
	)
	(via
		(at 153.45 133.86)
		(size 0.45)
		(drill 0.1)
		(layers "F.Cu" "B.Cu")
		(remove_unused_layers yes)
		(keep_end_layers yes)
		(zone_layer_connections "In1.Cu" "In4.Cu" "In6.Cu")
		(teardrops
			(best_length_ratio 0.4)
			(max_length 1)
			(best_width_ratio 0.9)
			(max_width 2)
			(curved_edges yes)
			(filter_ratio 0.9)
			(enabled yes)
			(allow_two_segments yes)
			(prefer_zone_connections yes)
		)
		(net 1)
	)
	(via
		(at 140.45 152.81)
		(size 0.45)
		(drill 0.1)
		(layers "F.Cu" "B.Cu")
		(remove_unused_layers yes)
		(keep_end_layers yes)
		(zone_layer_connections "In1.Cu" "In4.Cu" "In6.Cu")
		(teardrops
			(best_length_ratio 0.4)
			(max_length 1)
			(best_width_ratio 0.9)
			(max_width 2)
			(curved_edges yes)
			(filter_ratio 0.9)
			(enabled yes)
			(allow_two_segments yes)
			(prefer_zone_connections yes)
		)
		(net 1)
	)
	(via
		(at 107.8 144.75)
		(size 0.45)
		(drill 0.1)
		(layers "F.Cu" "B.Cu")
		(teardrops
			(best_length_ratio 0.4)
			(max_length 1)
			(best_width_ratio 0.9)
			(max_width 2)
			(curved_edges yes)
			(filter_ratio 0.9)
			(enabled yes)
			(allow_two_segments yes)
			(prefer_zone_connections yes)
		)
		(net 1)
	)
	(via
		(at 120.2 90.78)
		(size 0.45)
		(drill 0.1)
		(layers "F.Cu" "B.Cu")
		(remove_unused_layers yes)
		(keep_end_layers yes)
		(zone_layer_connections "In1.Cu" "In4.Cu" "In6.Cu")
		(teardrops
			(best_length_ratio 0.4)
			(max_length 1)
			(best_width_ratio 0.9)
			(max_width 2)
			(curved_edges yes)
			(filter_ratio 0.9)
			(enabled yes)
			(allow_two_segments yes)
			(prefer_zone_connections yes)
		)
		(net 1)
	)
	(via
		(at 282.45 107.81)
		(size 0.45)
		(drill 0.1)
		(layers "F.Cu" "B.Cu")
		(remove_unused_layers yes)
		(keep_end_layers yes)
		(zone_layer_connections "In1.Cu" "In4.Cu" "In6.Cu")
		(teardrops
			(best_length_ratio 0.4)
			(max_length 1)
			(best_width_ratio 0.9)
			(max_width 2)
			(curved_edges yes)
			(filter_ratio 0.9)
			(enabled yes)
			(allow_two_segments yes)
			(prefer_zone_connections yes)
		)
		(net 1)
	)
	(via
		(at 311.464499 117.4465)
		(size 0.45)
		(drill 0.1)
		(layers "F.Cu" "B.Cu")
		(remove_unused_layers yes)
		(keep_end_layers yes)
		(free yes)
		(zone_layer_connections "In1.Cu" "In4.Cu" "In6.Cu")
		(teardrops
			(best_length_ratio 0.4)
			(max_length 1)
			(best_width_ratio 0.9)
			(max_width 2)
			(curved_edges yes)
			(filter_ratio 0.9)
			(enabled yes)
			(allow_two_segments yes)
			(prefer_zone_connections yes)
		)
		(net 1)
	)
	(via
		(at 282.45 116.81)
		(size 0.45)
		(drill 0.1)
		(layers "F.Cu" "B.Cu")
		(remove_unused_layers yes)
		(keep_end_layers yes)
		(zone_layer_connections "In1.Cu" "In4.Cu" "In6.Cu")
		(teardrops
			(best_length_ratio 0.4)
			(max_length 1)
			(best_width_ratio 0.9)
			(max_width 2)
			(curved_edges yes)
			(filter_ratio 0.9)
			(enabled yes)
			(allow_two_segments yes)
			(prefer_zone_connections yes)
		)
		(net 1)
	)
	(via
		(at 114.509999 76.475)
		(size 0.45)
		(drill 0.1)
		(layers "F.Cu" "B.Cu")
		(remove_unused_layers yes)
		(keep_end_layers yes)
		(zone_layer_connections "In1.Cu" "In4.Cu" "In6.Cu")
		(teardrops
			(best_length_ratio 0.4)
			(max_length 1)
			(best_width_ratio 0.9)
			(max_width 2)
			(curved_edges yes)
			(filter_ratio 0.9)
			(enabled yes)
			(allow_two_segments yes)
			(prefer_zone_connections yes)
		)
		(net 1)
	)
	(via
		(at 166.45 82.31)
		(size 0.45)
		(drill 0.1)
		(layers "F.Cu" "B.Cu")
		(remove_unused_layers yes)
		(keep_end_layers yes)
		(free yes)
		(zone_layer_connections "In1.Cu" "In4.Cu" "In6.Cu")
		(teardrops
			(best_length_ratio 0.4)
			(max_length 1)
			(best_width_ratio 0.9)
			(max_width 2)
			(curved_edges yes)
			(filter_ratio 0.9)
			(enabled yes)
			(allow_two_segments yes)
			(prefer_zone_connections yes)
		)
		(net 1)
	)
	(via
		(at 130.86 147.62681)
		(size 0.45)
		(drill 0.1)
		(layers "F.Cu" "B.Cu")
		(remove_unused_layers yes)
		(keep_end_layers yes)
		(zone_layer_connections "In1.Cu" "In4.Cu" "In6.Cu")
		(teardrops
			(best_length_ratio 0.4)
			(max_length 1)
			(best_width_ratio 0.9)
			(max_width 2)
			(curved_edges yes)
			(filter_ratio 0.9)
			(enabled yes)
			(allow_two_segments yes)
			(prefer_zone_connections yes)
		)
		(net 1)
	)
	(via
		(at 317.7 157.71)
		(size 0.45)
		(drill 0.1)
		(layers "F.Cu" "B.Cu")
		(remove_unused_layers yes)
		(keep_end_layers yes)
		(zone_layer_connections "In1.Cu" "In4.Cu" "In6.Cu")
		(teardrops
			(best_length_ratio 0.4)
			(max_length 1)
			(best_width_ratio 0.9)
			(max_width 2)
			(curved_edges yes)
			(filter_ratio 0.9)
			(enabled yes)
			(allow_two_segments yes)
			(prefer_zone_connections yes)
		)
		(net 1)
	)
	(via
		(at 132.29 141.86)
		(size 0.45)
		(drill 0.1)
		(layers "F.Cu" "B.Cu")
		(remove_unused_layers yes)
		(keep_end_layers yes)
		(zone_layer_connections "In1.Cu" "In4.Cu" "In6.Cu")
		(teardrops
			(best_length_ratio 0.4)
			(max_length 1)
			(best_width_ratio 0.9)
			(max_width 2)
			(curved_edges yes)
			(filter_ratio 0.9)
			(enabled yes)
			(allow_two_segments yes)
			(prefer_zone_connections yes)
		)
		(net 1)
	)
	(via
		(at 205.95 84.31)
		(size 0.45)
		(drill 0.1)
		(layers "F.Cu" "B.Cu")
		(remove_unused_layers yes)
		(keep_end_layers yes)
		(zone_layer_connections "In1.Cu" "In4.Cu" "In6.Cu")
		(teardrops
			(best_length_ratio 0.4)
			(max_length 1)
			(best_width_ratio 0.9)
			(max_width 2)
			(curved_edges yes)
			(filter_ratio 0.9)
			(enabled yes)
			(allow_two_segments yes)
			(prefer_zone_connections yes)
		)
		(net 1)
	)
	(via
		(at 194.503317 135.7959)
		(size 0.45)
		(drill 0.1)
		(layers "F.Cu" "B.Cu")
		(remove_unused_layers yes)
		(keep_end_layers yes)
		(zone_layer_connections "In1.Cu" "In4.Cu" "In6.Cu")
		(teardrops
			(best_length_ratio 0.4)
			(max_length 1)
			(best_width_ratio 0.9)
			(max_width 2)
			(curved_edges yes)
			(filter_ratio 0.9)
			(enabled yes)
			(allow_two_segments yes)
			(prefer_zone_connections yes)
		)
		(net 1)
	)
	(via
		(at 294.201 74.96)
		(size 0.45)
		(drill 0.1)
		(layers "F.Cu" "B.Cu")
		(remove_unused_layers yes)
		(keep_end_layers yes)
		(free yes)
		(zone_layer_connections "In1.Cu" "In4.Cu" "In6.Cu")
		(teardrops
			(best_length_ratio 0.4)
			(max_length 1)
			(best_width_ratio 0.9)
			(max_width 2)
			(curved_edges yes)
			(filter_ratio 0.9)
			(enabled yes)
			(allow_two_segments yes)
			(prefer_zone_connections yes)
		)
		(net 1)
	)
	(via
		(at 221.45 136.81)
		(size 0.45)
		(drill 0.1)
		(layers "F.Cu" "B.Cu")
		(remove_unused_layers yes)
		(keep_end_layers yes)
		(zone_layer_connections "In1.Cu" "In4.Cu" "In6.Cu")
		(teardrops
			(best_length_ratio 0.4)
			(max_length 1)
			(best_width_ratio 0.9)
			(max_width 2)
			(curved_edges yes)
			(filter_ratio 0.9)
			(enabled yes)
			(allow_two_segments yes)
			(prefer_zone_connections yes)
		)
		(net 1)
	)
	(via
		(at 228.95 145.45)
		(size 0.45)
		(drill 0.1)
		(layers "F.Cu" "B.Cu")
		(teardrops
			(best_length_ratio 0.4)
			(max_length 1)
			(best_width_ratio 0.9)
			(max_width 2)
			(curved_edges yes)
			(filter_ratio 0.9)
			(enabled yes)
			(allow_two_segments yes)
			(prefer_zone_connections yes)
		)
		(net 1)
	)
	(via
		(at 297.95 113.31)
		(size 0.45)
		(drill 0.1)
		(layers "F.Cu" "B.Cu")
		(remove_unused_layers yes)
		(keep_end_layers yes)
		(zone_layer_connections "In1.Cu" "In4.Cu" "In6.Cu")
		(teardrops
			(best_length_ratio 0.4)
			(max_length 1)
			(best_width_ratio 0.9)
			(max_width 2)
			(curved_edges yes)
			(filter_ratio 0.9)
			(enabled yes)
			(allow_two_segments yes)
			(prefer_zone_connections yes)
		)
		(net 1)
	)
	(via
		(at 101.35 166.96)
		(size 0.45)
		(drill 0.1)
		(layers "F.Cu" "B.Cu")
		(remove_unused_layers yes)
		(keep_end_layers yes)
		(zone_layer_connections "In1.Cu" "In4.Cu" "In6.Cu")
		(teardrops
			(best_length_ratio 0.4)
			(max_length 1)
			(best_width_ratio 0.9)
			(max_width 2)
			(curved_edges yes)
			(filter_ratio 0.9)
			(enabled yes)
			(allow_two_segments yes)
			(prefer_zone_connections yes)
		)
		(net 1)
	)
	(via
		(at 257.95 123.31)
		(size 0.45)
		(drill 0.1)
		(layers "F.Cu" "B.Cu")
		(remove_unused_layers yes)
		(keep_end_layers yes)
		(zone_layer_connections "In1.Cu" "In4.Cu" "In6.Cu")
		(teardrops
			(best_length_ratio 0.4)
			(max_length 1)
			(best_width_ratio 0.9)
			(max_width 2)
			(curved_edges yes)
			(filter_ratio 0.9)
			(enabled yes)
			(allow_two_segments yes)
			(prefer_zone_connections yes)
		)
		(net 1)
	)
	(via
		(at 316.549999 139.759999)
		(size 0.45)
		(drill 0.1)
		(layers "F.Cu" "B.Cu")
		(remove_unused_layers yes)
		(keep_end_layers yes)
		(zone_layer_connections "In1.Cu" "In4.Cu" "In6.Cu")
		(teardrops
			(best_length_ratio 0.4)
			(max_length 1)
			(best_width_ratio 0.9)
			(max_width 2)
			(curved_edges yes)
			(filter_ratio 0.9)
			(enabled yes)
			(allow_two_segments yes)
			(prefer_zone_connections yes)
		)
		(net 1)
	)
	(via
		(at 286.925 78.42)
		(size 0.45)
		(drill 0.1)
		(layers "F.Cu" "B.Cu")
		(remove_unused_layers yes)
		(keep_end_layers yes)
		(free yes)
		(zone_layer_connections "In1.Cu" "In4.Cu" "In6.Cu")
		(teardrops
			(best_length_ratio 0.4)
			(max_length 1)
			(best_width_ratio 0.9)
			(max_width 2)
			(curved_edges yes)
			(filter_ratio 0.9)
			(enabled yes)
			(allow_two_segments yes)
			(prefer_zone_connections yes)
		)
		(net 1)
	)
	(via
		(at 152.5685 79.0595)
		(size 0.45)
		(drill 0.1)
		(layers "F.Cu" "B.Cu")
		(remove_unused_layers yes)
		(keep_end_layers yes)
		(zone_layer_connections "In1.Cu" "In4.Cu" "In6.Cu")
		(teardrops
			(best_length_ratio 0.4)
			(max_length 1)
			(best_width_ratio 0.9)
			(max_width 2)
			(curved_edges yes)
			(filter_ratio 0.9)
			(enabled yes)
			(allow_two_segments yes)
			(prefer_zone_connections yes)
		)
		(net 1)
	)
	(via
		(at 137 106.4)
		(size 0.45)
		(drill 0.1)
		(layers "F.Cu" "B.Cu")
		(remove_unused_layers yes)
		(keep_end_layers yes)
		(zone_layer_connections "In1.Cu" "In4.Cu" "In6.Cu")
		(teardrops
			(best_length_ratio 0.4)
			(max_length 1)
			(best_width_ratio 0.9)
			(max_width 2)
			(curved_edges yes)
			(filter_ratio 0.9)
			(enabled yes)
			(allow_two_segments yes)
			(prefer_zone_connections yes)
		)
		(net 1)
	)
	(via
		(at 150.879999 147.63)
		(size 0.45)
		(drill 0.1)
		(layers "F.Cu" "B.Cu")
		(remove_unused_layers yes)
		(keep_end_layers yes)
		(zone_layer_connections "In1.Cu" "In4.Cu" "In6.Cu")
		(teardrops
			(best_length_ratio 0.4)
			(max_length 1)
			(best_width_ratio 0.9)
			(max_width 2)
			(curved_edges yes)
			(filter_ratio 0.9)
			(enabled yes)
			(allow_two_segments yes)
			(prefer_zone_connections yes)
		)
		(net 1)
	)
	(via
		(at 177.18 111.36)
		(size 0.45)
		(drill 0.1)
		(layers "F.Cu" "B.Cu")
		(remove_unused_layers yes)
		(keep_end_layers yes)
		(zone_layer_connections "In1.Cu" "In4.Cu" "In6.Cu")
		(teardrops
			(best_length_ratio 0.4)
			(max_length 1)
			(best_width_ratio 0.9)
			(max_width 2)
			(curved_edges yes)
			(filter_ratio 0.9)
			(enabled yes)
			(allow_two_segments yes)
			(prefer_zone_connections yes)
		)
		(net 1)
	)
	(via
		(at 236.95 133.81)
		(size 0.45)
		(drill 0.1)
		(layers "F.Cu" "B.Cu")
		(remove_unused_layers yes)
		(keep_end_layers yes)
		(zone_layer_connections "In1.Cu" "In4.Cu" "In6.Cu")
		(teardrops
			(best_length_ratio 0.4)
			(max_length 1)
			(best_width_ratio 0.9)
			(max_width 2)
			(curved_edges yes)
			(filter_ratio 0.9)
			(enabled yes)
			(allow_two_segments yes)
			(prefer_zone_connections yes)
		)
		(net 1)
	)
	(via
		(at 129.29 131.86)
		(size 0.45)
		(drill 0.1)
		(layers "F.Cu" "B.Cu")
		(remove_unused_layers yes)
		(keep_end_layers yes)
		(zone_layer_connections "In1.Cu" "In4.Cu" "In6.Cu")
		(teardrops
			(best_length_ratio 0.4)
			(max_length 1)
			(best_width_ratio 0.9)
			(max_width 2)
			(curved_edges yes)
			(filter_ratio 0.9)
			(enabled yes)
			(allow_two_segments yes)
			(prefer_zone_connections yes)
		)
		(net 1)
	)
	(via
		(at 287.6 85.66)
		(size 0.45)
		(drill 0.1)
		(layers "F.Cu" "B.Cu")
		(remove_unused_layers yes)
		(keep_end_layers yes)
		(zone_layer_connections "In1.Cu" "In4.Cu" "In6.Cu")
		(teardrops
			(best_length_ratio 0.4)
			(max_length 1)
			(best_width_ratio 0.9)
			(max_width 2)
			(curved_edges yes)
			(filter_ratio 0.9)
			(enabled yes)
			(allow_two_segments yes)
			(prefer_zone_connections yes)
		)
		(net 1)
	)
	(via
		(at 101.3 163.51)
		(size 0.45)
		(drill 0.1)
		(layers "F.Cu" "B.Cu")
		(remove_unused_layers yes)
		(keep_end_layers yes)
		(zone_layer_connections "In1.Cu" "In4.Cu" "In6.Cu")
		(teardrops
			(best_length_ratio 0.4)
			(max_length 1)
			(best_width_ratio 0.9)
			(max_width 2)
			(curved_edges yes)
			(filter_ratio 0.9)
			(enabled yes)
			(allow_two_segments yes)
			(prefer_zone_connections yes)
		)
		(net 1)
	)
	(via
		(at 136.268854 110.37094)
		(size 0.45)
		(drill 0.1)
		(layers "F.Cu" "B.Cu")
		(remove_unused_layers yes)
		(keep_end_layers yes)
		(zone_layer_connections "In1.Cu" "In4.Cu" "In6.Cu")
		(teardrops
			(best_length_ratio 0.4)
			(max_length 1)
			(best_width_ratio 0.9)
			(max_width 2)
			(curved_edges yes)
			(filter_ratio 0.9)
			(enabled yes)
			(allow_two_segments yes)
			(prefer_zone_connections yes)
		)
		(net 1)
	)
	(via
		(at 97.45 142.81)
		(size 0.45)
		(drill 0.1)
		(layers "F.Cu" "B.Cu")
		(remove_unused_layers yes)
		(keep_end_layers yes)
		(zone_layer_connections "In1.Cu" "In4.Cu" "In6.Cu")
		(teardrops
			(best_length_ratio 0.4)
			(max_length 1)
			(best_width_ratio 0.9)
			(max_width 2)
			(curved_edges yes)
			(filter_ratio 0.9)
			(enabled yes)
			(allow_two_segments yes)
			(prefer_zone_connections yes)
		)
		(net 1)
	)
	(via
		(at 170.95 80.81)
		(size 0.45)
		(drill 0.1)
		(layers "F.Cu" "B.Cu")
		(remove_unused_layers yes)
		(keep_end_layers yes)
		(zone_layer_connections "In1.Cu" "In4.Cu" "In6.Cu")
		(teardrops
			(best_length_ratio 0.4)
			(max_length 1)
			(best_width_ratio 0.9)
			(max_width 2)
			(curved_edges yes)
			(filter_ratio 0.9)
			(enabled yes)
			(allow_two_segments yes)
			(prefer_zone_connections yes)
		)
		(net 1)
	)
	(via
		(at 203.85 165.4)
		(size 0.45)
		(drill 0.1)
		(layers "F.Cu" "B.Cu")
		(teardrops
			(best_length_ratio 0.4)
			(max_length 1)
			(best_width_ratio 0.9)
			(max_width 2)
			(curved_edges yes)
			(filter_ratio 0.9)
			(enabled yes)
			(allow_two_segments yes)
			(prefer_zone_connections yes)
		)
		(net 1)
	)
	(via
		(at 225.45 74.96)
		(size 0.45)
		(drill 0.1)
		(layers "F.Cu" "B.Cu")
		(remove_unused_layers yes)
		(keep_end_layers yes)
		(zone_layer_connections "In1.Cu" "In4.Cu" "In6.Cu")
		(teardrops
			(best_length_ratio 0.4)
			(max_length 1)
			(best_width_ratio 0.9)
			(max_width 2)
			(curved_edges yes)
			(filter_ratio 0.9)
			(enabled yes)
			(allow_two_segments yes)
			(prefer_zone_connections yes)
		)
		(net 1)
	)
	(via
		(at 119.625 146.65)
		(size 0.45)
		(drill 0.1)
		(layers "F.Cu" "B.Cu")
		(remove_unused_layers yes)
		(keep_end_layers yes)
		(zone_layer_connections "In1.Cu" "In4.Cu" "In6.Cu")
		(teardrops
			(best_length_ratio 0.4)
			(max_length 1)
			(best_width_ratio 0.9)
			(max_width 2)
			(curved_edges yes)
			(filter_ratio 0.9)
			(enabled yes)
			(allow_two_segments yes)
			(prefer_zone_connections yes)
		)
		(net 1)
	)
	(via
		(at 194.45 97.31)
		(size 0.45)
		(drill 0.1)
		(layers "F.Cu" "B.Cu")
		(remove_unused_layers yes)
		(keep_end_layers yes)
		(free yes)
		(zone_layer_connections "In1.Cu" "In4.Cu" "In6.Cu")
		(teardrops
			(best_length_ratio 0.4)
			(max_length 1)
			(best_width_ratio 0.9)
			(max_width 2)
			(curved_edges yes)
			(filter_ratio 0.9)
			(enabled yes)
			(allow_two_segments yes)
			(prefer_zone_connections yes)
		)
		(net 1)
	)
	(via
		(at 130 84.91)
		(size 0.45)
		(drill 0.1)
		(layers "F.Cu" "B.Cu")
		(remove_unused_layers yes)
		(keep_end_layers yes)
		(zone_layer_connections "In1.Cu" "In4.Cu" "In6.Cu")
		(teardrops
			(best_length_ratio 0.4)
			(max_length 1)
			(best_width_ratio 0.9)
			(max_width 2)
			(curved_edges yes)
			(filter_ratio 0.9)
			(enabled yes)
			(allow_two_segments yes)
			(prefer_zone_connections yes)
		)
		(net 1)
	)
	(via
		(at 173.2 167.2)
		(size 0.45)
		(drill 0.1)
		(layers "F.Cu" "B.Cu")
		(teardrops
			(best_length_ratio 0.4)
			(max_length 1)
			(best_width_ratio 0.9)
			(max_width 2)
			(curved_edges yes)
			(filter_ratio 0.9)
			(enabled yes)
			(allow_two_segments yes)
			(prefer_zone_connections yes)
		)
		(net 1)
	)
	(via
		(at 130.45 164.81)
		(size 0.45)
		(drill 0.1)
		(layers "F.Cu" "B.Cu")
		(remove_unused_layers yes)
		(keep_end_layers yes)
		(zone_layer_connections "In1.Cu" "In4.Cu" "In6.Cu")
		(teardrops
			(best_length_ratio 0.4)
			(max_length 1)
			(best_width_ratio 0.9)
			(max_width 2)
			(curved_edges yes)
			(filter_ratio 0.9)
			(enabled yes)
			(allow_two_segments yes)
			(prefer_zone_connections yes)
		)
		(net 1)
	)
	(via
		(at 234.4 155.2)
		(size 0.45)
		(drill 0.1)
		(layers "F.Cu" "B.Cu")
		(teardrops
			(best_length_ratio 0.4)
			(max_length 1)
			(best_width_ratio 0.9)
			(max_width 2)
			(curved_edges yes)
			(filter_ratio 0.9)
			(enabled yes)
			(allow_two_segments yes)
			(prefer_zone_connections yes)
		)
		(net 1)
	)
	(via
		(at 163.58 159.36)
		(size 0.45)
		(drill 0.1)
		(layers "F.Cu" "B.Cu")
		(remove_unused_layers yes)
		(keep_end_layers yes)
		(zone_layer_connections "In1.Cu" "In4.Cu" "In6.Cu")
		(teardrops
			(best_length_ratio 0.4)
			(max_length 1)
			(best_width_ratio 0.9)
			(max_width 2)
			(curved_edges yes)
			(filter_ratio 0.9)
			(enabled yes)
			(allow_two_segments yes)
			(prefer_zone_connections yes)
		)
		(net 1)
	)
	(via
		(at 193.591857 135.943686)
		(size 0.45)
		(drill 0.1)
		(layers "F.Cu" "B.Cu")
		(remove_unused_layers yes)
		(keep_end_layers yes)
		(zone_layer_connections "In1.Cu" "In4.Cu" "In6.Cu")
		(teardrops
			(best_length_ratio 0.4)
			(max_length 1)
			(best_width_ratio 0.9)
			(max_width 2)
			(curved_edges yes)
			(filter_ratio 0.9)
			(enabled yes)
			(allow_two_segments yes)
			(prefer_zone_connections yes)
		)
		(net 1)
	)
	(via
		(at 304.95 170.81)
		(size 0.45)
		(drill 0.1)
		(layers "F.Cu" "B.Cu")
		(remove_unused_layers yes)
		(keep_end_layers yes)
		(zone_layer_connections "In1.Cu" "In4.Cu" "In6.Cu")
		(teardrops
			(best_length_ratio 0.4)
			(max_length 1)
			(best_width_ratio 0.9)
			(max_width 2)
			(curved_edges yes)
			(filter_ratio 0.9)
			(enabled yes)
			(allow_two_segments yes)
			(prefer_zone_connections yes)
		)
		(net 1)
	)
	(via
		(at 236.95 123.31)
		(size 0.45)
		(drill 0.1)
		(layers "F.Cu" "B.Cu")
		(remove_unused_layers yes)
		(keep_end_layers yes)
		(free yes)
		(zone_layer_connections "In1.Cu" "In4.Cu" "In6.Cu")
		(teardrops
			(best_length_ratio 0.4)
			(max_length 1)
			(best_width_ratio 0.9)
			(max_width 2)
			(curved_edges yes)
			(filter_ratio 0.9)
			(enabled yes)
			(allow_two_segments yes)
			(prefer_zone_connections yes)
		)
		(net 1)
	)
	(via
		(at 100.45 131.81)
		(size 0.45)
		(drill 0.1)
		(layers "F.Cu" "B.Cu")
		(remove_unused_layers yes)
		(keep_end_layers yes)
		(zone_layer_connections "In1.Cu" "In4.Cu" "In6.Cu")
		(teardrops
			(best_length_ratio 0.4)
			(max_length 1)
			(best_width_ratio 0.9)
			(max_width 2)
			(curved_edges yes)
			(filter_ratio 0.9)
			(enabled yes)
			(allow_two_segments yes)
			(prefer_zone_connections yes)
		)
		(net 1)
	)
	(via
		(at 276.45 119.81)
		(size 0.45)
		(drill 0.1)
		(layers "F.Cu" "B.Cu")
		(remove_unused_layers yes)
		(keep_end_layers yes)
		(zone_layer_connections "In1.Cu" "In4.Cu" "In6.Cu")
		(teardrops
			(best_length_ratio 0.4)
			(max_length 1)
			(best_width_ratio 0.9)
			(max_width 2)
			(curved_edges yes)
			(filter_ratio 0.9)
			(enabled yes)
			(allow_two_segments yes)
			(prefer_zone_connections yes)
		)
		(net 1)
	)
	(via
		(at 95.45 94.81)
		(size 0.45)
		(drill 0.1)
		(layers "F.Cu" "B.Cu")
		(remove_unused_layers yes)
		(keep_end_layers yes)
		(zone_layer_connections "In1.Cu" "In4.Cu" "In6.Cu")
		(teardrops
			(best_length_ratio 0.4)
			(max_length 1)
			(best_width_ratio 0.9)
			(max_width 2)
			(curved_edges yes)
			(filter_ratio 0.9)
			(enabled yes)
			(allow_two_segments yes)
			(prefer_zone_connections yes)
		)
		(net 1)
	)
	(via
		(at 191.05 161.921)
		(size 0.45)
		(drill 0.1)
		(layers "F.Cu" "B.Cu")
		(teardrops
			(best_length_ratio 0.4)
			(max_length 1)
			(best_width_ratio 0.9)
			(max_width 2)
			(curved_edges yes)
			(filter_ratio 0.9)
			(enabled yes)
			(allow_two_segments yes)
			(prefer_zone_connections yes)
		)
		(net 1)
	)
	(via
		(at 317.464501 96.6365)
		(size 0.45)
		(drill 0.1)
		(layers "F.Cu" "B.Cu")
		(remove_unused_layers yes)
		(keep_end_layers yes)
		(zone_layer_connections "In1.Cu" "In4.Cu" "In6.Cu")
		(teardrops
			(best_length_ratio 0.4)
			(max_length 1)
			(best_width_ratio 0.9)
			(max_width 2)
			(curved_edges yes)
			(filter_ratio 0.9)
			(enabled yes)
			(allow_two_segments yes)
			(prefer_zone_connections yes)
		)
		(net 1)
	)
	(via
		(at 173.203893 97.859175)
		(size 0.45)
		(drill 0.1)
		(layers "F.Cu" "B.Cu")
		(remove_unused_layers yes)
		(keep_end_layers yes)
		(zone_layer_connections "In1.Cu" "In4.Cu" "In6.Cu")
		(teardrops
			(best_length_ratio 0.4)
			(max_length 1)
			(best_width_ratio 0.9)
			(max_width 2)
			(curved_edges yes)
			(filter_ratio 0.9)
			(enabled yes)
			(allow_two_segments yes)
			(prefer_zone_connections yes)
		)
		(net 1)
	)
	(via
		(at 124.45 158.81)
		(size 0.45)
		(drill 0.1)
		(layers "F.Cu" "B.Cu")
		(remove_unused_layers yes)
		(keep_end_layers yes)
		(zone_layer_connections "In1.Cu" "In4.Cu" "In6.Cu")
		(teardrops
			(best_length_ratio 0.4)
			(max_length 1)
			(best_width_ratio 0.9)
			(max_width 2)
			(curved_edges yes)
			(filter_ratio 0.9)
			(enabled yes)
			(allow_two_segments yes)
			(prefer_zone_connections yes)
		)
		(net 1)
	)
	(via
		(at 282.45 122.81)
		(size 0.45)
		(drill 0.1)
		(layers "F.Cu" "B.Cu")
		(remove_unused_layers yes)
		(keep_end_layers yes)
		(zone_layer_connections "In1.Cu" "In4.Cu" "In6.Cu")
		(teardrops
			(best_length_ratio 0.4)
			(max_length 1)
			(best_width_ratio 0.9)
			(max_width 2)
			(curved_edges yes)
			(filter_ratio 0.9)
			(enabled yes)
			(allow_two_segments yes)
			(prefer_zone_connections yes)
		)
		(net 1)
	)
	(via
		(at 287.95 154.31)
		(size 0.45)
		(drill 0.1)
		(layers "F.Cu" "B.Cu")
		(remove_unused_layers yes)
		(keep_end_layers yes)
		(zone_layer_connections "In1.Cu" "In4.Cu" "In6.Cu")
		(teardrops
			(best_length_ratio 0.4)
			(max_length 1)
			(best_width_ratio 0.9)
			(max_width 2)
			(curved_edges yes)
			(filter_ratio 0.9)
			(enabled yes)
			(allow_two_segments yes)
			(prefer_zone_connections yes)
		)
		(net 1)
	)
	(via
		(at 153.95 92.31)
		(size 0.45)
		(drill 0.1)
		(layers "F.Cu" "B.Cu")
		(remove_unused_layers yes)
		(keep_end_layers yes)
		(zone_layer_connections "In1.Cu" "In4.Cu" "In6.Cu")
		(teardrops
			(best_length_ratio 0.4)
			(max_length 1)
			(best_width_ratio 0.9)
			(max_width 2)
			(curved_edges yes)
			(filter_ratio 0.9)
			(enabled yes)
			(allow_two_segments yes)
			(prefer_zone_connections yes)
		)
		(net 1)
	)
	(via
		(at 152.05 168.72)
		(size 0.45)
		(drill 0.1)
		(layers "F.Cu" "B.Cu")
		(remove_unused_layers yes)
		(keep_end_layers yes)
		(zone_layer_connections "In1.Cu" "In4.Cu" "In6.Cu")
		(teardrops
			(best_length_ratio 0.4)
			(max_length 1)
			(best_width_ratio 0.9)
			(max_width 2)
			(curved_edges yes)
			(filter_ratio 0.9)
			(enabled yes)
			(allow_two_segments yes)
			(prefer_zone_connections yes)
		)
		(net 1)
	)
	(via
		(at 109.449999 170.81)
		(size 0.45)
		(drill 0.1)
		(layers "F.Cu" "B.Cu")
		(remove_unused_layers yes)
		(keep_end_layers yes)
		(zone_layer_connections "In1.Cu" "In4.Cu" "In6.Cu")
		(teardrops
			(best_length_ratio 0.4)
			(max_length 1)
			(best_width_ratio 0.9)
			(max_width 2)
			(curved_edges yes)
			(filter_ratio 0.9)
			(enabled yes)
			(allow_two_segments yes)
			(prefer_zone_connections yes)
		)
		(net 1)
	)
	(via
		(at 163.45 88.31)
		(size 0.45)
		(drill 0.1)
		(layers "F.Cu" "B.Cu")
		(remove_unused_layers yes)
		(keep_end_layers yes)
		(zone_layer_connections "In1.Cu" "In4.Cu" "In6.Cu")
		(teardrops
			(best_length_ratio 0.4)
			(max_length 1)
			(best_width_ratio 0.9)
			(max_width 2)
			(curved_edges yes)
			(filter_ratio 0.9)
			(enabled yes)
			(allow_two_segments yes)
			(prefer_zone_connections yes)
		)
		(net 1)
	)
	(via
		(at 95.45 90.81)
		(size 0.45)
		(drill 0.1)
		(layers "F.Cu" "B.Cu")
		(remove_unused_layers yes)
		(keep_end_layers yes)
		(zone_layer_connections "In1.Cu" "In4.Cu" "In6.Cu")
		(teardrops
			(best_length_ratio 0.4)
			(max_length 1)
			(best_width_ratio 0.9)
			(max_width 2)
			(curved_edges yes)
			(filter_ratio 0.9)
			(enabled yes)
			(allow_two_segments yes)
			(prefer_zone_connections yes)
		)
		(net 1)
	)
	(via
		(at 317.45 81.81)
		(size 0.45)
		(drill 0.1)
		(layers "F.Cu" "B.Cu")
		(remove_unused_layers yes)
		(keep_end_layers yes)
		(zone_layer_connections "In1.Cu" "In4.Cu" "In6.Cu")
		(teardrops
			(best_length_ratio 0.4)
			(max_length 1)
			(best_width_ratio 0.9)
			(max_width 2)
			(curved_edges yes)
			(filter_ratio 0.9)
			(enabled yes)
			(allow_two_segments yes)
			(prefer_zone_connections yes)
		)
		(net 1)
	)
	(via
		(at 101.45 130.81)
		(size 0.45)
		(drill 0.1)
		(layers "F.Cu" "B.Cu")
		(remove_unused_layers yes)
		(keep_end_layers yes)
		(zone_layer_connections "In1.Cu" "In4.Cu" "In6.Cu")
		(teardrops
			(best_length_ratio 0.4)
			(max_length 1)
			(best_width_ratio 0.9)
			(max_width 2)
			(curved_edges yes)
			(filter_ratio 0.9)
			(enabled yes)
			(allow_two_segments yes)
			(prefer_zone_connections yes)
		)
		(net 1)
	)
	(via
		(at 311.45 70.81)
		(size 0.45)
		(drill 0.1)
		(layers "F.Cu" "B.Cu")
		(remove_unused_layers yes)
		(keep_end_layers yes)
		(zone_layer_connections "In1.Cu" "In4.Cu" "In6.Cu")
		(teardrops
			(best_length_ratio 0.4)
			(max_length 1)
			(best_width_ratio 0.9)
			(max_width 2)
			(curved_edges yes)
			(filter_ratio 0.9)
			(enabled yes)
			(allow_two_segments yes)
			(prefer_zone_connections yes)
		)
		(net 1)
	)
	(via
		(at 276.45 116.81)
		(size 0.45)
		(drill 0.1)
		(layers "F.Cu" "B.Cu")
		(remove_unused_layers yes)
		(keep_end_layers yes)
		(zone_layer_connections "In1.Cu" "In4.Cu" "In6.Cu")
		(teardrops
			(best_length_ratio 0.4)
			(max_length 1)
			(best_width_ratio 0.9)
			(max_width 2)
			(curved_edges yes)
			(filter_ratio 0.9)
			(enabled yes)
			(allow_two_segments yes)
			(prefer_zone_connections yes)
		)
		(net 1)
	)
	(via
		(at 254.95 120.31)
		(size 0.45)
		(drill 0.1)
		(layers "F.Cu" "B.Cu")
		(remove_unused_layers yes)
		(keep_end_layers yes)
		(zone_layer_connections "In1.Cu" "In4.Cu" "In6.Cu")
		(teardrops
			(best_length_ratio 0.4)
			(max_length 1)
			(best_width_ratio 0.9)
			(max_width 2)
			(curved_edges yes)
			(filter_ratio 0.9)
			(enabled yes)
			(allow_two_segments yes)
			(prefer_zone_connections yes)
		)
		(net 1)
	)
	(via
		(at 284.45 102.31)
		(size 0.45)
		(drill 0.1)
		(layers "F.Cu" "B.Cu")
		(remove_unused_layers yes)
		(keep_end_layers yes)
		(zone_layer_connections "In1.Cu" "In4.Cu" "In6.Cu")
		(teardrops
			(best_length_ratio 0.4)
			(max_length 1)
			(best_width_ratio 0.9)
			(max_width 2)
			(curved_edges yes)
			(filter_ratio 0.9)
			(enabled yes)
			(allow_two_segments yes)
			(prefer_zone_connections yes)
		)
		(net 1)
	)
	(via
		(at 289.6 85.66)
		(size 0.45)
		(drill 0.1)
		(layers "F.Cu" "B.Cu")
		(remove_unused_layers yes)
		(keep_end_layers yes)
		(zone_layer_connections "In1.Cu" "In4.Cu" "In6.Cu")
		(teardrops
			(best_length_ratio 0.4)
			(max_length 1)
			(best_width_ratio 0.9)
			(max_width 2)
			(curved_edges yes)
			(filter_ratio 0.9)
			(enabled yes)
			(allow_two_segments yes)
			(prefer_zone_connections yes)
		)
		(net 1)
	)
	(via
		(at 225.45 84.81)
		(size 0.45)
		(drill 0.1)
		(layers "F.Cu" "B.Cu")
		(remove_unused_layers yes)
		(keep_end_layers yes)
		(zone_layer_connections "In1.Cu" "In4.Cu" "In6.Cu")
		(teardrops
			(best_length_ratio 0.4)
			(max_length 1)
			(best_width_ratio 0.9)
			(max_width 2)
			(curved_edges yes)
			(filter_ratio 0.9)
			(enabled yes)
			(allow_two_segments yes)
			(prefer_zone_connections yes)
		)
		(net 1)
	)
	(via
		(at 151.25 159.75)
		(size 0.45)
		(drill 0.1)
		(layers "F.Cu" "B.Cu")
		(remove_unused_layers yes)
		(keep_end_layers yes)
		(zone_layer_connections "In1.Cu" "In4.Cu" "In6.Cu")
		(teardrops
			(best_length_ratio 0.4)
			(max_length 1)
			(best_width_ratio 0.9)
			(max_width 2)
			(curved_edges yes)
			(filter_ratio 0.9)
			(enabled yes)
			(allow_two_segments yes)
			(prefer_zone_connections yes)
		)
		(net 1)
	)
	(via
		(at 253.45 121.81)
		(size 0.45)
		(drill 0.1)
		(layers "F.Cu" "B.Cu")
		(remove_unused_layers yes)
		(keep_end_layers yes)
		(zone_layer_connections "In1.Cu" "In4.Cu" "In6.Cu")
		(teardrops
			(best_length_ratio 0.4)
			(max_length 1)
			(best_width_ratio 0.9)
			(max_width 2)
			(curved_edges yes)
			(filter_ratio 0.9)
			(enabled yes)
			(allow_two_segments yes)
			(prefer_zone_connections yes)
		)
		(net 1)
	)
	(via
		(at 219.8 155.4)
		(size 0.45)
		(drill 0.1)
		(layers "F.Cu" "B.Cu")
		(teardrops
			(best_length_ratio 0.4)
			(max_length 1)
			(best_width_ratio 0.9)
			(max_width 2)
			(curved_edges yes)
			(filter_ratio 0.9)
			(enabled yes)
			(allow_two_segments yes)
			(prefer_zone_connections yes)
		)
		(net 1)
	)
	(via
		(at 213.45 87.81)
		(size 0.45)
		(drill 0.1)
		(layers "F.Cu" "B.Cu")
		(remove_unused_layers yes)
		(keep_end_layers yes)
		(free yes)
		(zone_layer_connections "In1.Cu" "In4.Cu" "In6.Cu")
		(teardrops
			(best_length_ratio 0.4)
			(max_length 1)
			(best_width_ratio 0.9)
			(max_width 2)
			(curved_edges yes)
			(filter_ratio 0.9)
			(enabled yes)
			(allow_two_segments yes)
			(prefer_zone_connections yes)
		)
		(net 1)
	)
	(via
		(at 102.45 127.81)
		(size 0.45)
		(drill 0.1)
		(layers "F.Cu" "B.Cu")
		(remove_unused_layers yes)
		(keep_end_layers yes)
		(zone_layer_connections "In1.Cu" "In4.Cu" "In6.Cu")
		(teardrops
			(best_length_ratio 0.4)
			(max_length 1)
			(best_width_ratio 0.9)
			(max_width 2)
			(curved_edges yes)
			(filter_ratio 0.9)
			(enabled yes)
			(allow_two_segments yes)
			(prefer_zone_connections yes)
		)
		(net 1)
	)
	(via
		(at 225.4 159.4)
		(size 0.45)
		(drill 0.1)
		(layers "F.Cu" "B.Cu")
		(teardrops
			(best_length_ratio 0.4)
			(max_length 1)
			(best_width_ratio 0.9)
			(max_width 2)
			(curved_edges yes)
			(filter_ratio 0.9)
			(enabled yes)
			(allow_two_segments yes)
			(prefer_zone_connections yes)
		)
		(net 1)
	)
	(via
		(at 282.95 170.81)
		(size 0.45)
		(drill 0.1)
		(layers "F.Cu" "B.Cu")
		(remove_unused_layers yes)
		(keep_end_layers yes)
		(zone_layer_connections "In1.Cu" "In4.Cu" "In6.Cu")
		(teardrops
			(best_length_ratio 0.4)
			(max_length 1)
			(best_width_ratio 0.9)
			(max_width 2)
			(curved_edges yes)
			(filter_ratio 0.9)
			(enabled yes)
			(allow_two_segments yes)
			(prefer_zone_connections yes)
		)
		(net 1)
	)
	(via
		(at 155.45 74.81)
		(size 0.45)
		(drill 0.1)
		(layers "F.Cu" "B.Cu")
		(remove_unused_layers yes)
		(keep_end_layers yes)
		(zone_layer_connections "In1.Cu" "In4.Cu" "In6.Cu")
		(teardrops
			(best_length_ratio 0.4)
			(max_length 1)
			(best_width_ratio 0.9)
			(max_width 2)
			(curved_edges yes)
			(filter_ratio 0.9)
			(enabled yes)
			(allow_two_segments yes)
			(prefer_zone_connections yes)
		)
		(net 1)
	)
	(via
		(at 314.4645 116.4465)
		(size 0.45)
		(drill 0.1)
		(layers "F.Cu" "B.Cu")
		(remove_unused_layers yes)
		(keep_end_layers yes)
		(free yes)
		(zone_layer_connections "In1.Cu" "In4.Cu" "In6.Cu")
		(teardrops
			(best_length_ratio 0.4)
			(max_length 1)
			(best_width_ratio 0.9)
			(max_width 2)
			(curved_edges yes)
			(filter_ratio 0.9)
			(enabled yes)
			(allow_two_segments yes)
			(prefer_zone_connections yes)
		)
		(net 1)
	)
	(via
		(at 198.1 153.1)
		(size 0.45)
		(drill 0.1)
		(layers "F.Cu" "B.Cu")
		(teardrops
			(best_length_ratio 0.4)
			(max_length 1)
			(best_width_ratio 0.9)
			(max_width 2)
			(curved_edges yes)
			(filter_ratio 0.9)
			(enabled yes)
			(allow_two_segments yes)
			(prefer_zone_connections yes)
		)
		(net 1)
	)
	(via
		(at 110.83 169.435)
		(size 0.45)
		(drill 0.1)
		(layers "F.Cu" "B.Cu")
		(remove_unused_layers yes)
		(keep_end_layers yes)
		(zone_layer_connections "In1.Cu" "In4.Cu" "In6.Cu")
		(teardrops
			(best_length_ratio 0.4)
			(max_length 1)
			(best_width_ratio 0.9)
			(max_width 2)
			(curved_edges yes)
			(filter_ratio 0.9)
			(enabled yes)
			(allow_two_segments yes)
			(prefer_zone_connections yes)
		)
		(net 1)
	)
	(via
		(at 107.8 128.6)
		(size 0.45)
		(drill 0.1)
		(layers "F.Cu" "B.Cu")
		(teardrops
			(best_length_ratio 0.4)
			(max_length 1)
			(best_width_ratio 0.9)
			(max_width 2)
			(curved_edges yes)
			(filter_ratio 0.9)
			(enabled yes)
			(allow_two_segments yes)
			(prefer_zone_connections yes)
		)
		(net 1)
	)
	(via
		(at 220.328476 128.592195)
		(size 0.45)
		(drill 0.1)
		(layers "F.Cu" "B.Cu")
		(remove_unused_layers yes)
		(keep_end_layers yes)
		(zone_layer_connections "In1.Cu" "In4.Cu" "In6.Cu")
		(teardrops
			(best_length_ratio 0.4)
			(max_length 1)
			(best_width_ratio 0.9)
			(max_width 2)
			(curved_edges yes)
			(filter_ratio 0.9)
			(enabled yes)
			(allow_two_segments yes)
			(prefer_zone_connections yes)
		)
		(net 1)
	)
	(via
		(at 309.174999 119.68)
		(size 0.45)
		(drill 0.1)
		(layers "F.Cu" "B.Cu")
		(remove_unused_layers yes)
		(keep_end_layers yes)
		(zone_layer_connections "In1.Cu" "In4.Cu" "In6.Cu")
		(teardrops
			(best_length_ratio 0.4)
			(max_length 1)
			(best_width_ratio 0.9)
			(max_width 2)
			(curved_edges yes)
			(filter_ratio 0.9)
			(enabled yes)
			(allow_two_segments yes)
			(prefer_zone_connections yes)
		)
		(net 1)
	)
	(via
		(at 104.45 138.81)
		(size 0.45)
		(drill 0.1)
		(layers "F.Cu" "B.Cu")
		(remove_unused_layers yes)
		(keep_end_layers yes)
		(zone_layer_connections "In1.Cu" "In4.Cu" "In6.Cu")
		(teardrops
			(best_length_ratio 0.4)
			(max_length 1)
			(best_width_ratio 0.9)
			(max_width 2)
			(curved_edges yes)
			(filter_ratio 0.9)
			(enabled yes)
			(allow_two_segments yes)
			(prefer_zone_connections yes)
		)
		(net 1)
	)
	(via
		(at 205.75 93.81)
		(size 0.45)
		(drill 0.1)
		(layers "F.Cu" "B.Cu")
		(remove_unused_layers yes)
		(keep_end_layers yes)
		(zone_layer_connections "In1.Cu" "In4.Cu" "In6.Cu")
		(teardrops
			(best_length_ratio 0.4)
			(max_length 1)
			(best_width_ratio 0.9)
			(max_width 2)
			(curved_edges yes)
			(filter_ratio 0.9)
			(enabled yes)
			(allow_two_segments yes)
			(prefer_zone_connections yes)
		)
		(net 1)
	)
	(via
		(at 279.45 122.81)
		(size 0.45)
		(drill 0.1)
		(layers "F.Cu" "B.Cu")
		(remove_unused_layers yes)
		(keep_end_layers yes)
		(zone_layer_connections "In1.Cu" "In4.Cu" "In6.Cu")
		(teardrops
			(best_length_ratio 0.4)
			(max_length 1)
			(best_width_ratio 0.9)
			(max_width 2)
			(curved_edges yes)
			(filter_ratio 0.9)
			(enabled yes)
			(allow_two_segments yes)
			(prefer_zone_connections yes)
		)
		(net 1)
	)
	(via
		(at 127.208062 108.243897)
		(size 0.45)
		(drill 0.1)
		(layers "F.Cu" "B.Cu")
		(remove_unused_layers yes)
		(keep_end_layers yes)
		(zone_layer_connections "In1.Cu" "In4.Cu" "In6.Cu")
		(teardrops
			(best_length_ratio 0.4)
			(max_length 1)
			(best_width_ratio 0.9)
			(max_width 2)
			(curved_edges yes)
			(filter_ratio 0.9)
			(enabled yes)
			(allow_two_segments yes)
			(prefer_zone_connections yes)
		)
		(net 1)
	)
	(via
		(at 199.525 157.875)
		(size 0.45)
		(drill 0.1)
		(layers "F.Cu" "B.Cu")
		(teardrops
			(best_length_ratio 0.4)
			(max_length 1)
			(best_width_ratio 0.9)
			(max_width 2)
			(curved_edges yes)
			(filter_ratio 0.9)
			(enabled yes)
			(allow_two_segments yes)
			(prefer_zone_connections yes)
		)
		(net 1)
	)
	(via
		(at 208.875 167.1)
		(size 0.45)
		(drill 0.1)
		(layers "F.Cu" "B.Cu")
		(teardrops
			(best_length_ratio 0.4)
			(max_length 1)
			(best_width_ratio 0.9)
			(max_width 2)
			(curved_edges yes)
			(filter_ratio 0.9)
			(enabled yes)
			(allow_two_segments yes)
			(prefer_zone_connections yes)
		)
		(net 1)
	)
	(via
		(at 113.45 80.81)
		(size 0.45)
		(drill 0.1)
		(layers "F.Cu" "B.Cu")
		(remove_unused_layers yes)
		(keep_end_layers yes)
		(zone_layer_connections "In1.Cu" "In4.Cu" "In6.Cu")
		(teardrops
			(best_length_ratio 0.4)
			(max_length 1)
			(best_width_ratio 0.9)
			(max_width 2)
			(curved_edges yes)
			(filter_ratio 0.9)
			(enabled yes)
			(allow_two_segments yes)
			(prefer_zone_connections yes)
		)
		(net 1)
	)
	(via
		(at 196 169.899)
		(size 0.45)
		(drill 0.1)
		(layers "F.Cu" "B.Cu")
		(teardrops
			(best_length_ratio 0.4)
			(max_length 1)
			(best_width_ratio 0.9)
			(max_width 2)
			(curved_edges yes)
			(filter_ratio 0.9)
			(enabled yes)
			(allow_two_segments yes)
			(prefer_zone_connections yes)
		)
		(net 1)
	)
	(via
		(at 315.4645 101.636501)
		(size 0.45)
		(drill 0.1)
		(layers "F.Cu" "B.Cu")
		(remove_unused_layers yes)
		(keep_end_layers yes)
		(free yes)
		(zone_layer_connections "In1.Cu" "In4.Cu" "In6.Cu")
		(teardrops
			(best_length_ratio 0.4)
			(max_length 1)
			(best_width_ratio 0.9)
			(max_width 2)
			(curved_edges yes)
			(filter_ratio 0.9)
			(enabled yes)
			(allow_two_segments yes)
			(prefer_zone_connections yes)
		)
		(net 1)
	)
	(via
		(at 155.291089 82.0779)
		(size 0.45)
		(drill 0.1)
		(layers "F.Cu" "B.Cu")
		(remove_unused_layers yes)
		(keep_end_layers yes)
		(zone_layer_connections "In1.Cu" "In4.Cu" "In6.Cu")
		(teardrops
			(best_length_ratio 0.4)
			(max_length 1)
			(best_width_ratio 0.9)
			(max_width 2)
			(curved_edges yes)
			(filter_ratio 0.9)
			(enabled yes)
			(allow_two_segments yes)
			(prefer_zone_connections yes)
		)
		(net 1)
	)
	(via
		(at 152.45 134.86)
		(size 0.45)
		(drill 0.1)
		(layers "F.Cu" "B.Cu")
		(remove_unused_layers yes)
		(keep_end_layers yes)
		(zone_layer_connections "In1.Cu" "In4.Cu" "In6.Cu")
		(teardrops
			(best_length_ratio 0.4)
			(max_length 1)
			(best_width_ratio 0.9)
			(max_width 2)
			(curved_edges yes)
			(filter_ratio 0.9)
			(enabled yes)
			(allow_two_segments yes)
			(prefer_zone_connections yes)
		)
		(net 1)
	)
	(via
		(at 276.45 107.81)
		(size 0.45)
		(drill 0.1)
		(layers "F.Cu" "B.Cu")
		(remove_unused_layers yes)
		(keep_end_layers yes)
		(zone_layer_connections "In1.Cu" "In4.Cu" "In6.Cu")
		(teardrops
			(best_length_ratio 0.4)
			(max_length 1)
			(best_width_ratio 0.9)
			(max_width 2)
			(curved_edges yes)
			(filter_ratio 0.9)
			(enabled yes)
			(allow_two_segments yes)
			(prefer_zone_connections yes)
		)
		(net 1)
	)
	(via
		(at 97.45 126.81)
		(size 0.45)
		(drill 0.1)
		(layers "F.Cu" "B.Cu")
		(remove_unused_layers yes)
		(keep_end_layers yes)
		(zone_layer_connections "In1.Cu" "In4.Cu" "In6.Cu")
		(teardrops
			(best_length_ratio 0.4)
			(max_length 1)
			(best_width_ratio 0.9)
			(max_width 2)
			(curved_edges yes)
			(filter_ratio 0.9)
			(enabled yes)
			(allow_two_segments yes)
			(prefer_zone_connections yes)
		)
		(net 1)
	)
	(via
		(at 125.45 157.81)
		(size 0.45)
		(drill 0.1)
		(layers "F.Cu" "B.Cu")
		(remove_unused_layers yes)
		(keep_end_layers yes)
		(zone_layer_connections "In1.Cu" "In4.Cu" "In6.Cu")
		(teardrops
			(best_length_ratio 0.4)
			(max_length 1)
			(best_width_ratio 0.9)
			(max_width 2)
			(curved_edges yes)
			(filter_ratio 0.9)
			(enabled yes)
			(allow_two_segments yes)
			(prefer_zone_connections yes)
		)
		(net 1)
	)
	(via
		(at 97.45 68.81)
		(size 0.45)
		(drill 0.1)
		(layers "F.Cu" "B.Cu")
		(remove_unused_layers yes)
		(keep_end_layers yes)
		(zone_layer_connections "In1.Cu" "In4.Cu" "In6.Cu")
		(teardrops
			(best_length_ratio 0.4)
			(max_length 1)
			(best_width_ratio 0.9)
			(max_width 2)
			(curved_edges yes)
			(filter_ratio 0.9)
			(enabled yes)
			(allow_two_segments yes)
			(prefer_zone_connections yes)
		)
		(net 1)
	)
	(via
		(at 230.6 152.3)
		(size 0.45)
		(drill 0.1)
		(layers "F.Cu" "B.Cu")
		(teardrops
			(best_length_ratio 0.4)
			(max_length 1)
			(best_width_ratio 0.9)
			(max_width 2)
			(curved_edges yes)
			(filter_ratio 0.9)
			(enabled yes)
			(allow_two_segments yes)
			(prefer_zone_connections yes)
		)
		(net 1)
	)
	(via
		(at 194.45 100.31)
		(size 0.45)
		(drill 0.1)
		(layers "F.Cu" "B.Cu")
		(remove_unused_layers yes)
		(keep_end_layers yes)
		(free yes)
		(zone_layer_connections "In1.Cu" "In4.Cu" "In6.Cu")
		(teardrops
			(best_length_ratio 0.4)
			(max_length 1)
			(best_width_ratio 0.9)
			(max_width 2)
			(curved_edges yes)
			(filter_ratio 0.9)
			(enabled yes)
			(allow_two_segments yes)
			(prefer_zone_connections yes)
		)
		(net 1)
	)
	(via
		(at 126.184839 143.449318)
		(size 0.45)
		(drill 0.1)
		(layers "F.Cu" "B.Cu")
		(remove_unused_layers yes)
		(keep_end_layers yes)
		(zone_layer_connections "In1.Cu" "In4.Cu" "In6.Cu")
		(teardrops
			(best_length_ratio 0.4)
			(max_length 1)
			(best_width_ratio 0.9)
			(max_width 2)
			(curved_edges yes)
			(filter_ratio 0.9)
			(enabled yes)
			(allow_two_segments yes)
			(prefer_zone_connections yes)
		)
		(net 1)
	)
	(via
		(at 131.3 86.210002)
		(size 0.45)
		(drill 0.1)
		(layers "F.Cu" "B.Cu")
		(remove_unused_layers yes)
		(keep_end_layers yes)
		(zone_layer_connections "In1.Cu" "In4.Cu" "In6.Cu")
		(teardrops
			(best_length_ratio 0.4)
			(max_length 1)
			(best_width_ratio 0.9)
			(max_width 2)
			(curved_edges yes)
			(filter_ratio 0.9)
			(enabled yes)
			(allow_two_segments yes)
			(prefer_zone_connections yes)
		)
		(net 1)
	)
	(via
		(at 149.45 132.86)
		(size 0.45)
		(drill 0.1)
		(layers "F.Cu" "B.Cu")
		(remove_unused_layers yes)
		(keep_end_layers yes)
		(zone_layer_connections "In1.Cu" "In4.Cu" "In6.Cu")
		(teardrops
			(best_length_ratio 0.4)
			(max_length 1)
			(best_width_ratio 0.9)
			(max_width 2)
			(curved_edges yes)
			(filter_ratio 0.9)
			(enabled yes)
			(allow_two_segments yes)
			(prefer_zone_connections yes)
		)
		(net 1)
	)
	(via
		(at 296.72 98.670999)
		(size 0.45)
		(drill 0.1)
		(layers "F.Cu" "B.Cu")
		(remove_unused_layers yes)
		(keep_end_layers yes)
		(zone_layer_connections "In1.Cu" "In4.Cu" "In6.Cu")
		(teardrops
			(best_length_ratio 0.4)
			(max_length 1)
			(best_width_ratio 0.9)
			(max_width 2)
			(curved_edges yes)
			(filter_ratio 0.9)
			(enabled yes)
			(allow_two_segments yes)
			(prefer_zone_connections yes)
		)
		(net 1)
	)
	(via
		(at 297.95 109.81)
		(size 0.45)
		(drill 0.1)
		(layers "F.Cu" "B.Cu")
		(remove_unused_layers yes)
		(keep_end_layers yes)
		(zone_layer_connections "In1.Cu" "In4.Cu" "In6.Cu")
		(teardrops
			(best_length_ratio 0.4)
			(max_length 1)
			(best_width_ratio 0.9)
			(max_width 2)
			(curved_edges yes)
			(filter_ratio 0.9)
			(enabled yes)
			(allow_two_segments yes)
			(prefer_zone_connections yes)
		)
		(net 1)
	)
	(via
		(at 279.45 107.81)
		(size 0.45)
		(drill 0.1)
		(layers "F.Cu" "B.Cu")
		(remove_unused_layers yes)
		(keep_end_layers yes)
		(zone_layer_connections "In1.Cu" "In4.Cu" "In6.Cu")
		(teardrops
			(best_length_ratio 0.4)
			(max_length 1)
			(best_width_ratio 0.9)
			(max_width 2)
			(curved_edges yes)
			(filter_ratio 0.9)
			(enabled yes)
			(allow_two_segments yes)
			(prefer_zone_connections yes)
		)
		(net 1)
	)
	(via
		(at 185.975 152.225)
		(size 0.45)
		(drill 0.1)
		(layers "F.Cu" "B.Cu")
		(teardrops
			(best_length_ratio 0.4)
			(max_length 1)
			(best_width_ratio 0.9)
			(max_width 2)
			(curved_edges yes)
			(filter_ratio 0.9)
			(enabled yes)
			(allow_two_segments yes)
			(prefer_zone_connections yes)
		)
		(net 1)
	)
	(via
		(at 294.949999 170.81)
		(size 0.45)
		(drill 0.1)
		(layers "F.Cu" "B.Cu")
		(remove_unused_layers yes)
		(keep_end_layers yes)
		(zone_layer_connections "In1.Cu" "In4.Cu" "In6.Cu")
		(teardrops
			(best_length_ratio 0.4)
			(max_length 1)
			(best_width_ratio 0.9)
			(max_width 2)
			(curved_edges yes)
			(filter_ratio 0.9)
			(enabled yes)
			(allow_two_segments yes)
			(prefer_zone_connections yes)
		)
		(net 1)
	)
	(via
		(at 140.45 78.31)
		(size 0.45)
		(drill 0.1)
		(layers "F.Cu" "B.Cu")
		(remove_unused_layers yes)
		(keep_end_layers yes)
		(zone_layer_connections "In1.Cu" "In4.Cu" "In6.Cu")
		(teardrops
			(best_length_ratio 0.4)
			(max_length 1)
			(best_width_ratio 0.9)
			(max_width 2)
			(curved_edges yes)
			(filter_ratio 0.9)
			(enabled yes)
			(allow_two_segments yes)
			(prefer_zone_connections yes)
		)
		(net 1)
	)
	(via
		(at 96.95 79.81)
		(size 0.45)
		(drill 0.1)
		(layers "F.Cu" "B.Cu")
		(remove_unused_layers yes)
		(keep_end_layers yes)
		(zone_layer_connections "In1.Cu" "In4.Cu" "In6.Cu")
		(teardrops
			(best_length_ratio 0.4)
			(max_length 1)
			(best_width_ratio 0.9)
			(max_width 2)
			(curved_edges yes)
			(filter_ratio 0.9)
			(enabled yes)
			(allow_two_segments yes)
			(prefer_zone_connections yes)
		)
		(net 1)
	)
	(via
		(at 289.95 113.31)
		(size 0.45)
		(drill 0.1)
		(layers "F.Cu" "B.Cu")
		(remove_unused_layers yes)
		(keep_end_layers yes)
		(zone_layer_connections "In1.Cu" "In4.Cu" "In6.Cu")
		(teardrops
			(best_length_ratio 0.4)
			(max_length 1)
			(best_width_ratio 0.9)
			(max_width 2)
			(curved_edges yes)
			(filter_ratio 0.9)
			(enabled yes)
			(allow_two_segments yes)
			(prefer_zone_connections yes)
		)
		(net 1)
	)
	(via
		(at 241.45 118.81)
		(size 0.45)
		(drill 0.1)
		(layers "F.Cu" "B.Cu")
		(remove_unused_layers yes)
		(keep_end_layers yes)
		(zone_layer_connections "In1.Cu" "In4.Cu" "In6.Cu")
		(teardrops
			(best_length_ratio 0.4)
			(max_length 1)
			(best_width_ratio 0.9)
			(max_width 2)
			(curved_edges yes)
			(filter_ratio 0.9)
			(enabled yes)
			(allow_two_segments yes)
			(prefer_zone_connections yes)
		)
		(net 1)
	)
	(via
		(at 311.45 87.81)
		(size 0.45)
		(drill 0.1)
		(layers "F.Cu" "B.Cu")
		(remove_unused_layers yes)
		(keep_end_layers yes)
		(zone_layer_connections "In1.Cu" "In4.Cu" "In6.Cu")
		(teardrops
			(best_length_ratio 0.4)
			(max_length 1)
			(best_width_ratio 0.9)
			(max_width 2)
			(curved_edges yes)
			(filter_ratio 0.9)
			(enabled yes)
			(allow_two_segments yes)
			(prefer_zone_connections yes)
		)
		(net 1)
	)
	(via
		(at 152.5 122.6)
		(size 0.45)
		(drill 0.1)
		(layers "F.Cu" "B.Cu")
		(remove_unused_layers yes)
		(keep_end_layers yes)
		(zone_layer_connections "In1.Cu" "In4.Cu" "In6.Cu")
		(teardrops
			(best_length_ratio 0.4)
			(max_length 1)
			(best_width_ratio 0.9)
			(max_width 2)
			(curved_edges yes)
			(filter_ratio 0.9)
			(enabled yes)
			(allow_two_segments yes)
			(prefer_zone_connections yes)
		)
		(net 1)
	)
	(via
		(at 237.45 90.81)
		(size 0.45)
		(drill 0.1)
		(layers "F.Cu" "B.Cu")
		(remove_unused_layers yes)
		(keep_end_layers yes)
		(zone_layer_connections "In1.Cu" "In4.Cu" "In6.Cu")
		(teardrops
			(best_length_ratio 0.4)
			(max_length 1)
			(best_width_ratio 0.9)
			(max_width 2)
			(curved_edges yes)
			(filter_ratio 0.9)
			(enabled yes)
			(allow_two_segments yes)
			(prefer_zone_connections yes)
		)
		(net 1)
	)
	(via
		(at 150.45 133.86)
		(size 0.45)
		(drill 0.1)
		(layers "F.Cu" "B.Cu")
		(remove_unused_layers yes)
		(keep_end_layers yes)
		(zone_layer_connections "In1.Cu" "In4.Cu" "In6.Cu")
		(teardrops
			(best_length_ratio 0.4)
			(max_length 1)
			(best_width_ratio 0.9)
			(max_width 2)
			(curved_edges yes)
			(filter_ratio 0.9)
			(enabled yes)
			(allow_two_segments yes)
			(prefer_zone_connections yes)
		)
		(net 1)
	)
	(via
		(at 205.95 87.31)
		(size 0.45)
		(drill 0.1)
		(layers "F.Cu" "B.Cu")
		(remove_unused_layers yes)
		(keep_end_layers yes)
		(zone_layer_connections "In1.Cu" "In4.Cu" "In6.Cu")
		(teardrops
			(best_length_ratio 0.4)
			(max_length 1)
			(best_width_ratio 0.9)
			(max_width 2)
			(curved_edges yes)
			(filter_ratio 0.9)
			(enabled yes)
			(allow_two_segments yes)
			(prefer_zone_connections yes)
		)
		(net 1)
	)
	(via
		(at 300.95 170.81)
		(size 0.45)
		(drill 0.1)
		(layers "F.Cu" "B.Cu")
		(remove_unused_layers yes)
		(keep_end_layers yes)
		(zone_layer_connections "In1.Cu" "In4.Cu" "In6.Cu")
		(teardrops
			(best_length_ratio 0.4)
			(max_length 1)
			(best_width_ratio 0.9)
			(max_width 2)
			(curved_edges yes)
			(filter_ratio 0.9)
			(enabled yes)
			(allow_two_segments yes)
			(prefer_zone_connections yes)
		)
		(net 1)
	)
	(via
		(at 260.95 129.31)
		(size 0.45)
		(drill 0.1)
		(layers "F.Cu" "B.Cu")
		(remove_unused_layers yes)
		(keep_end_layers yes)
		(zone_layer_connections "In1.Cu" "In4.Cu" "In6.Cu")
		(teardrops
			(best_length_ratio 0.4)
			(max_length 1)
			(best_width_ratio 0.9)
			(max_width 2)
			(curved_edges yes)
			(filter_ratio 0.9)
			(enabled yes)
			(allow_two_segments yes)
			(prefer_zone_connections yes)
		)
		(net 1)
	)
	(via
		(at 118.9 147.361)
		(size 0.45)
		(drill 0.1)
		(layers "F.Cu" "B.Cu")
		(remove_unused_layers yes)
		(keep_end_layers yes)
		(zone_layer_connections "In1.Cu" "In4.Cu" "In6.Cu")
		(teardrops
			(best_length_ratio 0.4)
			(max_length 1)
			(best_width_ratio 0.9)
			(max_width 2)
			(curved_edges yes)
			(filter_ratio 0.9)
			(enabled yes)
			(allow_two_segments yes)
			(prefer_zone_connections yes)
		)
		(net 1)
	)
	(via
		(at 214.16 127.2)
		(size 0.45)
		(drill 0.1)
		(layers "F.Cu" "B.Cu")
		(remove_unused_layers yes)
		(keep_end_layers yes)
		(zone_layer_connections "In1.Cu" "In4.Cu" "In6.Cu")
		(teardrops
			(best_length_ratio 0.4)
			(max_length 1)
			(best_width_ratio 0.9)
			(max_width 2)
			(curved_edges yes)
			(filter_ratio 0.9)
			(enabled yes)
			(allow_two_segments yes)
			(prefer_zone_connections yes)
		)
		(net 1)
	)
	(via
		(at 146.020001 147.633964)
		(size 0.45)
		(drill 0.1)
		(layers "F.Cu" "B.Cu")
		(remove_unused_layers yes)
		(keep_end_layers yes)
		(zone_layer_connections "In1.Cu" "In4.Cu" "In6.Cu")
		(teardrops
			(best_length_ratio 0.4)
			(max_length 1)
			(best_width_ratio 0.9)
			(max_width 2)
			(curved_edges yes)
			(filter_ratio 0.9)
			(enabled yes)
			(allow_two_segments yes)
			(prefer_zone_connections yes)
		)
		(net 1)
	)
	(via
		(at 225.25 149.85)
		(size 0.45)
		(drill 0.1)
		(layers "F.Cu" "B.Cu")
		(teardrops
			(best_length_ratio 0.4)
			(max_length 1)
			(best_width_ratio 0.9)
			(max_width 2)
			(curved_edges yes)
			(filter_ratio 0.9)
			(enabled yes)
			(allow_two_segments yes)
			(prefer_zone_connections yes)
		)
		(net 1)
	)
	(via
		(at 234.45 90.81)
		(size 0.45)
		(drill 0.1)
		(layers "F.Cu" "B.Cu")
		(remove_unused_layers yes)
		(keep_end_layers yes)
		(free yes)
		(zone_layer_connections "In1.Cu" "In4.Cu" "In6.Cu")
		(teardrops
			(best_length_ratio 0.4)
			(max_length 1)
			(best_width_ratio 0.9)
			(max_width 2)
			(curved_edges yes)
			(filter_ratio 0.9)
			(enabled yes)
			(allow_two_segments yes)
			(prefer_zone_connections yes)
		)
		(net 1)
	)
	(via
		(at 115.809998 75.175)
		(size 0.45)
		(drill 0.1)
		(layers "F.Cu" "B.Cu")
		(remove_unused_layers yes)
		(keep_end_layers yes)
		(zone_layer_connections "In1.Cu" "In4.Cu" "In6.Cu")
		(teardrops
			(best_length_ratio 0.4)
			(max_length 1)
			(best_width_ratio 0.9)
			(max_width 2)
			(curved_edges yes)
			(filter_ratio 0.9)
			(enabled yes)
			(allow_two_segments yes)
			(prefer_zone_connections yes)
		)
		(net 1)
	)
	(via
		(at 96.45 127.81)
		(size 0.45)
		(drill 0.1)
		(layers "F.Cu" "B.Cu")
		(remove_unused_layers yes)
		(keep_end_layers yes)
		(zone_layer_connections "In1.Cu" "In4.Cu" "In6.Cu")
		(teardrops
			(best_length_ratio 0.4)
			(max_length 1)
			(best_width_ratio 0.9)
			(max_width 2)
			(curved_edges yes)
			(filter_ratio 0.9)
			(enabled yes)
			(allow_two_segments yes)
			(prefer_zone_connections yes)
		)
		(net 1)
	)
	(via
		(at 183.45 71.81)
		(size 0.45)
		(drill 0.1)
		(layers "F.Cu" "B.Cu")
		(remove_unused_layers yes)
		(keep_end_layers yes)
		(zone_layer_connections "In1.Cu" "In4.Cu" "In6.Cu")
		(teardrops
			(best_length_ratio 0.4)
			(max_length 1)
			(best_width_ratio 0.9)
			(max_width 2)
			(curved_edges yes)
			(filter_ratio 0.9)
			(enabled yes)
			(allow_two_segments yes)
			(prefer_zone_connections yes)
		)
		(net 1)
	)
	(via
		(at 115.15 146.801)
		(size 0.45)
		(drill 0.1)
		(layers "F.Cu" "B.Cu")
		(remove_unused_layers yes)
		(keep_end_layers yes)
		(zone_layer_connections "In1.Cu" "In4.Cu" "In6.Cu")
		(teardrops
			(best_length_ratio 0.4)
			(max_length 1)
			(best_width_ratio 0.9)
			(max_width 2)
			(curved_edges yes)
			(filter_ratio 0.9)
			(enabled yes)
			(allow_two_segments yes)
			(prefer_zone_connections yes)
		)
		(net 1)
	)
	(via
		(at 313.648 167.26)
		(size 0.45)
		(drill 0.1)
		(layers "F.Cu" "B.Cu")
		(remove_unused_layers yes)
		(keep_end_layers yes)
		(zone_layer_connections "In1.Cu" "In4.Cu" "In6.Cu")
		(teardrops
			(best_length_ratio 0.4)
			(max_length 1)
			(best_width_ratio 0.9)
			(max_width 2)
			(curved_edges yes)
			(filter_ratio 0.9)
			(enabled yes)
			(allow_two_segments yes)
			(prefer_zone_connections yes)
		)
		(net 1)
	)
	(via
		(at 259.45 118.81)
		(size 0.45)
		(drill 0.1)
		(layers "F.Cu" "B.Cu")
		(remove_unused_layers yes)
		(keep_end_layers yes)
		(zone_layer_connections "In1.Cu" "In4.Cu" "In6.Cu")
		(teardrops
			(best_length_ratio 0.4)
			(max_length 1)
			(best_width_ratio 0.9)
			(max_width 2)
			(curved_edges yes)
			(filter_ratio 0.9)
			(enabled yes)
			(allow_two_segments yes)
			(prefer_zone_connections yes)
		)
		(net 1)
	)
	(via
		(at 280.95 121.31)
		(size 0.45)
		(drill 0.1)
		(layers "F.Cu" "B.Cu")
		(remove_unused_layers yes)
		(keep_end_layers yes)
		(zone_layer_connections "In1.Cu" "In4.Cu" "In6.Cu")
		(teardrops
			(best_length_ratio 0.4)
			(max_length 1)
			(best_width_ratio 0.9)
			(max_width 2)
			(curved_edges yes)
			(filter_ratio 0.9)
			(enabled yes)
			(allow_two_segments yes)
			(prefer_zone_connections yes)
		)
		(net 1)
	)
	(via
		(at 136.279664 98.711911)
		(size 0.45)
		(drill 0.1)
		(layers "F.Cu" "B.Cu")
		(remove_unused_layers yes)
		(keep_end_layers yes)
		(zone_layer_connections "In1.Cu" "In4.Cu" "In6.Cu")
		(teardrops
			(best_length_ratio 0.4)
			(max_length 1)
			(best_width_ratio 0.9)
			(max_width 2)
			(curved_edges yes)
			(filter_ratio 0.9)
			(enabled yes)
			(allow_two_segments yes)
			(prefer_zone_connections yes)
		)
		(net 1)
	)
	(via
		(at 117.45 163.81)
		(size 0.45)
		(drill 0.1)
		(layers "F.Cu" "B.Cu")
		(remove_unused_layers yes)
		(keep_end_layers yes)
		(zone_layer_connections "In1.Cu" "In4.Cu" "In6.Cu")
		(teardrops
			(best_length_ratio 0.4)
			(max_length 1)
			(best_width_ratio 0.9)
			(max_width 2)
			(curved_edges yes)
			(filter_ratio 0.9)
			(enabled yes)
			(allow_two_segments yes)
			(prefer_zone_connections yes)
		)
		(net 1)
	)
	(via
		(at 155.45 137.86)
		(size 0.45)
		(drill 0.1)
		(layers "F.Cu" "B.Cu")
		(remove_unused_layers yes)
		(keep_end_layers yes)
		(zone_layer_connections "In1.Cu" "In4.Cu" "In6.Cu")
		(teardrops
			(best_length_ratio 0.4)
			(max_length 1)
			(best_width_ratio 0.9)
			(max_width 2)
			(curved_edges yes)
			(filter_ratio 0.9)
			(enabled yes)
			(allow_two_segments yes)
			(prefer_zone_connections yes)
		)
		(net 1)
	)
	(via
		(at 155.45 69.81)
		(size 0.45)
		(drill 0.1)
		(layers "F.Cu" "B.Cu")
		(remove_unused_layers yes)
		(keep_end_layers yes)
		(zone_layer_connections "In1.Cu" "In4.Cu" "In6.Cu")
		(teardrops
			(best_length_ratio 0.4)
			(max_length 1)
			(best_width_ratio 0.9)
			(max_width 2)
			(curved_edges yes)
			(filter_ratio 0.9)
			(enabled yes)
			(allow_two_segments yes)
			(prefer_zone_connections yes)
		)
		(net 1)
	)
	(via
		(at 103.19 162.61)
		(size 0.45)
		(drill 0.1)
		(layers "F.Cu" "B.Cu")
		(remove_unused_layers yes)
		(keep_end_layers yes)
		(zone_layer_connections "In1.Cu" "In4.Cu" "In6.Cu")
		(teardrops
			(best_length_ratio 0.4)
			(max_length 1)
			(best_width_ratio 0.9)
			(max_width 2)
			(curved_edges yes)
			(filter_ratio 0.9)
			(enabled yes)
			(allow_two_segments yes)
			(prefer_zone_connections yes)
		)
		(net 1)
	)
	(via
		(at 132.29 133.86)
		(size 0.45)
		(drill 0.1)
		(layers "F.Cu" "B.Cu")
		(remove_unused_layers yes)
		(keep_end_layers yes)
		(zone_layer_connections "In1.Cu" "In4.Cu" "In6.Cu")
		(teardrops
			(best_length_ratio 0.4)
			(max_length 1)
			(best_width_ratio 0.9)
			(max_width 2)
			(curved_edges yes)
			(filter_ratio 0.9)
			(enabled yes)
			(allow_two_segments yes)
			(prefer_zone_connections yes)
		)
		(net 1)
	)
	(via
		(at 199.94639 82.787837)
		(size 0.45)
		(drill 0.1)
		(layers "F.Cu" "B.Cu")
		(remove_unused_layers yes)
		(keep_end_layers yes)
		(zone_layer_connections "In1.Cu" "In4.Cu" "In6.Cu")
		(teardrops
			(best_length_ratio 0.4)
			(max_length 1)
			(best_width_ratio 0.9)
			(max_width 2)
			(curved_edges yes)
			(filter_ratio 0.9)
			(enabled yes)
			(allow_two_segments yes)
			(prefer_zone_connections yes)
		)
		(net 1)
	)
	(via
		(at 191.05 152.275)
		(size 0.45)
		(drill 0.1)
		(layers "F.Cu" "B.Cu")
		(teardrops
			(best_length_ratio 0.4)
			(max_length 1)
			(best_width_ratio 0.9)
			(max_width 2)
			(curved_edges yes)
			(filter_ratio 0.9)
			(enabled yes)
			(allow_two_segments yes)
			(prefer_zone_connections yes)
		)
		(net 1)
	)
	(via
		(at 95.45 82.81)
		(size 0.45)
		(drill 0.1)
		(layers "F.Cu" "B.Cu")
		(remove_unused_layers yes)
		(keep_end_layers yes)
		(zone_layer_connections "In1.Cu" "In4.Cu" "In6.Cu")
		(teardrops
			(best_length_ratio 0.4)
			(max_length 1)
			(best_width_ratio 0.9)
			(max_width 2)
			(curved_edges yes)
			(filter_ratio 0.9)
			(enabled yes)
			(allow_two_segments yes)
			(prefer_zone_connections yes)
		)
		(net 1)
	)
	(via
		(at 286.45 139.81)
		(size 0.45)
		(drill 0.1)
		(layers "F.Cu" "B.Cu")
		(remove_unused_layers yes)
		(keep_end_layers yes)
		(zone_layer_connections "In1.Cu" "In4.Cu" "In6.Cu")
		(teardrops
			(best_length_ratio 0.4)
			(max_length 1)
			(best_width_ratio 0.9)
			(max_width 2)
			(curved_edges yes)
			(filter_ratio 0.9)
			(enabled yes)
			(allow_two_segments yes)
			(prefer_zone_connections yes)
		)
		(net 1)
	)
	(via
		(at 288.95 110.81)
		(size 0.45)
		(drill 0.1)
		(layers "F.Cu" "B.Cu")
		(remove_unused_layers yes)
		(keep_end_layers yes)
		(zone_layer_connections "In1.Cu" "In4.Cu" "In6.Cu")
		(teardrops
			(best_length_ratio 0.4)
			(max_length 1)
			(best_width_ratio 0.9)
			(max_width 2)
			(curved_edges yes)
			(filter_ratio 0.9)
			(enabled yes)
			(allow_two_segments yes)
			(prefer_zone_connections yes)
		)
		(net 1)
	)
	(via
		(at 205.575 167.1)
		(size 0.45)
		(drill 0.1)
		(layers "F.Cu" "B.Cu")
		(teardrops
			(best_length_ratio 0.4)
			(max_length 1)
			(best_width_ratio 0.9)
			(max_width 2)
			(curved_edges yes)
			(filter_ratio 0.9)
			(enabled yes)
			(allow_two_segments yes)
			(prefer_zone_connections yes)
		)
		(net 1)
	)
	(via
		(at 286.699 74.96)
		(size 0.45)
		(drill 0.1)
		(layers "F.Cu" "B.Cu")
		(remove_unused_layers yes)
		(keep_end_layers yes)
		(free yes)
		(zone_layer_connections "In1.Cu" "In4.Cu" "In6.Cu")
		(teardrops
			(best_length_ratio 0.4)
			(max_length 1)
			(best_width_ratio 0.9)
			(max_width 2)
			(curved_edges yes)
			(filter_ratio 0.9)
			(enabled yes)
			(allow_two_segments yes)
			(prefer_zone_connections yes)
		)
		(net 1)
	)
	(via
		(at 130.9 81.280001)
		(size 0.45)
		(drill 0.1)
		(layers "F.Cu" "B.Cu")
		(remove_unused_layers yes)
		(keep_end_layers yes)
		(zone_layer_connections "In1.Cu" "In4.Cu" "In6.Cu")
		(teardrops
			(best_length_ratio 0.4)
			(max_length 1)
			(best_width_ratio 0.9)
			(max_width 2)
			(curved_edges yes)
			(filter_ratio 0.9)
			(enabled yes)
			(allow_two_segments yes)
			(prefer_zone_connections yes)
		)
		(net 1)
	)
	(via
		(at 131.29 141.86)
		(size 0.45)
		(drill 0.1)
		(layers "F.Cu" "B.Cu")
		(remove_unused_layers yes)
		(keep_end_layers yes)
		(zone_layer_connections "In1.Cu" "In4.Cu" "In6.Cu")
		(teardrops
			(best_length_ratio 0.4)
			(max_length 1)
			(best_width_ratio 0.9)
			(max_width 2)
			(curved_edges yes)
			(filter_ratio 0.9)
			(enabled yes)
			(allow_two_segments yes)
			(prefer_zone_connections yes)
		)
		(net 1)
	)
	(via
		(at 316.4645 96.6365)
		(size 0.45)
		(drill 0.1)
		(layers "F.Cu" "B.Cu")
		(remove_unused_layers yes)
		(keep_end_layers yes)
		(zone_layer_connections "In1.Cu" "In4.Cu" "In6.Cu")
		(teardrops
			(best_length_ratio 0.4)
			(max_length 1)
			(best_width_ratio 0.9)
			(max_width 2)
			(curved_edges yes)
			(filter_ratio 0.9)
			(enabled yes)
			(allow_two_segments yes)
			(prefer_zone_connections yes)
		)
		(net 1)
	)
	(via
		(at 234.4 152.4)
		(size 0.45)
		(drill 0.1)
		(layers "F.Cu" "B.Cu")
		(teardrops
			(best_length_ratio 0.4)
			(max_length 1)
			(best_width_ratio 0.9)
			(max_width 2)
			(curved_edges yes)
			(filter_ratio 0.9)
			(enabled yes)
			(allow_two_segments yes)
			(prefer_zone_connections yes)
		)
		(net 1)
	)
	(via
		(at 169.45 85.31)
		(size 0.45)
		(drill 0.1)
		(layers "F.Cu" "B.Cu")
		(remove_unused_layers yes)
		(keep_end_layers yes)
		(zone_layer_connections "In1.Cu" "In4.Cu" "In6.Cu")
		(teardrops
			(best_length_ratio 0.4)
			(max_length 1)
			(best_width_ratio 0.9)
			(max_width 2)
			(curved_edges yes)
			(filter_ratio 0.9)
			(enabled yes)
			(allow_two_segments yes)
			(prefer_zone_connections yes)
		)
		(net 1)
	)
	(via
		(at 268.65 138.3)
		(size 0.45)
		(drill 0.1)
		(layers "F.Cu" "B.Cu")
		(remove_unused_layers yes)
		(keep_end_layers yes)
		(zone_layer_connections "In1.Cu" "In4.Cu" "In6.Cu")
		(teardrops
			(best_length_ratio 0.4)
			(max_length 1)
			(best_width_ratio 0.9)
			(max_width 2)
			(curved_edges yes)
			(filter_ratio 0.9)
			(enabled yes)
			(allow_two_segments yes)
			(prefer_zone_connections yes)
		)
		(net 1)
	)
	(via
		(at 102.95 101.81)
		(size 0.45)
		(drill 0.1)
		(layers "F.Cu" "B.Cu")
		(remove_unused_layers yes)
		(keep_end_layers yes)
		(zone_layer_connections "In1.Cu" "In4.Cu" "In6.Cu")
		(teardrops
			(best_length_ratio 0.4)
			(max_length 1)
			(best_width_ratio 0.9)
			(max_width 2)
			(curved_edges yes)
			(filter_ratio 0.9)
			(enabled yes)
			(allow_two_segments yes)
			(prefer_zone_connections yes)
		)
		(net 1)
	)
	(via
		(at 125.95 155.81)
		(size 0.45)
		(drill 0.1)
		(layers "F.Cu" "B.Cu")
		(remove_unused_layers yes)
		(keep_end_layers yes)
		(zone_layer_connections "In1.Cu" "In4.Cu" "In6.Cu")
		(teardrops
			(best_length_ratio 0.4)
			(max_length 1)
			(best_width_ratio 0.9)
			(max_width 2)
			(curved_edges yes)
			(filter_ratio 0.9)
			(enabled yes)
			(allow_two_segments yes)
			(prefer_zone_connections yes)
		)
		(net 1)
	)
	(via
		(at 283.95 126.81)
		(size 0.45)
		(drill 0.1)
		(layers "F.Cu" "B.Cu")
		(remove_unused_layers yes)
		(keep_end_layers yes)
		(zone_layer_connections "In1.Cu" "In4.Cu" "In6.Cu")
		(teardrops
			(best_length_ratio 0.4)
			(max_length 1)
			(best_width_ratio 0.9)
			(max_width 2)
			(curved_edges yes)
			(filter_ratio 0.9)
			(enabled yes)
			(allow_two_segments yes)
			(prefer_zone_connections yes)
		)
		(net 1)
	)
	(via
		(at 153.45 141.86)
		(size 0.45)
		(drill 0.1)
		(layers "F.Cu" "B.Cu")
		(remove_unused_layers yes)
		(keep_end_layers yes)
		(zone_layer_connections "In1.Cu" "In4.Cu" "In6.Cu")
		(teardrops
			(best_length_ratio 0.4)
			(max_length 1)
			(best_width_ratio 0.9)
			(max_width 2)
			(curved_edges yes)
			(filter_ratio 0.9)
			(enabled yes)
			(allow_two_segments yes)
			(prefer_zone_connections yes)
		)
		(net 1)
	)
	(via
		(at 217 167.55)
		(size 0.45)
		(drill 0.1)
		(layers "F.Cu" "B.Cu")
		(teardrops
			(best_length_ratio 0.4)
			(max_length 1)
			(best_width_ratio 0.9)
			(max_width 2)
			(curved_edges yes)
			(filter_ratio 0.9)
			(enabled yes)
			(allow_two_segments yes)
			(prefer_zone_connections yes)
		)
		(net 1)
	)
	(via
		(at 248.215708 75.76)
		(size 0.45)
		(drill 0.1)
		(layers "F.Cu" "B.Cu")
		(remove_unused_layers yes)
		(keep_end_layers yes)
		(zone_layer_connections "In1.Cu" "In4.Cu" "In6.Cu")
		(teardrops
			(best_length_ratio 0.4)
			(max_length 1)
			(best_width_ratio 0.9)
			(max_width 2)
			(curved_edges yes)
			(filter_ratio 0.9)
			(enabled yes)
			(allow_two_segments yes)
			(prefer_zone_connections yes)
		)
		(net 1)
	)
	(via
		(at 96.95 89.81)
		(size 0.45)
		(drill 0.1)
		(layers "F.Cu" "B.Cu")
		(remove_unused_layers yes)
		(keep_end_layers yes)
		(zone_layer_connections "In1.Cu" "In4.Cu" "In6.Cu")
		(teardrops
			(best_length_ratio 0.4)
			(max_length 1)
			(best_width_ratio 0.9)
			(max_width 2)
			(curved_edges yes)
			(filter_ratio 0.9)
			(enabled yes)
			(allow_two_segments yes)
			(prefer_zone_connections yes)
		)
		(net 1)
	)
	(via
		(at 226.9 149.65)
		(size 0.45)
		(drill 0.1)
		(layers "F.Cu" "B.Cu")
		(teardrops
			(best_length_ratio 0.4)
			(max_length 1)
			(best_width_ratio 0.9)
			(max_width 2)
			(curved_edges yes)
			(filter_ratio 0.9)
			(enabled yes)
			(allow_two_segments yes)
			(prefer_zone_connections yes)
		)
		(net 1)
	)
	(via
		(at 310.93 166.35)
		(size 0.45)
		(drill 0.1)
		(layers "F.Cu" "B.Cu")
		(remove_unused_layers yes)
		(keep_end_layers yes)
		(zone_layer_connections "In1.Cu" "In4.Cu" "In6.Cu")
		(teardrops
			(best_length_ratio 0.4)
			(max_length 1)
			(best_width_ratio 0.9)
			(max_width 2)
			(curved_edges yes)
			(filter_ratio 0.9)
			(enabled yes)
			(allow_two_segments yes)
			(prefer_zone_connections yes)
		)
		(net 1)
	)
	(via
		(at 105.6 156.86)
		(size 0.45)
		(drill 0.1)
		(layers "F.Cu" "B.Cu")
		(remove_unused_layers yes)
		(keep_end_layers yes)
		(zone_layer_connections "In1.Cu" "In4.Cu" "In6.Cu")
		(teardrops
			(best_length_ratio 0.4)
			(max_length 1)
			(best_width_ratio 0.9)
			(max_width 2)
			(curved_edges yes)
			(filter_ratio 0.9)
			(enabled yes)
			(allow_two_segments yes)
			(prefer_zone_connections yes)
		)
		(net 1)
	)
	(via
		(at 236.95 130.81)
		(size 0.45)
		(drill 0.1)
		(layers "F.Cu" "B.Cu")
		(remove_unused_layers yes)
		(keep_end_layers yes)
		(zone_layer_connections "In1.Cu" "In4.Cu" "In6.Cu")
		(teardrops
			(best_length_ratio 0.4)
			(max_length 1)
			(best_width_ratio 0.9)
			(max_width 2)
			(curved_edges yes)
			(filter_ratio 0.9)
			(enabled yes)
			(allow_two_segments yes)
			(prefer_zone_connections yes)
		)
		(net 1)
	)
	(via
		(at 241.420708 78.135)
		(size 0.45)
		(drill 0.1)
		(layers "F.Cu" "B.Cu")
		(remove_unused_layers yes)
		(keep_end_layers yes)
		(zone_layer_connections "In1.Cu" "In4.Cu" "In6.Cu")
		(teardrops
			(best_length_ratio 0.4)
			(max_length 1)
			(best_width_ratio 0.9)
			(max_width 2)
			(curved_edges yes)
			(filter_ratio 0.9)
			(enabled yes)
			(allow_two_segments yes)
			(prefer_zone_connections yes)
		)
		(net 1)
	)
	(via
		(at 171.3 164.5)
		(size 0.45)
		(drill 0.1)
		(layers "F.Cu" "B.Cu")
		(teardrops
			(best_length_ratio 0.4)
			(max_length 1)
			(best_width_ratio 0.9)
			(max_width 2)
			(curved_edges yes)
			(filter_ratio 0.9)
			(enabled yes)
			(allow_two_segments yes)
			(prefer_zone_connections yes)
		)
		(net 1)
	)
	(via
		(at 222 152.349)
		(size 0.45)
		(drill 0.1)
		(layers "F.Cu" "B.Cu")
		(teardrops
			(best_length_ratio 0.4)
			(max_length 1)
			(best_width_ratio 0.9)
			(max_width 2)
			(curved_edges yes)
			(filter_ratio 0.9)
			(enabled yes)
			(allow_two_segments yes)
			(prefer_zone_connections yes)
		)
		(net 1)
	)
	(via
		(at 247.45 88.31)
		(size 0.45)
		(drill 0.1)
		(layers "F.Cu" "B.Cu")
		(remove_unused_layers yes)
		(keep_end_layers yes)
		(zone_layer_connections "In1.Cu" "In4.Cu" "In6.Cu")
		(teardrops
			(best_length_ratio 0.4)
			(max_length 1)
			(best_width_ratio 0.9)
			(max_width 2)
			(curved_edges yes)
			(filter_ratio 0.9)
			(enabled yes)
			(allow_two_segments yes)
			(prefer_zone_connections yes)
		)
		(net 1)
	)
	(via
		(at 309.18 102.91)
		(size 0.45)
		(drill 0.1)
		(layers "F.Cu" "B.Cu")
		(remove_unused_layers yes)
		(keep_end_layers yes)
		(free yes)
		(zone_layer_connections "In1.Cu" "In4.Cu" "In6.Cu")
		(teardrops
			(best_length_ratio 0.4)
			(max_length 1)
			(best_width_ratio 0.9)
			(max_width 2)
			(curved_edges yes)
			(filter_ratio 0.9)
			(enabled yes)
			(allow_two_segments yes)
			(prefer_zone_connections yes)
		)
		(net 1)
	)
	(via
		(at 232.95 86.31)
		(size 0.45)
		(drill 0.1)
		(layers "F.Cu" "B.Cu")
		(remove_unused_layers yes)
		(keep_end_layers yes)
		(zone_layer_connections "In1.Cu" "In4.Cu" "In6.Cu")
		(teardrops
			(best_length_ratio 0.4)
			(max_length 1)
			(best_width_ratio 0.9)
			(max_width 2)
			(curved_edges yes)
			(filter_ratio 0.9)
			(enabled yes)
			(allow_two_segments yes)
			(prefer_zone_connections yes)
		)
		(net 1)
	)
	(via
		(at 159.55 156.33)
		(size 0.45)
		(drill 0.1)
		(layers "F.Cu" "B.Cu")
		(remove_unused_layers yes)
		(keep_end_layers yes)
		(zone_layer_connections "In1.Cu" "In4.Cu" "In6.Cu")
		(teardrops
			(best_length_ratio 0.4)
			(max_length 1)
			(best_width_ratio 0.9)
			(max_width 2)
			(curved_edges yes)
			(filter_ratio 0.9)
			(enabled yes)
			(allow_two_segments yes)
			(prefer_zone_connections yes)
		)
		(net 1)
	)
	(via
		(at 276.45 128.31)
		(size 0.45)
		(drill 0.1)
		(layers "F.Cu" "B.Cu")
		(remove_unused_layers yes)
		(keep_end_layers yes)
		(zone_layer_connections "In1.Cu" "In4.Cu" "In6.Cu")
		(teardrops
			(best_length_ratio 0.4)
			(max_length 1)
			(best_width_ratio 0.9)
			(max_width 2)
			(curved_edges yes)
			(filter_ratio 0.9)
			(enabled yes)
			(allow_two_segments yes)
			(prefer_zone_connections yes)
		)
		(net 1)
	)
	(via
		(at 172.2 152.4)
		(size 0.45)
		(drill 0.1)
		(layers "F.Cu" "B.Cu")
		(teardrops
			(best_length_ratio 0.4)
			(max_length 1)
			(best_width_ratio 0.9)
			(max_width 2)
			(curved_edges yes)
			(filter_ratio 0.9)
			(enabled yes)
			(allow_two_segments yes)
			(prefer_zone_connections yes)
		)
		(net 1)
	)
	(via
		(at 271.95 166.41)
		(size 0.45)
		(drill 0.1)
		(layers "F.Cu" "B.Cu")
		(remove_unused_layers yes)
		(keep_end_layers yes)
		(zone_layer_connections "In1.Cu" "In4.Cu" "In6.Cu")
		(teardrops
			(best_length_ratio 0.4)
			(max_length 1)
			(best_width_ratio 0.9)
			(max_width 2)
			(curved_edges yes)
			(filter_ratio 0.9)
			(enabled yes)
			(allow_two_segments yes)
			(prefer_zone_connections yes)
		)
		(net 1)
	)
	(via
		(at 95.45 167.31)
		(size 0.45)
		(drill 0.1)
		(layers "F.Cu" "B.Cu")
		(remove_unused_layers yes)
		(keep_end_layers yes)
		(zone_layer_connections "In1.Cu" "In4.Cu" "In6.Cu")
		(teardrops
			(best_length_ratio 0.4)
			(max_length 1)
			(best_width_ratio 0.9)
			(max_width 2)
			(curved_edges yes)
			(filter_ratio 0.9)
			(enabled yes)
			(allow_two_segments yes)
			(prefer_zone_connections yes)
		)
		(net 1)
	)
	(via
		(at 211.45 135.31)
		(size 0.45)
		(drill 0.1)
		(layers "F.Cu" "B.Cu")
		(remove_unused_layers yes)
		(keep_end_layers yes)
		(zone_layer_connections "In1.Cu" "In4.Cu" "In6.Cu")
		(teardrops
			(best_length_ratio 0.4)
			(max_length 1)
			(best_width_ratio 0.9)
			(max_width 2)
			(curved_edges yes)
			(filter_ratio 0.9)
			(enabled yes)
			(allow_two_segments yes)
			(prefer_zone_connections yes)
		)
		(net 1)
	)
	(via
		(at 146.45 137.86)
		(size 0.45)
		(drill 0.1)
		(layers "F.Cu" "B.Cu")
		(remove_unused_layers yes)
		(keep_end_layers yes)
		(zone_layer_connections "In1.Cu" "In4.Cu" "In6.Cu")
		(teardrops
			(best_length_ratio 0.4)
			(max_length 1)
			(best_width_ratio 0.9)
			(max_width 2)
			(curved_edges yes)
			(filter_ratio 0.9)
			(enabled yes)
			(allow_two_segments yes)
			(prefer_zone_connections yes)
		)
		(net 1)
	)
	(via
		(at 254.45 90.81)
		(size 0.45)
		(drill 0.1)
		(layers "F.Cu" "B.Cu")
		(remove_unused_layers yes)
		(keep_end_layers yes)
		(zone_layer_connections "In1.Cu" "In4.Cu" "In6.Cu")
		(teardrops
			(best_length_ratio 0.4)
			(max_length 1)
			(best_width_ratio 0.9)
			(max_width 2)
			(curved_edges yes)
			(filter_ratio 0.9)
			(enabled yes)
			(allow_two_segments yes)
			(prefer_zone_connections yes)
		)
		(net 1)
	)
	(via
		(at 211.6 171.15)
		(size 0.45)
		(drill 0.1)
		(layers "F.Cu" "B.Cu")
		(teardrops
			(best_length_ratio 0.4)
			(max_length 1)
			(best_width_ratio 0.9)
			(max_width 2)
			(curved_edges yes)
			(filter_ratio 0.9)
			(enabled yes)
			(allow_two_segments yes)
			(prefer_zone_connections yes)
		)
		(net 1)
	)
	(via
		(at 100.45 80.81)
		(size 0.45)
		(drill 0.1)
		(layers "F.Cu" "B.Cu")
		(remove_unused_layers yes)
		(keep_end_layers yes)
		(zone_layer_connections "In1.Cu" "In4.Cu" "In6.Cu")
		(teardrops
			(best_length_ratio 0.4)
			(max_length 1)
			(best_width_ratio 0.9)
			(max_width 2)
			(curved_edges yes)
			(filter_ratio 0.9)
			(enabled yes)
			(allow_two_segments yes)
			(prefer_zone_connections yes)
		)
		(net 1)
	)
	(via
		(at 207.45 85.31)
		(size 0.45)
		(drill 0.1)
		(layers "F.Cu" "B.Cu")
		(remove_unused_layers yes)
		(keep_end_layers yes)
		(zone_layer_connections "In1.Cu" "In4.Cu" "In6.Cu")
		(teardrops
			(best_length_ratio 0.4)
			(max_length 1)
			(best_width_ratio 0.9)
			(max_width 2)
			(curved_edges yes)
			(filter_ratio 0.9)
			(enabled yes)
			(allow_two_segments yes)
			(prefer_zone_connections yes)
		)
		(net 1)
	)
	(via
		(at 297.45 133.31)
		(size 0.45)
		(drill 0.1)
		(layers "F.Cu" "B.Cu")
		(remove_unused_layers yes)
		(keep_end_layers yes)
		(zone_layer_connections "In1.Cu" "In4.Cu" "In6.Cu")
		(teardrops
			(best_length_ratio 0.4)
			(max_length 1)
			(best_width_ratio 0.9)
			(max_width 2)
			(curved_edges yes)
			(filter_ratio 0.9)
			(enabled yes)
			(allow_two_segments yes)
			(prefer_zone_connections yes)
		)
		(net 1)
	)
	(via
		(at 289.7 74.96)
		(size 0.45)
		(drill 0.1)
		(layers "F.Cu" "B.Cu")
		(remove_unused_layers yes)
		(keep_end_layers yes)
		(free yes)
		(zone_layer_connections "In1.Cu" "In4.Cu" "In6.Cu")
		(teardrops
			(best_length_ratio 0.4)
			(max_length 1)
			(best_width_ratio 0.9)
			(max_width 2)
			(curved_edges yes)
			(filter_ratio 0.9)
			(enabled yes)
			(allow_two_segments yes)
			(prefer_zone_connections yes)
		)
		(net 1)
	)
	(via
		(at 262.45 127.81)
		(size 0.45)
		(drill 0.1)
		(layers "F.Cu" "B.Cu")
		(remove_unused_layers yes)
		(keep_end_layers yes)
		(zone_layer_connections "In1.Cu" "In4.Cu" "In6.Cu")
		(teardrops
			(best_length_ratio 0.4)
			(max_length 1)
			(best_width_ratio 0.9)
			(max_width 2)
			(curved_edges yes)
			(filter_ratio 0.9)
			(enabled yes)
			(allow_two_segments yes)
			(prefer_zone_connections yes)
		)
		(net 1)
	)
	(via
		(at 198.95 101.81)
		(size 0.45)
		(drill 0.1)
		(layers "F.Cu" "B.Cu")
		(remove_unused_layers yes)
		(keep_end_layers yes)
		(zone_layer_connections "In1.Cu" "In4.Cu" "In6.Cu")
		(teardrops
			(best_length_ratio 0.4)
			(max_length 1)
			(best_width_ratio 0.9)
			(max_width 2)
			(curved_edges yes)
			(filter_ratio 0.9)
			(enabled yes)
			(allow_two_segments yes)
			(prefer_zone_connections yes)
		)
		(net 1)
	)
	(via
		(at 144.45 88.31)
		(size 0.45)
		(drill 0.1)
		(layers "F.Cu" "B.Cu")
		(remove_unused_layers yes)
		(keep_end_layers yes)
		(zone_layer_connections "In1.Cu" "In4.Cu" "In6.Cu")
		(teardrops
			(best_length_ratio 0.4)
			(max_length 1)
			(best_width_ratio 0.9)
			(max_width 2)
			(curved_edges yes)
			(filter_ratio 0.9)
			(enabled yes)
			(allow_two_segments yes)
			(prefer_zone_connections yes)
		)
		(net 1)
	)
	(via
		(at 96.95 75.81)
		(size 0.45)
		(drill 0.1)
		(layers "F.Cu" "B.Cu")
		(remove_unused_layers yes)
		(keep_end_layers yes)
		(zone_layer_connections "In1.Cu" "In4.Cu" "In6.Cu")
		(teardrops
			(best_length_ratio 0.4)
			(max_length 1)
			(best_width_ratio 0.9)
			(max_width 2)
			(curved_edges yes)
			(filter_ratio 0.9)
			(enabled yes)
			(allow_two_segments yes)
			(prefer_zone_connections yes)
		)
		(net 1)
	)
	(via
		(at 251.95 117.31)
		(size 0.45)
		(drill 0.1)
		(layers "F.Cu" "B.Cu")
		(remove_unused_layers yes)
		(keep_end_layers yes)
		(zone_layer_connections "In1.Cu" "In4.Cu" "In6.Cu")
		(teardrops
			(best_length_ratio 0.4)
			(max_length 1)
			(best_width_ratio 0.9)
			(max_width 2)
			(curved_edges yes)
			(filter_ratio 0.9)
			(enabled yes)
			(allow_two_segments yes)
			(prefer_zone_connections yes)
		)
		(net 1)
	)
	(via
		(at 96.45 145.81)
		(size 0.45)
		(drill 0.1)
		(layers "F.Cu" "B.Cu")
		(remove_unused_layers yes)
		(keep_end_layers yes)
		(zone_layer_connections "In1.Cu" "In4.Cu" "In6.Cu")
		(teardrops
			(best_length_ratio 0.4)
			(max_length 1)
			(best_width_ratio 0.9)
			(max_width 2)
			(curved_edges yes)
			(filter_ratio 0.9)
			(enabled yes)
			(allow_two_segments yes)
			(prefer_zone_connections yes)
		)
		(net 1)
	)
	(via
		(at 174.703893 105.409175)
		(size 0.45)
		(drill 0.1)
		(layers "F.Cu" "B.Cu")
		(remove_unused_layers yes)
		(keep_end_layers yes)
		(zone_layer_connections "In1.Cu" "In4.Cu" "In6.Cu")
		(teardrops
			(best_length_ratio 0.4)
			(max_length 1)
			(best_width_ratio 0.9)
			(max_width 2)
			(curved_edges yes)
			(filter_ratio 0.9)
			(enabled yes)
			(allow_two_segments yes)
			(prefer_zone_connections yes)
		)
		(net 1)
	)
	(via
		(at 215.7 155.5)
		(size 0.45)
		(drill 0.1)
		(layers "F.Cu" "B.Cu")
		(teardrops
			(best_length_ratio 0.4)
			(max_length 1)
			(best_width_ratio 0.9)
			(max_width 2)
			(curved_edges yes)
			(filter_ratio 0.9)
			(enabled yes)
			(allow_two_segments yes)
			(prefer_zone_connections yes)
		)
		(net 1)
	)
	(via
		(at 124.45 152.81)
		(size 0.45)
		(drill 0.1)
		(layers "F.Cu" "B.Cu")
		(remove_unused_layers yes)
		(keep_end_layers yes)
		(zone_layer_connections "In1.Cu" "In4.Cu" "In6.Cu")
		(teardrops
			(best_length_ratio 0.4)
			(max_length 1)
			(best_width_ratio 0.9)
			(max_width 2)
			(curved_edges yes)
			(filter_ratio 0.9)
			(enabled yes)
			(allow_two_segments yes)
			(prefer_zone_connections yes)
		)
		(net 1)
	)
	(via
		(at 244.45 90.81)
		(size 0.45)
		(drill 0.1)
		(layers "F.Cu" "B.Cu")
		(remove_unused_layers yes)
		(keep_end_layers yes)
		(zone_layer_connections "In1.Cu" "In4.Cu" "In6.Cu")
		(teardrops
			(best_length_ratio 0.4)
			(max_length 1)
			(best_width_ratio 0.9)
			(max_width 2)
			(curved_edges yes)
			(filter_ratio 0.9)
			(enabled yes)
			(allow_two_segments yes)
			(prefer_zone_connections yes)
		)
		(net 1)
	)
	(via
		(at 315.4645 99.6365)
		(size 0.45)
		(drill 0.1)
		(layers "F.Cu" "B.Cu")
		(remove_unused_layers yes)
		(keep_end_layers yes)
		(free yes)
		(zone_layer_connections "In1.Cu" "In4.Cu" "In6.Cu")
		(teardrops
			(best_length_ratio 0.4)
			(max_length 1)
			(best_width_ratio 0.9)
			(max_width 2)
			(curved_edges yes)
			(filter_ratio 0.9)
			(enabled yes)
			(allow_two_segments yes)
			(prefer_zone_connections yes)
		)
		(net 1)
	)
	(via
		(at 264.45 166.41)
		(size 0.45)
		(drill 0.1)
		(layers "F.Cu" "B.Cu")
		(remove_unused_layers yes)
		(keep_end_layers yes)
		(zone_layer_connections "In1.Cu" "In4.Cu" "In6.Cu")
		(teardrops
			(best_length_ratio 0.4)
			(max_length 1)
			(best_width_ratio 0.9)
			(max_width 2)
			(curved_edges yes)
			(filter_ratio 0.9)
			(enabled yes)
			(allow_two_segments yes)
			(prefer_zone_connections yes)
		)
		(net 1)
	)
	(via
		(at 141.3 74.51)
		(size 0.45)
		(drill 0.1)
		(layers "F.Cu" "B.Cu")
		(remove_unused_layers yes)
		(keep_end_layers yes)
		(free yes)
		(zone_layer_connections "In1.Cu" "In4.Cu" "In6.Cu")
		(teardrops
			(best_length_ratio 0.4)
			(max_length 1)
			(best_width_ratio 0.9)
			(max_width 2)
			(curved_edges yes)
			(filter_ratio 0.9)
			(enabled yes)
			(allow_two_segments yes)
			(prefer_zone_connections yes)
		)
		(net 1)
	)
	(via
		(at 99.95 93.81)
		(size 0.45)
		(drill 0.1)
		(layers "F.Cu" "B.Cu")
		(remove_unused_layers yes)
		(keep_end_layers yes)
		(zone_layer_connections "In1.Cu" "In4.Cu" "In6.Cu")
		(teardrops
			(best_length_ratio 0.4)
			(max_length 1)
			(best_width_ratio 0.9)
			(max_width 2)
			(curved_edges yes)
			(filter_ratio 0.9)
			(enabled yes)
			(allow_two_segments yes)
			(prefer_zone_connections yes)
		)
		(net 1)
	)
	(via
		(at 177.18 102.36)
		(size 0.45)
		(drill 0.1)
		(layers "F.Cu" "B.Cu")
		(remove_unused_layers yes)
		(keep_end_layers yes)
		(zone_layer_connections "In1.Cu" "In4.Cu" "In6.Cu")
		(teardrops
			(best_length_ratio 0.4)
			(max_length 1)
			(best_width_ratio 0.9)
			(max_width 2)
			(curved_edges yes)
			(filter_ratio 0.9)
			(enabled yes)
			(allow_two_segments yes)
			(prefer_zone_connections yes)
		)
		(net 1)
	)
	(via
		(at 214.16 129.12)
		(size 0.45)
		(drill 0.1)
		(layers "F.Cu" "B.Cu")
		(remove_unused_layers yes)
		(keep_end_layers yes)
		(zone_layer_connections "In1.Cu" "In4.Cu" "In6.Cu")
		(teardrops
			(best_length_ratio 0.4)
			(max_length 1)
			(best_width_ratio 0.9)
			(max_width 2)
			(curved_edges yes)
			(filter_ratio 0.9)
			(enabled yes)
			(allow_two_segments yes)
			(prefer_zone_connections yes)
		)
		(net 1)
	)
	(via
		(at 289.45 148.81)
		(size 0.45)
		(drill 0.1)
		(layers "F.Cu" "B.Cu")
		(remove_unused_layers yes)
		(keep_end_layers yes)
		(zone_layer_connections "In1.Cu" "In4.Cu" "In6.Cu")
		(teardrops
			(best_length_ratio 0.4)
			(max_length 1)
			(best_width_ratio 0.9)
			(max_width 2)
			(curved_edges yes)
			(filter_ratio 0.9)
			(enabled yes)
			(allow_two_segments yes)
			(prefer_zone_connections yes)
		)
		(net 1)
	)
	(via
		(at 283.45 148.81)
		(size 0.45)
		(drill 0.1)
		(layers "F.Cu" "B.Cu")
		(remove_unused_layers yes)
		(keep_end_layers yes)
		(zone_layer_connections "In1.Cu" "In4.Cu" "In6.Cu")
		(teardrops
			(best_length_ratio 0.4)
			(max_length 1)
			(best_width_ratio 0.9)
			(max_width 2)
			(curved_edges yes)
			(filter_ratio 0.9)
			(enabled yes)
			(allow_two_segments yes)
			(prefer_zone_connections yes)
		)
		(net 1)
	)
	(via
		(at 244.45 121.81)
		(size 0.45)
		(drill 0.1)
		(layers "F.Cu" "B.Cu")
		(remove_unused_layers yes)
		(keep_end_layers yes)
		(zone_layer_connections "In1.Cu" "In4.Cu" "In6.Cu")
		(teardrops
			(best_length_ratio 0.4)
			(max_length 1)
			(best_width_ratio 0.9)
			(max_width 2)
			(curved_edges yes)
			(filter_ratio 0.9)
			(enabled yes)
			(allow_two_segments yes)
			(prefer_zone_connections yes)
		)
		(net 1)
	)
	(via
		(at 283.95 121.31)
		(size 0.45)
		(drill 0.1)
		(layers "F.Cu" "B.Cu")
		(remove_unused_layers yes)
		(keep_end_layers yes)
		(zone_layer_connections "In1.Cu" "In4.Cu" "In6.Cu")
		(teardrops
			(best_length_ratio 0.4)
			(max_length 1)
			(best_width_ratio 0.9)
			(max_width 2)
			(curved_edges yes)
			(filter_ratio 0.9)
			(enabled yes)
			(allow_two_segments yes)
			(prefer_zone_connections yes)
		)
		(net 1)
	)
	(via
		(at 280.45 139.81)
		(size 0.45)
		(drill 0.1)
		(layers "F.Cu" "B.Cu")
		(remove_unused_layers yes)
		(keep_end_layers yes)
		(zone_layer_connections "In1.Cu" "In4.Cu" "In6.Cu")
		(teardrops
			(best_length_ratio 0.4)
			(max_length 1)
			(best_width_ratio 0.9)
			(max_width 2)
			(curved_edges yes)
			(filter_ratio 0.9)
			(enabled yes)
			(allow_two_segments yes)
			(prefer_zone_connections yes)
		)
		(net 1)
	)
	(via
		(at 134.95 161.31)
		(size 0.45)
		(drill 0.1)
		(layers "F.Cu" "B.Cu")
		(remove_unused_layers yes)
		(keep_end_layers yes)
		(zone_layer_connections "In1.Cu" "In4.Cu" "In6.Cu")
		(teardrops
			(best_length_ratio 0.4)
			(max_length 1)
			(best_width_ratio 0.9)
			(max_width 2)
			(curved_edges yes)
			(filter_ratio 0.9)
			(enabled yes)
			(allow_two_segments yes)
			(prefer_zone_connections yes)
		)
		(net 1)
	)
	(via
		(at 101.45 126.81)
		(size 0.45)
		(drill 0.1)
		(layers "F.Cu" "B.Cu")
		(remove_unused_layers yes)
		(keep_end_layers yes)
		(zone_layer_connections "In1.Cu" "In4.Cu" "In6.Cu")
		(teardrops
			(best_length_ratio 0.4)
			(max_length 1)
			(best_width_ratio 0.9)
			(max_width 2)
			(curved_edges yes)
			(filter_ratio 0.9)
			(enabled yes)
			(allow_two_segments yes)
			(prefer_zone_connections yes)
		)
		(net 1)
	)
	(via
		(at 177.4 166.9)
		(size 0.45)
		(drill 0.1)
		(layers "F.Cu" "B.Cu")
		(teardrops
			(best_length_ratio 0.4)
			(max_length 1)
			(best_width_ratio 0.9)
			(max_width 2)
			(curved_edges yes)
			(filter_ratio 0.9)
			(enabled yes)
			(allow_two_segments yes)
			(prefer_zone_connections yes)
		)
		(net 1)
	)
	(via
		(at 205.5 152.3)
		(size 0.45)
		(drill 0.1)
		(layers "F.Cu" "B.Cu")
		(teardrops
			(best_length_ratio 0.4)
			(max_length 1)
			(best_width_ratio 0.9)
			(max_width 2)
			(curved_edges yes)
			(filter_ratio 0.9)
			(enabled yes)
			(allow_two_segments yes)
			(prefer_zone_connections yes)
		)
		(net 1)
	)
	(via
		(at 198.7 88.06)
		(size 0.45)
		(drill 0.1)
		(layers "F.Cu" "B.Cu")
		(remove_unused_layers yes)
		(keep_end_layers yes)
		(zone_layer_connections "In1.Cu" "In4.Cu" "In6.Cu")
		(teardrops
			(best_length_ratio 0.4)
			(max_length 1)
			(best_width_ratio 0.9)
			(max_width 2)
			(curved_edges yes)
			(filter_ratio 0.9)
			(enabled yes)
			(allow_two_segments yes)
			(prefer_zone_connections yes)
		)
		(net 1)
	)
	(via
		(at 146.45 141.86)
		(size 0.45)
		(drill 0.1)
		(layers "F.Cu" "B.Cu")
		(remove_unused_layers yes)
		(keep_end_layers yes)
		(zone_layer_connections "In1.Cu" "In4.Cu" "In6.Cu")
		(teardrops
			(best_length_ratio 0.4)
			(max_length 1)
			(best_width_ratio 0.9)
			(max_width 2)
			(curved_edges yes)
			(filter_ratio 0.9)
			(enabled yes)
			(allow_two_segments yes)
			(prefer_zone_connections yes)
		)
		(net 1)
	)
	(via
		(at 107.6 151.2)
		(size 0.45)
		(drill 0.1)
		(layers "F.Cu" "B.Cu")
		(remove_unused_layers yes)
		(keep_end_layers yes)
		(zone_layer_connections "In1.Cu" "In4.Cu" "In6.Cu")
		(teardrops
			(best_length_ratio 0.4)
			(max_length 1)
			(best_width_ratio 0.9)
			(max_width 2)
			(curved_edges yes)
			(filter_ratio 0.9)
			(enabled yes)
			(allow_two_segments yes)
			(prefer_zone_connections yes)
		)
		(net 1)
	)
	(via
		(at 260.95 115.81)
		(size 0.45)
		(drill 0.1)
		(layers "F.Cu" "B.Cu")
		(remove_unused_layers yes)
		(keep_end_layers yes)
		(zone_layer_connections "In1.Cu" "In4.Cu" "In6.Cu")
		(teardrops
			(best_length_ratio 0.4)
			(max_length 1)
			(best_width_ratio 0.9)
			(max_width 2)
			(curved_edges yes)
			(filter_ratio 0.9)
			(enabled yes)
			(allow_two_segments yes)
			(prefer_zone_connections yes)
		)
		(net 1)
	)
	(via
		(at 315.95 80.31)
		(size 0.45)
		(drill 0.1)
		(layers "F.Cu" "B.Cu")
		(remove_unused_layers yes)
		(keep_end_layers yes)
		(zone_layer_connections "In1.Cu" "In4.Cu" "In6.Cu")
		(teardrops
			(best_length_ratio 0.4)
			(max_length 1)
			(best_width_ratio 0.9)
			(max_width 2)
			(curved_edges yes)
			(filter_ratio 0.9)
			(enabled yes)
			(allow_two_segments yes)
			(prefer_zone_connections yes)
		)
		(net 1)
	)
	(via
		(at 150.175 87.91)
		(size 0.45)
		(drill 0.1)
		(layers "F.Cu" "B.Cu")
		(remove_unused_layers yes)
		(keep_end_layers yes)
		(free yes)
		(zone_layer_connections "In1.Cu" "In4.Cu" "In6.Cu")
		(teardrops
			(best_length_ratio 0.4)
			(max_length 1)
			(best_width_ratio 0.9)
			(max_width 2)
			(curved_edges yes)
			(filter_ratio 0.9)
			(enabled yes)
			(allow_two_segments yes)
			(prefer_zone_connections yes)
		)
		(net 1)
	)
	(via
		(at 253.328251 128.131748)
		(size 0.45)
		(drill 0.1)
		(layers "F.Cu" "B.Cu")
		(remove_unused_layers yes)
		(keep_end_layers yes)
		(zone_layer_connections "In1.Cu" "In4.Cu" "In6.Cu")
		(teardrops
			(best_length_ratio 0.4)
			(max_length 1)
			(best_width_ratio 0.9)
			(max_width 2)
			(curved_edges yes)
			(filter_ratio 0.9)
			(enabled yes)
			(allow_two_segments yes)
			(prefer_zone_connections yes)
		)
		(net 1)
	)
	(via
		(at 203.40639 82.857837)
		(size 0.45)
		(drill 0.1)
		(layers "F.Cu" "B.Cu")
		(remove_unused_layers yes)
		(keep_end_layers yes)
		(zone_layer_connections "In1.Cu" "In4.Cu" "In6.Cu")
		(teardrops
			(best_length_ratio 0.4)
			(max_length 1)
			(best_width_ratio 0.9)
			(max_width 2)
			(curved_edges yes)
			(filter_ratio 0.9)
			(enabled yes)
			(allow_two_segments yes)
			(prefer_zone_connections yes)
		)
		(net 1)
	)
	(via
		(at 111.45 170.81)
		(size 0.45)
		(drill 0.1)
		(layers "F.Cu" "B.Cu")
		(remove_unused_layers yes)
		(keep_end_layers yes)
		(zone_layer_connections "In1.Cu" "In4.Cu" "In6.Cu")
		(teardrops
			(best_length_ratio 0.4)
			(max_length 1)
			(best_width_ratio 0.9)
			(max_width 2)
			(curved_edges yes)
			(filter_ratio 0.9)
			(enabled yes)
			(allow_two_segments yes)
			(prefer_zone_connections yes)
		)
		(net 1)
	)
	(via
		(at 241.45 115.81)
		(size 0.45)
		(drill 0.1)
		(layers "F.Cu" "B.Cu")
		(remove_unused_layers yes)
		(keep_end_layers yes)
		(zone_layer_connections "In1.Cu" "In4.Cu" "In6.Cu")
		(teardrops
			(best_length_ratio 0.4)
			(max_length 1)
			(best_width_ratio 0.9)
			(max_width 2)
			(curved_edges yes)
			(filter_ratio 0.9)
			(enabled yes)
			(allow_two_segments yes)
			(prefer_zone_connections yes)
		)
		(net 1)
	)
	(via
		(at 201.95 107.81)
		(size 0.45)
		(drill 0.1)
		(layers "F.Cu" "B.Cu")
		(remove_unused_layers yes)
		(keep_end_layers yes)
		(zone_layer_connections "In1.Cu" "In4.Cu" "In6.Cu")
		(teardrops
			(best_length_ratio 0.4)
			(max_length 1)
			(best_width_ratio 0.9)
			(max_width 2)
			(curved_edges yes)
			(filter_ratio 0.9)
			(enabled yes)
			(allow_two_segments yes)
			(prefer_zone_connections yes)
		)
		(net 1)
	)
	(via
		(at 292.95 136.31)
		(size 0.45)
		(drill 0.1)
		(layers "F.Cu" "B.Cu")
		(remove_unused_layers yes)
		(keep_end_layers yes)
		(zone_layer_connections "In1.Cu" "In4.Cu" "In6.Cu")
		(teardrops
			(best_length_ratio 0.4)
			(max_length 1)
			(best_width_ratio 0.9)
			(max_width 2)
			(curved_edges yes)
			(filter_ratio 0.9)
			(enabled yes)
			(allow_two_segments yes)
			(prefer_zone_connections yes)
		)
		(net 1)
	)
	(via
		(at 212.05 164.35)
		(size 0.45)
		(drill 0.1)
		(layers "F.Cu" "B.Cu")
		(teardrops
			(best_length_ratio 0.4)
			(max_length 1)
			(best_width_ratio 0.9)
			(max_width 2)
			(curved_edges yes)
			(filter_ratio 0.9)
			(enabled yes)
			(allow_two_segments yes)
			(prefer_zone_connections yes)
		)
		(net 1)
	)
	(via
		(at 222.95 133.31)
		(size 0.45)
		(drill 0.1)
		(layers "F.Cu" "B.Cu")
		(remove_unused_layers yes)
		(keep_end_layers yes)
		(zone_layer_connections "In1.Cu" "In4.Cu" "In6.Cu")
		(teardrops
			(best_length_ratio 0.4)
			(max_length 1)
			(best_width_ratio 0.9)
			(max_width 2)
			(curved_edges yes)
			(filter_ratio 0.9)
			(enabled yes)
			(allow_two_segments yes)
			(prefer_zone_connections yes)
		)
		(net 1)
	)
	(via
		(at 312.074999 105.05)
		(size 0.45)
		(drill 0.1)
		(layers "F.Cu" "B.Cu")
		(remove_unused_layers yes)
		(keep_end_layers yes)
		(zone_layer_connections "In1.Cu" "In4.Cu" "In6.Cu")
		(teardrops
			(best_length_ratio 0.4)
			(max_length 1)
			(best_width_ratio 0.9)
			(max_width 2)
			(curved_edges yes)
			(filter_ratio 0.9)
			(enabled yes)
			(allow_two_segments yes)
			(prefer_zone_connections yes)
		)
		(net 1)
	)
	(via
		(at 129.45 170.81)
		(size 0.45)
		(drill 0.1)
		(layers "F.Cu" "B.Cu")
		(remove_unused_layers yes)
		(keep_end_layers yes)
		(zone_layer_connections "In1.Cu" "In4.Cu" "In6.Cu")
		(teardrops
			(best_length_ratio 0.4)
			(max_length 1)
			(best_width_ratio 0.9)
			(max_width 2)
			(curved_edges yes)
			(filter_ratio 0.9)
			(enabled yes)
			(allow_two_segments yes)
			(prefer_zone_connections yes)
		)
		(net 1)
	)
	(via
		(at 170.95 83.81)
		(size 0.45)
		(drill 0.1)
		(layers "F.Cu" "B.Cu")
		(remove_unused_layers yes)
		(keep_end_layers yes)
		(zone_layer_connections "In1.Cu" "In4.Cu" "In6.Cu")
		(teardrops
			(best_length_ratio 0.4)
			(max_length 1)
			(best_width_ratio 0.9)
			(max_width 2)
			(curved_edges yes)
			(filter_ratio 0.9)
			(enabled yes)
			(allow_two_segments yes)
			(prefer_zone_connections yes)
		)
		(net 1)
	)
	(via
		(at 97.45 134.81)
		(size 0.45)
		(drill 0.1)
		(layers "F.Cu" "B.Cu")
		(remove_unused_layers yes)
		(keep_end_layers yes)
		(zone_layer_connections "In1.Cu" "In4.Cu" "In6.Cu")
		(teardrops
			(best_length_ratio 0.4)
			(max_length 1)
			(best_width_ratio 0.9)
			(max_width 2)
			(curved_edges yes)
			(filter_ratio 0.9)
			(enabled yes)
			(allow_two_segments yes)
			(prefer_zone_connections yes)
		)
		(net 1)
	)
	(via
		(at 305.45 87.81)
		(size 0.45)
		(drill 0.1)
		(layers "F.Cu" "B.Cu")
		(remove_unused_layers yes)
		(keep_end_layers yes)
		(zone_layer_connections "In1.Cu" "In4.Cu" "In6.Cu")
		(teardrops
			(best_length_ratio 0.4)
			(max_length 1)
			(best_width_ratio 0.9)
			(max_width 2)
			(curved_edges yes)
			(filter_ratio 0.9)
			(enabled yes)
			(allow_two_segments yes)
			(prefer_zone_connections yes)
		)
		(net 1)
	)
	(via
		(at 258.95 170.81)
		(size 0.45)
		(drill 0.1)
		(layers "F.Cu" "B.Cu")
		(remove_unused_layers yes)
		(keep_end_layers yes)
		(zone_layer_connections "In1.Cu" "In4.Cu" "In6.Cu")
		(teardrops
			(best_length_ratio 0.4)
			(max_length 1)
			(best_width_ratio 0.9)
			(max_width 2)
			(curved_edges yes)
			(filter_ratio 0.9)
			(enabled yes)
			(allow_two_segments yes)
			(prefer_zone_connections yes)
		)
		(net 1)
	)
	(via
		(at 112.95 97.81)
		(size 0.45)
		(drill 0.1)
		(layers "F.Cu" "B.Cu")
		(remove_unused_layers yes)
		(keep_end_layers yes)
		(zone_layer_connections "In1.Cu" "In4.Cu" "In6.Cu")
		(teardrops
			(best_length_ratio 0.4)
			(max_length 1)
			(best_width_ratio 0.9)
			(max_width 2)
			(curved_edges yes)
			(filter_ratio 0.9)
			(enabled yes)
			(allow_two_segments yes)
			(prefer_zone_connections yes)
		)
		(net 1)
	)
	(via
		(at 250.45 118.81)
		(size 0.45)
		(drill 0.1)
		(layers "F.Cu" "B.Cu")
		(remove_unused_layers yes)
		(keep_end_layers yes)
		(zone_layer_connections "In1.Cu" "In4.Cu" "In6.Cu")
		(teardrops
			(best_length_ratio 0.4)
			(max_length 1)
			(best_width_ratio 0.9)
			(max_width 2)
			(curved_edges yes)
			(filter_ratio 0.9)
			(enabled yes)
			(allow_two_segments yes)
			(prefer_zone_connections yes)
		)
		(net 1)
	)
	(via
		(at 282.45 119.81)
		(size 0.45)
		(drill 0.1)
		(layers "F.Cu" "B.Cu")
		(remove_unused_layers yes)
		(keep_end_layers yes)
		(zone_layer_connections "In1.Cu" "In4.Cu" "In6.Cu")
		(teardrops
			(best_length_ratio 0.4)
			(max_length 1)
			(best_width_ratio 0.9)
			(max_width 2)
			(curved_edges yes)
			(filter_ratio 0.9)
			(enabled yes)
			(allow_two_segments yes)
			(prefer_zone_connections yes)
		)
		(net 1)
	)
	(via
		(at 158.649 159.947)
		(size 0.45)
		(drill 0.1)
		(layers "F.Cu" "B.Cu")
		(remove_unused_layers yes)
		(keep_end_layers yes)
		(zone_layer_connections "In1.Cu" "In4.Cu" "In6.Cu")
		(teardrops
			(best_length_ratio 0.4)
			(max_length 1)
			(best_width_ratio 0.9)
			(max_width 2)
			(curved_edges yes)
			(filter_ratio 0.9)
			(enabled yes)
			(allow_two_segments yes)
			(prefer_zone_connections yes)
		)
		(net 1)
	)
	(via
		(at 143.0449 142.504698)
		(size 0.45)
		(drill 0.1)
		(layers "F.Cu" "B.Cu")
		(remove_unused_layers yes)
		(keep_end_layers yes)
		(zone_layer_connections "In1.Cu" "In4.Cu" "In6.Cu")
		(teardrops
			(best_length_ratio 0.4)
			(max_length 1)
			(best_width_ratio 0.9)
			(max_width 2)
			(curved_edges yes)
			(filter_ratio 0.9)
			(enabled yes)
			(allow_two_segments yes)
			(prefer_zone_connections yes)
		)
		(net 1)
	)
	(via
		(at 115.599 91.764)
		(size 0.45)
		(drill 0.1)
		(layers "F.Cu" "B.Cu")
		(remove_unused_layers yes)
		(keep_end_layers yes)
		(zone_layer_connections "In1.Cu" "In4.Cu" "In6.Cu")
		(teardrops
			(best_length_ratio 0.4)
			(max_length 1)
			(best_width_ratio 0.9)
			(max_width 2)
			(curved_edges yes)
			(filter_ratio 0.9)
			(enabled yes)
			(allow_two_segments yes)
			(prefer_zone_connections yes)
		)
		(net 1)
	)
	(via
		(at 121.45 96.31)
		(size 0.45)
		(drill 0.1)
		(layers "F.Cu" "B.Cu")
		(remove_unused_layers yes)
		(keep_end_layers yes)
		(zone_layer_connections "In1.Cu" "In4.Cu" "In6.Cu")
		(teardrops
			(best_length_ratio 0.4)
			(max_length 1)
			(best_width_ratio 0.9)
			(max_width 2)
			(curved_edges yes)
			(filter_ratio 0.9)
			(enabled yes)
			(allow_two_segments yes)
			(prefer_zone_connections yes)
		)
		(net 1)
	)
	(via
		(at 259.95 166.41)
		(size 0.45)
		(drill 0.1)
		(layers "F.Cu" "B.Cu")
		(remove_unused_layers yes)
		(keep_end_layers yes)
		(zone_layer_connections "In1.Cu" "In4.Cu" "In6.Cu")
		(teardrops
			(best_length_ratio 0.4)
			(max_length 1)
			(best_width_ratio 0.9)
			(max_width 2)
			(curved_edges yes)
			(filter_ratio 0.9)
			(enabled yes)
			(allow_two_segments yes)
			(prefer_zone_connections yes)
		)
		(net 1)
	)
	(via
		(at 190.65 164.45)
		(size 0.45)
		(drill 0.1)
		(layers "F.Cu" "B.Cu")
		(teardrops
			(best_length_ratio 0.4)
			(max_length 1)
			(best_width_ratio 0.9)
			(max_width 2)
			(curved_edges yes)
			(filter_ratio 0.9)
			(enabled yes)
			(allow_two_segments yes)
			(prefer_zone_connections yes)
		)
		(net 1)
	)
	(via
		(at 102.45 125.81)
		(size 0.45)
		(drill 0.1)
		(layers "F.Cu" "B.Cu")
		(remove_unused_layers yes)
		(keep_end_layers yes)
		(zone_layer_connections "In1.Cu" "In4.Cu" "In6.Cu")
		(teardrops
			(best_length_ratio 0.4)
			(max_length 1)
			(best_width_ratio 0.9)
			(max_width 2)
			(curved_edges yes)
			(filter_ratio 0.9)
			(enabled yes)
			(allow_two_segments yes)
			(prefer_zone_connections yes)
		)
		(net 1)
	)
	(via
		(at 101.45 68.81)
		(size 0.45)
		(drill 0.1)
		(layers "F.Cu" "B.Cu")
		(remove_unused_layers yes)
		(keep_end_layers yes)
		(zone_layer_connections "In1.Cu" "In4.Cu" "In6.Cu")
		(teardrops
			(best_length_ratio 0.4)
			(max_length 1)
			(best_width_ratio 0.9)
			(max_width 2)
			(curved_edges yes)
			(filter_ratio 0.9)
			(enabled yes)
			(allow_two_segments yes)
			(prefer_zone_connections yes)
		)
		(net 1)
	)
	(via
		(at 311.4645 100.6365)
		(size 0.45)
		(drill 0.1)
		(layers "F.Cu" "B.Cu")
		(remove_unused_layers yes)
		(keep_end_layers yes)
		(free yes)
		(zone_layer_connections "In1.Cu" "In4.Cu" "In6.Cu")
		(teardrops
			(best_length_ratio 0.4)
			(max_length 1)
			(best_width_ratio 0.9)
			(max_width 2)
			(curved_edges yes)
			(filter_ratio 0.9)
			(enabled yes)
			(allow_two_segments yes)
			(prefer_zone_connections yes)
		)
		(net 1)
	)
	(via
		(at 182.5 157.9)
		(size 0.45)
		(drill 0.1)
		(layers "F.Cu" "B.Cu")
		(teardrops
			(best_length_ratio 0.4)
			(max_length 1)
			(best_width_ratio 0.9)
			(max_width 2)
			(curved_edges yes)
			(filter_ratio 0.9)
			(enabled yes)
			(allow_two_segments yes)
			(prefer_zone_connections yes)
		)
		(net 1)
	)
	(via
		(at 288.95 170.81)
		(size 0.45)
		(drill 0.1)
		(layers "F.Cu" "B.Cu")
		(remove_unused_layers yes)
		(keep_end_layers yes)
		(zone_layer_connections "In1.Cu" "In4.Cu" "In6.Cu")
		(teardrops
			(best_length_ratio 0.4)
			(max_length 1)
			(best_width_ratio 0.9)
			(max_width 2)
			(curved_edges yes)
			(filter_ratio 0.9)
			(enabled yes)
			(allow_two_segments yes)
			(prefer_zone_connections yes)
		)
		(net 1)
	)
	(via
		(at 99.46 165.1)
		(size 0.45)
		(drill 0.1)
		(layers "F.Cu" "B.Cu")
		(remove_unused_layers yes)
		(keep_end_layers yes)
		(zone_layer_connections "In1.Cu" "In4.Cu" "In6.Cu")
		(teardrops
			(best_length_ratio 0.4)
			(max_length 1)
			(best_width_ratio 0.9)
			(max_width 2)
			(curved_edges yes)
			(filter_ratio 0.9)
			(enabled yes)
			(allow_two_segments yes)
			(prefer_zone_connections yes)
		)
		(net 1)
	)
	(via
		(at 125.45 76.81)
		(size 0.45)
		(drill 0.1)
		(layers "F.Cu" "B.Cu")
		(remove_unused_layers yes)
		(keep_end_layers yes)
		(zone_layer_connections "In1.Cu" "In4.Cu" "In6.Cu")
		(teardrops
			(best_length_ratio 0.4)
			(max_length 1)
			(best_width_ratio 0.9)
			(max_width 2)
			(curved_edges yes)
			(filter_ratio 0.9)
			(enabled yes)
			(allow_two_segments yes)
			(prefer_zone_connections yes)
		)
		(net 1)
	)
	(via
		(at 150.175 88.91)
		(size 0.45)
		(drill 0.1)
		(layers "F.Cu" "B.Cu")
		(remove_unused_layers yes)
		(keep_end_layers yes)
		(free yes)
		(zone_layer_connections "In1.Cu" "In4.Cu" "In6.Cu")
		(teardrops
			(best_length_ratio 0.4)
			(max_length 1)
			(best_width_ratio 0.9)
			(max_width 2)
			(curved_edges yes)
			(filter_ratio 0.9)
			(enabled yes)
			(allow_two_segments yes)
			(prefer_zone_connections yes)
		)
		(net 1)
	)
	(via
		(at 283.45 145.81)
		(size 0.45)
		(drill 0.1)
		(layers "F.Cu" "B.Cu")
		(remove_unused_layers yes)
		(keep_end_layers yes)
		(zone_layer_connections "In1.Cu" "In4.Cu" "In6.Cu")
		(teardrops
			(best_length_ratio 0.4)
			(max_length 1)
			(best_width_ratio 0.9)
			(max_width 2)
			(curved_edges yes)
			(filter_ratio 0.9)
			(enabled yes)
			(allow_two_segments yes)
			(prefer_zone_connections yes)
		)
		(net 1)
	)
	(via
		(at 138.95 90.31)
		(size 0.45)
		(drill 0.1)
		(layers "F.Cu" "B.Cu")
		(remove_unused_layers yes)
		(keep_end_layers yes)
		(zone_layer_connections "In1.Cu" "In4.Cu" "In6.Cu")
		(teardrops
			(best_length_ratio 0.4)
			(max_length 1)
			(best_width_ratio 0.9)
			(max_width 2)
			(curved_edges yes)
			(filter_ratio 0.9)
			(enabled yes)
			(allow_two_segments yes)
			(prefer_zone_connections yes)
		)
		(net 1)
	)
	(via
		(at 181.95 73.31)
		(size 0.45)
		(drill 0.1)
		(layers "F.Cu" "B.Cu")
		(remove_unused_layers yes)
		(keep_end_layers yes)
		(zone_layer_connections "In1.Cu" "In4.Cu" "In6.Cu")
		(teardrops
			(best_length_ratio 0.4)
			(max_length 1)
			(best_width_ratio 0.9)
			(max_width 2)
			(curved_edges yes)
			(filter_ratio 0.9)
			(enabled yes)
			(allow_two_segments yes)
			(prefer_zone_connections yes)
		)
		(net 1)
	)
	(via
		(at 193.95 141.925)
		(size 0.45)
		(drill 0.1)
		(layers "F.Cu" "B.Cu")
		(teardrops
			(best_length_ratio 0.4)
			(max_length 1)
			(best_width_ratio 0.9)
			(max_width 2)
			(curved_edges yes)
			(filter_ratio 0.9)
			(enabled yes)
			(allow_two_segments yes)
			(prefer_zone_connections yes)
		)
		(net 1)
	)
	(via
		(at 220.5 157.8)
		(size 0.45)
		(drill 0.1)
		(layers "F.Cu" "B.Cu")
		(teardrops
			(best_length_ratio 0.4)
			(max_length 1)
			(best_width_ratio 0.9)
			(max_width 2)
			(curved_edges yes)
			(filter_ratio 0.9)
			(enabled yes)
			(allow_two_segments yes)
			(prefer_zone_connections yes)
		)
		(net 1)
	)
	(via
		(at 194.65181 134.883732)
		(size 0.45)
		(drill 0.1)
		(layers "F.Cu" "B.Cu")
		(remove_unused_layers yes)
		(keep_end_layers yes)
		(zone_layer_connections "In1.Cu" "In4.Cu" "In6.Cu")
		(teardrops
			(best_length_ratio 0.4)
			(max_length 1)
			(best_width_ratio 0.9)
			(max_width 2)
			(curved_edges yes)
			(filter_ratio 0.9)
			(enabled yes)
			(allow_two_segments yes)
			(prefer_zone_connections yes)
		)
		(net 1)
	)
	(via
		(at 126.95 151.81)
		(size 0.45)
		(drill 0.1)
		(layers "F.Cu" "B.Cu")
		(remove_unused_layers yes)
		(keep_end_layers yes)
		(zone_layer_connections "In1.Cu" "In4.Cu" "In6.Cu")
		(teardrops
			(best_length_ratio 0.4)
			(max_length 1)
			(best_width_ratio 0.9)
			(max_width 2)
			(curved_edges yes)
			(filter_ratio 0.9)
			(enabled yes)
			(allow_two_segments yes)
			(prefer_zone_connections yes)
		)
		(net 1)
	)
	(via
		(at 276.45 122.81)
		(size 0.45)
		(drill 0.1)
		(layers "F.Cu" "B.Cu")
		(remove_unused_layers yes)
		(keep_end_layers yes)
		(zone_layer_connections "In1.Cu" "In4.Cu" "In6.Cu")
		(teardrops
			(best_length_ratio 0.4)
			(max_length 1)
			(best_width_ratio 0.9)
			(max_width 2)
			(curved_edges yes)
			(filter_ratio 0.9)
			(enabled yes)
			(allow_two_segments yes)
			(prefer_zone_connections yes)
		)
		(net 1)
	)
	(via
		(at 251.625 130.89)
		(size 0.45)
		(drill 0.1)
		(layers "F.Cu" "B.Cu")
		(remove_unused_layers yes)
		(keep_end_layers yes)
		(zone_layer_connections "In1.Cu" "In4.Cu" "In6.Cu")
		(teardrops
			(best_length_ratio 0.4)
			(max_length 1)
			(best_width_ratio 0.9)
			(max_width 2)
			(curved_edges yes)
			(filter_ratio 0.9)
			(enabled yes)
			(allow_two_segments yes)
			(prefer_zone_connections yes)
		)
		(net 1)
	)
	(via
		(at 291.2 74.96)
		(size 0.45)
		(drill 0.1)
		(layers "F.Cu" "B.Cu")
		(remove_unused_layers yes)
		(keep_end_layers yes)
		(free yes)
		(zone_layer_connections "In1.Cu" "In4.Cu" "In6.Cu")
		(teardrops
			(best_length_ratio 0.4)
			(max_length 1)
			(best_width_ratio 0.9)
			(max_width 2)
			(curved_edges yes)
			(filter_ratio 0.9)
			(enabled yes)
			(allow_two_segments yes)
			(prefer_zone_connections yes)
		)
		(net 1)
	)
	(via
		(at 127.8 73.01)
		(size 0.45)
		(drill 0.1)
		(layers "F.Cu" "B.Cu")
		(remove_unused_layers yes)
		(keep_end_layers yes)
		(zone_layer_connections "In1.Cu" "In4.Cu" "In6.Cu")
		(teardrops
			(best_length_ratio 0.4)
			(max_length 1)
			(best_width_ratio 0.9)
			(max_width 2)
			(curved_edges yes)
			(filter_ratio 0.9)
			(enabled yes)
			(allow_two_segments yes)
			(prefer_zone_connections yes)
		)
		(net 1)
	)
	(via
		(at 109.9 148.4)
		(size 0.45)
		(drill 0.1)
		(layers "F.Cu" "B.Cu")
		(remove_unused_layers yes)
		(keep_end_layers yes)
		(zone_layer_connections "In1.Cu" "In4.Cu" "In6.Cu")
		(teardrops
			(best_length_ratio 0.4)
			(max_length 1)
			(best_width_ratio 0.9)
			(max_width 2)
			(curved_edges yes)
			(filter_ratio 0.9)
			(enabled yes)
			(allow_two_segments yes)
			(prefer_zone_connections yes)
		)
		(net 1)
	)
	(via
		(at 173.203893 100.909175)
		(size 0.45)
		(drill 0.1)
		(layers "F.Cu" "B.Cu")
		(remove_unused_layers yes)
		(keep_end_layers yes)
		(zone_layer_connections "In1.Cu" "In4.Cu" "In6.Cu")
		(teardrops
			(best_length_ratio 0.4)
			(max_length 1)
			(best_width_ratio 0.9)
			(max_width 2)
			(curved_edges yes)
			(filter_ratio 0.9)
			(enabled yes)
			(allow_two_segments yes)
			(prefer_zone_connections yes)
		)
		(net 1)
	)
	(via
		(at 158.38 142.36)
		(size 0.45)
		(drill 0.1)
		(layers "F.Cu" "B.Cu")
		(remove_unused_layers yes)
		(keep_end_layers yes)
		(zone_layer_connections "In1.Cu" "In4.Cu" "In6.Cu")
		(teardrops
			(best_length_ratio 0.4)
			(max_length 1)
			(best_width_ratio 0.9)
			(max_width 2)
			(curved_edges yes)
			(filter_ratio 0.9)
			(enabled yes)
			(allow_two_segments yes)
			(prefer_zone_connections yes)
		)
		(net 1)
	)
	(via
		(at 152.5685 80.5595)
		(size 0.45)
		(drill 0.1)
		(layers "F.Cu" "B.Cu")
		(remove_unused_layers yes)
		(keep_end_layers yes)
		(zone_layer_connections "In1.Cu" "In4.Cu" "In6.Cu")
		(teardrops
			(best_length_ratio 0.4)
			(max_length 1)
			(best_width_ratio 0.9)
			(max_width 2)
			(curved_edges yes)
			(filter_ratio 0.9)
			(enabled yes)
			(allow_two_segments yes)
			(prefer_zone_connections yes)
		)
		(net 1)
	)
	(via
		(at 166.8 159.425)
		(size 0.45)
		(drill 0.1)
		(layers "F.Cu" "B.Cu")
		(teardrops
			(best_length_ratio 0.4)
			(max_length 1)
			(best_width_ratio 0.9)
			(max_width 2)
			(curved_edges yes)
			(filter_ratio 0.9)
			(enabled yes)
			(allow_two_segments yes)
			(prefer_zone_connections yes)
		)
		(net 1)
	)
	(via
		(at 112.93 107.65)
		(size 0.45)
		(drill 0.1)
		(layers "F.Cu" "B.Cu")
		(remove_unused_layers yes)
		(keep_end_layers yes)
		(zone_layer_connections "In1.Cu" "In4.Cu" "In6.Cu")
		(teardrops
			(best_length_ratio 0.4)
			(max_length 1)
			(best_width_ratio 0.9)
			(max_width 2)
			(curved_edges yes)
			(filter_ratio 0.9)
			(enabled yes)
			(allow_two_segments yes)
			(prefer_zone_connections yes)
		)
		(net 1)
	)
	(via
		(at 159.949 161.297)
		(size 0.45)
		(drill 0.1)
		(layers "F.Cu" "B.Cu")
		(remove_unused_layers yes)
		(keep_end_layers yes)
		(zone_layer_connections "In1.Cu" "In4.Cu" "In6.Cu")
		(teardrops
			(best_length_ratio 0.4)
			(max_length 1)
			(best_width_ratio 0.9)
			(max_width 2)
			(curved_edges yes)
			(filter_ratio 0.9)
			(enabled yes)
			(allow_two_segments yes)
			(prefer_zone_connections yes)
		)
		(net 1)
	)
	(via
		(at 212 155.5)
		(size 0.45)
		(drill 0.1)
		(layers "F.Cu" "B.Cu")
		(teardrops
			(best_length_ratio 0.4)
			(max_length 1)
			(best_width_ratio 0.9)
			(max_width 2)
			(curved_edges yes)
			(filter_ratio 0.9)
			(enabled yes)
			(allow_two_segments yes)
			(prefer_zone_connections yes)
		)
		(net 1)
	)
	(via
		(at 298.699 75.04)
		(size 0.45)
		(drill 0.1)
		(layers "F.Cu" "B.Cu")
		(remove_unused_layers yes)
		(keep_end_layers yes)
		(zone_layer_connections "In1.Cu" "In4.Cu" "In6.Cu")
		(teardrops
			(best_length_ratio 0.4)
			(max_length 1)
			(best_width_ratio 0.9)
			(max_width 2)
			(curved_edges yes)
			(filter_ratio 0.9)
			(enabled yes)
			(allow_two_segments yes)
			(prefer_zone_connections yes)
		)
		(net 1)
	)
	(via
		(at 95.45 70.81)
		(size 0.45)
		(drill 0.1)
		(layers "F.Cu" "B.Cu")
		(remove_unused_layers yes)
		(keep_end_layers yes)
		(zone_layer_connections "In1.Cu" "In4.Cu" "In6.Cu")
		(teardrops
			(best_length_ratio 0.4)
			(max_length 1)
			(best_width_ratio 0.9)
			(max_width 2)
			(curved_edges yes)
			(filter_ratio 0.9)
			(enabled yes)
			(allow_two_segments yes)
			(prefer_zone_connections yes)
		)
		(net 1)
	)
	(via
		(at 104.45 129.81)
		(size 0.45)
		(drill 0.1)
		(layers "F.Cu" "B.Cu")
		(remove_unused_layers yes)
		(keep_end_layers yes)
		(zone_layer_connections "In1.Cu" "In4.Cu" "In6.Cu")
		(teardrops
			(best_length_ratio 0.4)
			(max_length 1)
			(best_width_ratio 0.9)
			(max_width 2)
			(curved_edges yes)
			(filter_ratio 0.9)
			(enabled yes)
			(allow_two_segments yes)
			(prefer_zone_connections yes)
		)
		(net 1)
	)
	(via
		(at 173.95 80.81)
		(size 0.45)
		(drill 0.1)
		(layers "F.Cu" "B.Cu")
		(remove_unused_layers yes)
		(keep_end_layers yes)
		(zone_layer_connections "In1.Cu" "In4.Cu" "In6.Cu")
		(teardrops
			(best_length_ratio 0.4)
			(max_length 1)
			(best_width_ratio 0.9)
			(max_width 2)
			(curved_edges yes)
			(filter_ratio 0.9)
			(enabled yes)
			(allow_two_segments yes)
			(prefer_zone_connections yes)
		)
		(net 1)
	)
	(via
		(at 245.95 120.31)
		(size 0.45)
		(drill 0.1)
		(layers "F.Cu" "B.Cu")
		(remove_unused_layers yes)
		(keep_end_layers yes)
		(free yes)
		(zone_layer_connections "In1.Cu" "In4.Cu" "In6.Cu")
		(teardrops
			(best_length_ratio 0.4)
			(max_length 1)
			(best_width_ratio 0.9)
			(max_width 2)
			(curved_edges yes)
			(filter_ratio 0.9)
			(enabled yes)
			(allow_two_segments yes)
			(prefer_zone_connections yes)
		)
		(net 1)
	)
	(via
		(at 159.15 71.1)
		(size 0.45)
		(drill 0.1)
		(layers "F.Cu" "B.Cu")
		(remove_unused_layers yes)
		(keep_end_layers yes)
		(zone_layer_connections "In1.Cu" "In4.Cu" "In6.Cu")
		(teardrops
			(best_length_ratio 0.4)
			(max_length 1)
			(best_width_ratio 0.9)
			(max_width 2)
			(curved_edges yes)
			(filter_ratio 0.9)
			(enabled yes)
			(allow_two_segments yes)
			(prefer_zone_connections yes)
		)
		(net 1)
	)
	(via
		(at 130.95 156.31)
		(size 0.45)
		(drill 0.1)
		(layers "F.Cu" "B.Cu")
		(remove_unused_layers yes)
		(keep_end_layers yes)
		(zone_layer_connections "In1.Cu" "In4.Cu" "In6.Cu")
		(teardrops
			(best_length_ratio 0.4)
			(max_length 1)
			(best_width_ratio 0.9)
			(max_width 2)
			(curved_edges yes)
			(filter_ratio 0.9)
			(enabled yes)
			(allow_two_segments yes)
			(prefer_zone_connections yes)
		)
		(net 1)
	)
	(via
		(at 174.7 97.85)
		(size 0.45)
		(drill 0.1)
		(layers "F.Cu" "B.Cu")
		(remove_unused_layers yes)
		(keep_end_layers yes)
		(zone_layer_connections "In1.Cu" "In4.Cu" "In6.Cu")
		(teardrops
			(best_length_ratio 0.4)
			(max_length 1)
			(best_width_ratio 0.9)
			(max_width 2)
			(curved_edges yes)
			(filter_ratio 0.9)
			(enabled yes)
			(allow_two_segments yes)
			(prefer_zone_connections yes)
		)
		(net 1)
	)
	(via
		(at 101.45 98.81)
		(size 0.45)
		(drill 0.1)
		(layers "F.Cu" "B.Cu")
		(remove_unused_layers yes)
		(keep_end_layers yes)
		(zone_layer_connections "In1.Cu" "In4.Cu" "In6.Cu")
		(teardrops
			(best_length_ratio 0.4)
			(max_length 1)
			(best_width_ratio 0.9)
			(max_width 2)
			(curved_edges yes)
			(filter_ratio 0.9)
			(enabled yes)
			(allow_two_segments yes)
			(prefer_zone_connections yes)
		)
		(net 1)
	)
	(via
		(at 184.95 70.31)
		(size 0.45)
		(drill 0.1)
		(layers "F.Cu" "B.Cu")
		(remove_unused_layers yes)
		(keep_end_layers yes)
		(free yes)
		(zone_layer_connections "In1.Cu" "In4.Cu" "In6.Cu")
		(teardrops
			(best_length_ratio 0.4)
			(max_length 1)
			(best_width_ratio 0.9)
			(max_width 2)
			(curved_edges yes)
			(filter_ratio 0.9)
			(enabled yes)
			(allow_two_segments yes)
			(prefer_zone_connections yes)
		)
		(net 1)
	)
	(via
		(at 202.95 90.31)
		(size 0.45)
		(drill 0.1)
		(layers "F.Cu" "B.Cu")
		(remove_unused_layers yes)
		(keep_end_layers yes)
		(zone_layer_connections "In1.Cu" "In4.Cu" "In6.Cu")
		(teardrops
			(best_length_ratio 0.4)
			(max_length 1)
			(best_width_ratio 0.9)
			(max_width 2)
			(curved_edges yes)
			(filter_ratio 0.9)
			(enabled yes)
			(allow_two_segments yes)
			(prefer_zone_connections yes)
		)
		(net 1)
	)
	(via
		(at 100.101 73.01)
		(size 0.45)
		(drill 0.1)
		(layers "F.Cu" "B.Cu")
		(remove_unused_layers yes)
		(keep_end_layers yes)
		(zone_layer_connections "In1.Cu" "In4.Cu" "In6.Cu")
		(teardrops
			(best_length_ratio 0.4)
			(max_length 1)
			(best_width_ratio 0.9)
			(max_width 2)
			(curved_edges yes)
			(filter_ratio 0.9)
			(enabled yes)
			(allow_two_segments yes)
			(prefer_zone_connections yes)
		)
		(net 1)
	)
	(via
		(at 216.45 87.81)
		(size 0.45)
		(drill 0.1)
		(layers "F.Cu" "B.Cu")
		(remove_unused_layers yes)
		(keep_end_layers yes)
		(zone_layer_connections "In1.Cu" "In4.Cu" "In6.Cu")
		(teardrops
			(best_length_ratio 0.4)
			(max_length 1)
			(best_width_ratio 0.9)
			(max_width 2)
			(curved_edges yes)
			(filter_ratio 0.9)
			(enabled yes)
			(allow_two_segments yes)
			(prefer_zone_connections yes)
		)
		(net 1)
	)
	(via
		(at 205.55 161.921)
		(size 0.45)
		(drill 0.1)
		(layers "F.Cu" "B.Cu")
		(teardrops
			(best_length_ratio 0.4)
			(max_length 1)
			(best_width_ratio 0.9)
			(max_width 2)
			(curved_edges yes)
			(filter_ratio 0.9)
			(enabled yes)
			(allow_two_segments yes)
			(prefer_zone_connections yes)
		)
		(net 1)
	)
	(via
		(at 276.45 125.31)
		(size 0.45)
		(drill 0.1)
		(layers "F.Cu" "B.Cu")
		(remove_unused_layers yes)
		(keep_end_layers yes)
		(zone_layer_connections "In1.Cu" "In4.Cu" "In6.Cu")
		(teardrops
			(best_length_ratio 0.4)
			(max_length 1)
			(best_width_ratio 0.9)
			(max_width 2)
			(curved_edges yes)
			(filter_ratio 0.9)
			(enabled yes)
			(allow_two_segments yes)
			(prefer_zone_connections yes)
		)
		(net 1)
	)
	(via
		(at 197.6 166.6)
		(size 0.45)
		(drill 0.1)
		(layers "F.Cu" "B.Cu")
		(teardrops
			(best_length_ratio 0.4)
			(max_length 1)
			(best_width_ratio 0.9)
			(max_width 2)
			(curved_edges yes)
			(filter_ratio 0.9)
			(enabled yes)
			(allow_two_segments yes)
			(prefer_zone_connections yes)
		)
		(net 1)
	)
	(via
		(at 152.5685 88.0585)
		(size 0.45)
		(drill 0.1)
		(layers "F.Cu" "B.Cu")
		(remove_unused_layers yes)
		(keep_end_layers yes)
		(zone_layer_connections "In1.Cu" "In4.Cu" "In6.Cu")
		(teardrops
			(best_length_ratio 0.4)
			(max_length 1)
			(best_width_ratio 0.9)
			(max_width 2)
			(curved_edges yes)
			(filter_ratio 0.9)
			(enabled yes)
			(allow_two_segments yes)
			(prefer_zone_connections yes)
		)
		(net 1)
	)
	(via
		(at 177.45 71.81)
		(size 0.45)
		(drill 0.1)
		(layers "F.Cu" "B.Cu")
		(remove_unused_layers yes)
		(keep_end_layers yes)
		(zone_layer_connections "In1.Cu" "In4.Cu" "In6.Cu")
		(teardrops
			(best_length_ratio 0.4)
			(max_length 1)
			(best_width_ratio 0.9)
			(max_width 2)
			(curved_edges yes)
			(filter_ratio 0.9)
			(enabled yes)
			(allow_two_segments yes)
			(prefer_zone_connections yes)
		)
		(net 1)
	)
	(via
		(at 263.95 123.31)
		(size 0.45)
		(drill 0.1)
		(layers "F.Cu" "B.Cu")
		(remove_unused_layers yes)
		(keep_end_layers yes)
		(zone_layer_connections "In1.Cu" "In4.Cu" "In6.Cu")
		(teardrops
			(best_length_ratio 0.4)
			(max_length 1)
			(best_width_ratio 0.9)
			(max_width 2)
			(curved_edges yes)
			(filter_ratio 0.9)
			(enabled yes)
			(allow_two_segments yes)
			(prefer_zone_connections yes)
		)
		(net 1)
	)
	(via
		(at 193.95 83.81)
		(size 0.45)
		(drill 0.1)
		(layers "F.Cu" "B.Cu")
		(remove_unused_layers yes)
		(keep_end_layers yes)
		(free yes)
		(zone_layer_connections "In1.Cu" "In4.Cu" "In6.Cu")
		(teardrops
			(best_length_ratio 0.4)
			(max_length 1)
			(best_width_ratio 0.9)
			(max_width 2)
			(curved_edges yes)
			(filter_ratio 0.9)
			(enabled yes)
			(allow_two_segments yes)
			(prefer_zone_connections yes)
		)
		(net 1)
	)
	(via
		(at 186.45 68.81)
		(size 0.45)
		(drill 0.1)
		(layers "F.Cu" "B.Cu")
		(remove_unused_layers yes)
		(keep_end_layers yes)
		(zone_layer_connections "In1.Cu" "In4.Cu" "In6.Cu")
		(teardrops
			(best_length_ratio 0.4)
			(max_length 1)
			(best_width_ratio 0.9)
			(max_width 2)
			(curved_edges yes)
			(filter_ratio 0.9)
			(enabled yes)
			(allow_two_segments yes)
			(prefer_zone_connections yes)
		)
		(net 1)
	)
	(via
		(at 106.95 168.31)
		(size 0.45)
		(drill 0.1)
		(layers "F.Cu" "B.Cu")
		(remove_unused_layers yes)
		(keep_end_layers yes)
		(zone_layer_connections "In1.Cu" "In4.Cu" "In6.Cu")
		(teardrops
			(best_length_ratio 0.4)
			(max_length 1)
			(best_width_ratio 0.9)
			(max_width 2)
			(curved_edges yes)
			(filter_ratio 0.9)
			(enabled yes)
			(allow_two_segments yes)
			(prefer_zone_connections yes)
		)
		(net 1)
	)
	(via
		(at 265.45 101.81)
		(size 0.45)
		(drill 0.1)
		(layers "F.Cu" "B.Cu")
		(remove_unused_layers yes)
		(keep_end_layers yes)
		(zone_layer_connections "In1.Cu" "In4.Cu" "In6.Cu")
		(teardrops
			(best_length_ratio 0.4)
			(max_length 1)
			(best_width_ratio 0.9)
			(max_width 2)
			(curved_edges yes)
			(filter_ratio 0.9)
			(enabled yes)
			(allow_two_segments yes)
			(prefer_zone_connections yes)
		)
		(net 1)
	)
	(via
		(at 95.45 76.81)
		(size 0.45)
		(drill 0.1)
		(layers "F.Cu" "B.Cu")
		(remove_unused_layers yes)
		(keep_end_layers yes)
		(zone_layer_connections "In1.Cu" "In4.Cu" "In6.Cu")
		(teardrops
			(best_length_ratio 0.4)
			(max_length 1)
			(best_width_ratio 0.9)
			(max_width 2)
			(curved_edges yes)
			(filter_ratio 0.9)
			(enabled yes)
			(allow_two_segments yes)
			(prefer_zone_connections yes)
		)
		(net 1)
	)
	(via
		(at 278.95 144.31)
		(size 0.45)
		(drill 0.1)
		(layers "F.Cu" "B.Cu")
		(remove_unused_layers yes)
		(keep_end_layers yes)
		(zone_layer_connections "In1.Cu" "In4.Cu" "In6.Cu")
		(teardrops
			(best_length_ratio 0.4)
			(max_length 1)
			(best_width_ratio 0.9)
			(max_width 2)
			(curved_edges yes)
			(filter_ratio 0.9)
			(enabled yes)
			(allow_two_segments yes)
			(prefer_zone_connections yes)
		)
		(net 1)
	)
	(via
		(at 219.45 90.81)
		(size 0.45)
		(drill 0.1)
		(layers "F.Cu" "B.Cu")
		(remove_unused_layers yes)
		(keep_end_layers yes)
		(zone_layer_connections "In1.Cu" "In4.Cu" "In6.Cu")
		(teardrops
			(best_length_ratio 0.4)
			(max_length 1)
			(best_width_ratio 0.9)
			(max_width 2)
			(curved_edges yes)
			(filter_ratio 0.9)
			(enabled yes)
			(allow_two_segments yes)
			(prefer_zone_connections yes)
		)
		(net 1)
	)
	(via
		(at 125.45 74.81)
		(size 0.45)
		(drill 0.1)
		(layers "F.Cu" "B.Cu")
		(remove_unused_layers yes)
		(keep_end_layers yes)
		(zone_layer_connections "In1.Cu" "In4.Cu" "In6.Cu")
		(teardrops
			(best_length_ratio 0.4)
			(max_length 1)
			(best_width_ratio 0.9)
			(max_width 2)
			(curved_edges yes)
			(filter_ratio 0.9)
			(enabled yes)
			(allow_two_segments yes)
			(prefer_zone_connections yes)
		)
		(net 1)
	)
	(via
		(at 222.45 82.31)
		(size 0.45)
		(drill 0.1)
		(layers "F.Cu" "B.Cu")
		(remove_unused_layers yes)
		(keep_end_layers yes)
		(free yes)
		(zone_layer_connections "In1.Cu" "In4.Cu" "In6.Cu")
		(teardrops
			(best_length_ratio 0.4)
			(max_length 1)
			(best_width_ratio 0.9)
			(max_width 2)
			(curved_edges yes)
			(filter_ratio 0.9)
			(enabled yes)
			(allow_two_segments yes)
			(prefer_zone_connections yes)
		)
		(net 1)
	)
	(via
		(at 106.95 169.81)
		(size 0.45)
		(drill 0.1)
		(layers "F.Cu" "B.Cu")
		(remove_unused_layers yes)
		(keep_end_layers yes)
		(zone_layer_connections "In1.Cu" "In4.Cu" "In6.Cu")
		(teardrops
			(best_length_ratio 0.4)
			(max_length 1)
			(best_width_ratio 0.9)
			(max_width 2)
			(curved_edges yes)
			(filter_ratio 0.9)
			(enabled yes)
			(allow_two_segments yes)
			(prefer_zone_connections yes)
		)
		(net 1)
	)
	(via
		(at 147.88 147.63355)
		(size 0.45)
		(drill 0.1)
		(layers "F.Cu" "B.Cu")
		(remove_unused_layers yes)
		(keep_end_layers yes)
		(zone_layer_connections "In1.Cu" "In4.Cu" "In6.Cu")
		(teardrops
			(best_length_ratio 0.4)
			(max_length 1)
			(best_width_ratio 0.9)
			(max_width 2)
			(curved_edges yes)
			(filter_ratio 0.9)
			(enabled yes)
			(allow_two_segments yes)
			(prefer_zone_connections yes)
		)
		(net 1)
	)
	(via
		(at 152.45 132.86)
		(size 0.45)
		(drill 0.1)
		(layers "F.Cu" "B.Cu")
		(remove_unused_layers yes)
		(keep_end_layers yes)
		(zone_layer_connections "In1.Cu" "In4.Cu" "In6.Cu")
		(teardrops
			(best_length_ratio 0.4)
			(max_length 1)
			(best_width_ratio 0.9)
			(max_width 2)
			(curved_edges yes)
			(filter_ratio 0.9)
			(enabled yes)
			(allow_two_segments yes)
			(prefer_zone_connections yes)
		)
		(net 1)
	)
	(via
		(at 293.95 144.31)
		(size 0.45)
		(drill 0.1)
		(layers "F.Cu" "B.Cu")
		(remove_unused_layers yes)
		(keep_end_layers yes)
		(zone_layer_connections "In1.Cu" "In4.Cu" "In6.Cu")
		(teardrops
			(best_length_ratio 0.4)
			(max_length 1)
			(best_width_ratio 0.9)
			(max_width 2)
			(curved_edges yes)
			(filter_ratio 0.9)
			(enabled yes)
			(allow_two_segments yes)
			(prefer_zone_connections yes)
		)
		(net 1)
	)
	(via
		(at 116.45 82.31)
		(size 0.45)
		(drill 0.1)
		(layers "F.Cu" "B.Cu")
		(remove_unused_layers yes)
		(keep_end_layers yes)
		(zone_layer_connections "In1.Cu" "In4.Cu" "In6.Cu")
		(teardrops
			(best_length_ratio 0.4)
			(max_length 1)
			(best_width_ratio 0.9)
			(max_width 2)
			(curved_edges yes)
			(filter_ratio 0.9)
			(enabled yes)
			(allow_two_segments yes)
			(prefer_zone_connections yes)
		)
		(net 1)
	)
	(via
		(at 166.725 160.4)
		(size 0.45)
		(drill 0.1)
		(layers "F.Cu" "B.Cu")
		(teardrops
			(best_length_ratio 0.4)
			(max_length 1)
			(best_width_ratio 0.9)
			(max_width 2)
			(curved_edges yes)
			(filter_ratio 0.9)
			(enabled yes)
			(allow_two_segments yes)
			(prefer_zone_connections yes)
		)
		(net 1)
	)
	(via
		(at 135.3 74.51)
		(size 0.45)
		(drill 0.1)
		(layers "F.Cu" "B.Cu")
		(remove_unused_layers yes)
		(keep_end_layers yes)
		(free yes)
		(zone_layer_connections "In1.Cu" "In4.Cu" "In6.Cu")
		(teardrops
			(best_length_ratio 0.4)
			(max_length 1)
			(best_width_ratio 0.9)
			(max_width 2)
			(curved_edges yes)
			(filter_ratio 0.9)
			(enabled yes)
			(allow_two_segments yes)
			(prefer_zone_connections yes)
		)
		(net 1)
	)
	(via
		(at 303.697 75.04)
		(size 0.45)
		(drill 0.1)
		(layers "F.Cu" "B.Cu")
		(remove_unused_layers yes)
		(keep_end_layers yes)
		(zone_layer_connections "In1.Cu" "In4.Cu" "In6.Cu")
		(teardrops
			(best_length_ratio 0.4)
			(max_length 1)
			(best_width_ratio 0.9)
			(max_width 2)
			(curved_edges yes)
			(filter_ratio 0.9)
			(enabled yes)
			(allow_two_segments yes)
			(prefer_zone_connections yes)
		)
		(net 1)
	)
	(via
		(at 119.65 147.851)
		(size 0.45)
		(drill 0.1)
		(layers "F.Cu" "B.Cu")
		(remove_unused_layers yes)
		(keep_end_layers yes)
		(zone_layer_connections "In1.Cu" "In4.Cu" "In6.Cu")
		(teardrops
			(best_length_ratio 0.4)
			(max_length 1)
			(best_width_ratio 0.9)
			(max_width 2)
			(curved_edges yes)
			(filter_ratio 0.9)
			(enabled yes)
			(allow_two_segments yes)
			(prefer_zone_connections yes)
		)
		(net 1)
	)
	(via
		(at 149.95 69.81)
		(size 0.45)
		(drill 0.1)
		(layers "F.Cu" "B.Cu")
		(remove_unused_layers yes)
		(keep_end_layers yes)
		(zone_layer_connections "In1.Cu" "In4.Cu" "In6.Cu")
		(teardrops
			(best_length_ratio 0.4)
			(max_length 1)
			(best_width_ratio 0.9)
			(max_width 2)
			(curved_edges yes)
			(filter_ratio 0.9)
			(enabled yes)
			(allow_two_segments yes)
			(prefer_zone_connections yes)
		)
		(net 1)
	)
	(via
		(at 108.3 148.4)
		(size 0.45)
		(drill 0.1)
		(layers "F.Cu" "B.Cu")
		(remove_unused_layers yes)
		(keep_end_layers yes)
		(zone_layer_connections "In1.Cu" "In4.Cu" "In6.Cu")
		(teardrops
			(best_length_ratio 0.4)
			(max_length 1)
			(best_width_ratio 0.9)
			(max_width 2)
			(curved_edges yes)
			(filter_ratio 0.9)
			(enabled yes)
			(allow_two_segments yes)
			(prefer_zone_connections yes)
		)
		(net 1)
	)
	(via
		(at 124.45 160.81)
		(size 0.45)
		(drill 0.1)
		(layers "F.Cu" "B.Cu")
		(remove_unused_layers yes)
		(keep_end_layers yes)
		(zone_layer_connections "In1.Cu" "In4.Cu" "In6.Cu")
		(teardrops
			(best_length_ratio 0.4)
			(max_length 1)
			(best_width_ratio 0.9)
			(max_width 2)
			(curved_edges yes)
			(filter_ratio 0.9)
			(enabled yes)
			(allow_two_segments yes)
			(prefer_zone_connections yes)
		)
		(net 1)
	)
	(via
		(at 127.45 76.81)
		(size 0.45)
		(drill 0.1)
		(layers "F.Cu" "B.Cu")
		(remove_unused_layers yes)
		(keep_end_layers yes)
		(zone_layer_connections "In1.Cu" "In4.Cu" "In6.Cu")
		(teardrops
			(best_length_ratio 0.4)
			(max_length 1)
			(best_width_ratio 0.9)
			(max_width 2)
			(curved_edges yes)
			(filter_ratio 0.9)
			(enabled yes)
			(allow_two_segments yes)
			(prefer_zone_connections yes)
		)
		(net 1)
	)
	(via
		(at 95.45 102.81)
		(size 0.45)
		(drill 0.1)
		(layers "F.Cu" "B.Cu")
		(remove_unused_layers yes)
		(keep_end_layers yes)
		(zone_layer_connections "In1.Cu" "In4.Cu" "In6.Cu")
		(teardrops
			(best_length_ratio 0.4)
			(max_length 1)
			(best_width_ratio 0.9)
			(max_width 2)
			(curved_edges yes)
			(filter_ratio 0.9)
			(enabled yes)
			(allow_two_segments yes)
			(prefer_zone_connections yes)
		)
		(net 1)
	)
	(via
		(at 98.45 125.81)
		(size 0.45)
		(drill 0.1)
		(layers "F.Cu" "B.Cu")
		(remove_unused_layers yes)
		(keep_end_layers yes)
		(zone_layer_connections "In1.Cu" "In4.Cu" "In6.Cu")
		(teardrops
			(best_length_ratio 0.4)
			(max_length 1)
			(best_width_ratio 0.9)
			(max_width 2)
			(curved_edges yes)
			(filter_ratio 0.9)
			(enabled yes)
			(allow_two_segments yes)
			(prefer_zone_connections yes)
		)
		(net 1)
	)
	(via
		(at 300.198 75.04)
		(size 0.45)
		(drill 0.1)
		(layers "F.Cu" "B.Cu")
		(remove_unused_layers yes)
		(keep_end_layers yes)
		(zone_layer_connections "In1.Cu" "In4.Cu" "In6.Cu")
		(teardrops
			(best_length_ratio 0.4)
			(max_length 1)
			(best_width_ratio 0.9)
			(max_width 2)
			(curved_edges yes)
			(filter_ratio 0.9)
			(enabled yes)
			(allow_two_segments yes)
			(prefer_zone_connections yes)
		)
		(net 1)
	)
	(via
		(at 104.45 140.31)
		(size 0.45)
		(drill 0.1)
		(layers "F.Cu" "B.Cu")
		(remove_unused_layers yes)
		(keep_end_layers yes)
		(zone_layer_connections "In1.Cu" "In4.Cu" "In6.Cu")
		(teardrops
			(best_length_ratio 0.4)
			(max_length 1)
			(best_width_ratio 0.9)
			(max_width 2)
			(curved_edges yes)
			(filter_ratio 0.9)
			(enabled yes)
			(allow_two_segments yes)
			(prefer_zone_connections yes)
		)
		(net 1)
	)
	(via
		(at 288.95 115.31)
		(size 0.45)
		(drill 0.1)
		(layers "F.Cu" "B.Cu")
		(remove_unused_layers yes)
		(keep_end_layers yes)
		(zone_layer_connections "In1.Cu" "In4.Cu" "In6.Cu")
		(teardrops
			(best_length_ratio 0.4)
			(max_length 1)
			(best_width_ratio 0.9)
			(max_width 2)
			(curved_edges yes)
			(filter_ratio 0.9)
			(enabled yes)
			(allow_two_segments yes)
			(prefer_zone_connections yes)
		)
		(net 1)
	)
	(via
		(at 168.45 71.81)
		(size 0.45)
		(drill 0.1)
		(layers "F.Cu" "B.Cu")
		(remove_unused_layers yes)
		(keep_end_layers yes)
		(zone_layer_connections "In1.Cu" "In4.Cu" "In6.Cu")
		(teardrops
			(best_length_ratio 0.4)
			(max_length 1)
			(best_width_ratio 0.9)
			(max_width 2)
			(curved_edges yes)
			(filter_ratio 0.9)
			(enabled yes)
			(allow_two_segments yes)
			(prefer_zone_connections yes)
		)
		(net 1)
	)
	(via
		(at 97.45 136.81)
		(size 0.45)
		(drill 0.1)
		(layers "F.Cu" "B.Cu")
		(remove_unused_layers yes)
		(keep_end_layers yes)
		(zone_layer_connections "In1.Cu" "In4.Cu" "In6.Cu")
		(teardrops
			(best_length_ratio 0.4)
			(max_length 1)
			(best_width_ratio 0.9)
			(max_width 2)
			(curved_edges yes)
			(filter_ratio 0.9)
			(enabled yes)
			(allow_two_segments yes)
			(prefer_zone_connections yes)
		)
		(net 1)
	)
	(via
		(at 260.95 170.81)
		(size 0.45)
		(drill 0.1)
		(layers "F.Cu" "B.Cu")
		(remove_unused_layers yes)
		(keep_end_layers yes)
		(zone_layer_connections "In1.Cu" "In4.Cu" "In6.Cu")
		(teardrops
			(best_length_ratio 0.4)
			(max_length 1)
			(best_width_ratio 0.9)
			(max_width 2)
			(curved_edges yes)
			(filter_ratio 0.9)
			(enabled yes)
			(allow_two_segments yes)
			(prefer_zone_connections yes)
		)
		(net 1)
	)
	(via
		(at 169.45 79.31)
		(size 0.45)
		(drill 0.1)
		(layers "F.Cu" "B.Cu")
		(remove_unused_layers yes)
		(keep_end_layers yes)
		(free yes)
		(zone_layer_connections "In1.Cu" "In4.Cu" "In6.Cu")
		(teardrops
			(best_length_ratio 0.4)
			(max_length 1)
			(best_width_ratio 0.9)
			(max_width 2)
			(curved_edges yes)
			(filter_ratio 0.9)
			(enabled yes)
			(allow_two_segments yes)
			(prefer_zone_connections yes)
		)
		(net 1)
	)
	(via
		(at 98.608352 159.100249)
		(size 0.45)
		(drill 0.1)
		(layers "F.Cu" "B.Cu")
		(remove_unused_layers yes)
		(keep_end_layers yes)
		(zone_layer_connections "In1.Cu" "In4.Cu" "In6.Cu")
		(teardrops
			(best_length_ratio 0.4)
			(max_length 1)
			(best_width_ratio 0.9)
			(max_width 2)
			(curved_edges yes)
			(filter_ratio 0.9)
			(enabled yes)
			(allow_two_segments yes)
			(prefer_zone_connections yes)
		)
		(net 1)
	)
	(via
		(at 197.55 155.6)
		(size 0.45)
		(drill 0.1)
		(layers "F.Cu" "B.Cu")
		(teardrops
			(best_length_ratio 0.4)
			(max_length 1)
			(best_width_ratio 0.9)
			(max_width 2)
			(curved_edges yes)
			(filter_ratio 0.9)
			(enabled yes)
			(allow_two_segments yes)
			(prefer_zone_connections yes)
		)
		(net 1)
	)
	(via
		(at 133.95 157.81)
		(size 0.45)
		(drill 0.1)
		(layers "F.Cu" "B.Cu")
		(remove_unused_layers yes)
		(keep_end_layers yes)
		(zone_layer_connections "In1.Cu" "In4.Cu" "In6.Cu")
		(teardrops
			(best_length_ratio 0.4)
			(max_length 1)
			(best_width_ratio 0.9)
			(max_width 2)
			(curved_edges yes)
			(filter_ratio 0.9)
			(enabled yes)
			(allow_two_segments yes)
			(prefer_zone_connections yes)
		)
		(net 1)
	)
	(via
		(at 194.525 167.45)
		(size 0.45)
		(drill 0.1)
		(layers "F.Cu" "B.Cu")
		(teardrops
			(best_length_ratio 0.4)
			(max_length 1)
			(best_width_ratio 0.9)
			(max_width 2)
			(curved_edges yes)
			(filter_ratio 0.9)
			(enabled yes)
			(allow_two_segments yes)
			(prefer_zone_connections yes)
		)
		(net 1)
	)
	(via
		(at 121.95 157.81)
		(size 0.45)
		(drill 0.1)
		(layers "F.Cu" "B.Cu")
		(remove_unused_layers yes)
		(keep_end_layers yes)
		(zone_layer_connections "In1.Cu" "In4.Cu" "In6.Cu")
		(teardrops
			(best_length_ratio 0.4)
			(max_length 1)
			(best_width_ratio 0.9)
			(max_width 2)
			(curved_edges yes)
			(filter_ratio 0.9)
			(enabled yes)
			(allow_two_segments yes)
			(prefer_zone_connections yes)
		)
		(net 1)
	)
	(via
		(at 95.45 68.81)
		(size 0.45)
		(drill 0.1)
		(layers "F.Cu" "B.Cu")
		(remove_unused_layers yes)
		(keep_end_layers yes)
		(zone_layer_connections "In1.Cu" "In4.Cu" "In6.Cu")
		(teardrops
			(best_length_ratio 0.4)
			(max_length 1)
			(best_width_ratio 0.9)
			(max_width 2)
			(curved_edges yes)
			(filter_ratio 0.9)
			(enabled yes)
			(allow_two_segments yes)
			(prefer_zone_connections yes)
		)
		(net 1)
	)
	(via
		(at 208.559175 131.875)
		(size 0.45)
		(drill 0.1)
		(layers "F.Cu" "B.Cu")
		(remove_unused_layers yes)
		(keep_end_layers yes)
		(zone_layer_connections "In1.Cu" "In4.Cu" "In6.Cu")
		(teardrops
			(best_length_ratio 0.4)
			(max_length 1)
			(best_width_ratio 0.9)
			(max_width 2)
			(curved_edges yes)
			(filter_ratio 0.9)
			(enabled yes)
			(allow_two_segments yes)
			(prefer_zone_connections yes)
		)
		(net 1)
	)
	(via
		(at 223.5 152.349)
		(size 0.45)
		(drill 0.1)
		(layers "F.Cu" "B.Cu")
		(teardrops
			(best_length_ratio 0.4)
			(max_length 1)
			(best_width_ratio 0.9)
			(max_width 2)
			(curved_edges yes)
			(filter_ratio 0.9)
			(enabled yes)
			(allow_two_segments yes)
			(prefer_zone_connections yes)
		)
		(net 1)
	)
	(via
		(at 293.95 133.31)
		(size 0.45)
		(drill 0.1)
		(layers "F.Cu" "B.Cu")
		(remove_unused_layers yes)
		(keep_end_layers yes)
		(zone_layer_connections "In1.Cu" "In4.Cu" "In6.Cu")
		(teardrops
			(best_length_ratio 0.4)
			(max_length 1)
			(best_width_ratio 0.9)
			(max_width 2)
			(curved_edges yes)
			(filter_ratio 0.9)
			(enabled yes)
			(allow_two_segments yes)
			(prefer_zone_connections yes)
		)
		(net 1)
	)
	(via
		(at 210.5 152.3)
		(size 0.45)
		(drill 0.1)
		(layers "F.Cu" "B.Cu")
		(teardrops
			(best_length_ratio 0.4)
			(max_length 1)
			(best_width_ratio 0.9)
			(max_width 2)
			(curved_edges yes)
			(filter_ratio 0.9)
			(enabled yes)
			(allow_two_segments yes)
			(prefer_zone_connections yes)
		)
		(net 1)
	)
	(via
		(at 146.45 90.31)
		(size 0.45)
		(drill 0.1)
		(layers "F.Cu" "B.Cu")
		(remove_unused_layers yes)
		(keep_end_layers yes)
		(zone_layer_connections "In1.Cu" "In4.Cu" "In6.Cu")
		(teardrops
			(best_length_ratio 0.4)
			(max_length 1)
			(best_width_ratio 0.9)
			(max_width 2)
			(curved_edges yes)
			(filter_ratio 0.9)
			(enabled yes)
			(allow_two_segments yes)
			(prefer_zone_connections yes)
		)
		(net 1)
	)
	(via
		(at 197.55 150.1)
		(size 0.45)
		(drill 0.1)
		(layers "F.Cu" "B.Cu")
		(teardrops
			(best_length_ratio 0.4)
			(max_length 1)
			(best_width_ratio 0.9)
			(max_width 2)
			(curved_edges yes)
			(filter_ratio 0.9)
			(enabled yes)
			(allow_two_segments yes)
			(prefer_zone_connections yes)
		)
		(net 1)
	)
	(via
		(at 148.45 142.86)
		(size 0.45)
		(drill 0.1)
		(layers "F.Cu" "B.Cu")
		(remove_unused_layers yes)
		(keep_end_layers yes)
		(zone_layer_connections "In1.Cu" "In4.Cu" "In6.Cu")
		(teardrops
			(best_length_ratio 0.4)
			(max_length 1)
			(best_width_ratio 0.9)
			(max_width 2)
			(curved_edges yes)
			(filter_ratio 0.9)
			(enabled yes)
			(allow_two_segments yes)
			(prefer_zone_connections yes)
		)
		(net 1)
	)
	(via
		(at 313.648 163.96)
		(size 0.45)
		(drill 0.1)
		(layers "F.Cu" "B.Cu")
		(remove_unused_layers yes)
		(keep_end_layers yes)
		(zone_layer_connections "In1.Cu" "In4.Cu" "In6.Cu")
		(teardrops
			(best_length_ratio 0.4)
			(max_length 1)
			(best_width_ratio 0.9)
			(max_width 2)
			(curved_edges yes)
			(filter_ratio 0.9)
			(enabled yes)
			(allow_two_segments yes)
			(prefer_zone_connections yes)
		)
		(net 1)
	)
	(via
		(at 223.5 157.8)
		(size 0.45)
		(drill 0.1)
		(layers "F.Cu" "B.Cu")
		(teardrops
			(best_length_ratio 0.4)
			(max_length 1)
			(best_width_ratio 0.9)
			(max_width 2)
			(curved_edges yes)
			(filter_ratio 0.9)
			(enabled yes)
			(allow_two_segments yes)
			(prefer_zone_connections yes)
		)
		(net 1)
	)
	(via
		(at 126.45 169.81)
		(size 0.45)
		(drill 0.1)
		(layers "F.Cu" "B.Cu")
		(remove_unused_layers yes)
		(keep_end_layers yes)
		(zone_layer_connections "In1.Cu" "In4.Cu" "In6.Cu")
		(teardrops
			(best_length_ratio 0.4)
			(max_length 1)
			(best_width_ratio 0.9)
			(max_width 2)
			(curved_edges yes)
			(filter_ratio 0.9)
			(enabled yes)
			(allow_two_segments yes)
			(prefer_zone_connections yes)
		)
		(net 1)
	)
	(via
		(at 126.45 75.81)
		(size 0.45)
		(drill 0.1)
		(layers "F.Cu" "B.Cu")
		(remove_unused_layers yes)
		(keep_end_layers yes)
		(zone_layer_connections "In1.Cu" "In4.Cu" "In6.Cu")
		(teardrops
			(best_length_ratio 0.4)
			(max_length 1)
			(best_width_ratio 0.9)
			(max_width 2)
			(curved_edges yes)
			(filter_ratio 0.9)
			(enabled yes)
			(allow_two_segments yes)
			(prefer_zone_connections yes)
		)
		(net 1)
	)
	(via
		(at 242.95 117.31)
		(size 0.45)
		(drill 0.1)
		(layers "F.Cu" "B.Cu")
		(remove_unused_layers yes)
		(keep_end_layers yes)
		(zone_layer_connections "In1.Cu" "In4.Cu" "In6.Cu")
		(teardrops
			(best_length_ratio 0.4)
			(max_length 1)
			(best_width_ratio 0.9)
			(max_width 2)
			(curved_edges yes)
			(filter_ratio 0.9)
			(enabled yes)
			(allow_two_segments yes)
			(prefer_zone_connections yes)
		)
		(net 1)
	)
	(via
		(at 220.5 162)
		(size 0.45)
		(drill 0.1)
		(layers "F.Cu" "B.Cu")
		(teardrops
			(best_length_ratio 0.4)
			(max_length 1)
			(best_width_ratio 0.9)
			(max_width 2)
			(curved_edges yes)
			(filter_ratio 0.9)
			(enabled yes)
			(allow_two_segments yes)
			(prefer_zone_connections yes)
		)
		(net 1)
	)
	(via
		(at 129.5 103.86)
		(size 0.45)
		(drill 0.1)
		(layers "F.Cu" "B.Cu")
		(remove_unused_layers yes)
		(keep_end_layers yes)
		(zone_layer_connections "In1.Cu" "In4.Cu" "In6.Cu")
		(teardrops
			(best_length_ratio 0.4)
			(max_length 1)
			(best_width_ratio 0.9)
			(max_width 2)
			(curved_edges yes)
			(filter_ratio 0.9)
			(enabled yes)
			(allow_two_segments yes)
			(prefer_zone_connections yes)
		)
		(net 1)
	)
	(via
		(at 187.3 128.1)
		(size 0.45)
		(drill 0.1)
		(layers "F.Cu" "B.Cu")
		(remove_unused_layers yes)
		(keep_end_layers yes)
		(zone_layer_connections "In1.Cu" "In4.Cu" "In6.Cu")
		(teardrops
			(best_length_ratio 0.4)
			(max_length 1)
			(best_width_ratio 0.9)
			(max_width 2)
			(curved_edges yes)
			(filter_ratio 0.9)
			(enabled yes)
			(allow_two_segments yes)
			(prefer_zone_connections yes)
		)
		(net 1)
	)
	(via
		(at 261.54 88.429999)
		(size 0.45)
		(drill 0.1)
		(layers "F.Cu" "B.Cu")
		(remove_unused_layers yes)
		(keep_end_layers yes)
		(zone_layer_connections "In1.Cu" "In4.Cu" "In6.Cu")
		(teardrops
			(best_length_ratio 0.4)
			(max_length 1)
			(best_width_ratio 0.9)
			(max_width 2)
			(curved_edges yes)
			(filter_ratio 0.9)
			(enabled yes)
			(allow_two_segments yes)
			(prefer_zone_connections yes)
		)
		(net 1)
	)
	(via
		(at 255.150707 78.135)
		(size 0.45)
		(drill 0.1)
		(layers "F.Cu" "B.Cu")
		(remove_unused_layers yes)
		(keep_end_layers yes)
		(zone_layer_connections "In1.Cu" "In4.Cu" "In6.Cu")
		(teardrops
			(best_length_ratio 0.4)
			(max_length 1)
			(best_width_ratio 0.9)
			(max_width 2)
			(curved_edges yes)
			(filter_ratio 0.9)
			(enabled yes)
			(allow_two_segments yes)
			(prefer_zone_connections yes)
		)
		(net 1)
	)
	(via
		(at 136.18 144.75)
		(size 0.45)
		(drill 0.1)
		(layers "F.Cu" "B.Cu")
		(remove_unused_layers yes)
		(keep_end_layers yes)
		(zone_layer_connections "In1.Cu" "In4.Cu" "In6.Cu")
		(teardrops
			(best_length_ratio 0.4)
			(max_length 1)
			(best_width_ratio 0.9)
			(max_width 2)
			(curved_edges yes)
			(filter_ratio 0.9)
			(enabled yes)
			(allow_two_segments yes)
			(prefer_zone_connections yes)
		)
		(net 1)
	)
	(via
		(at 105.35 168.76)
		(size 0.45)
		(drill 0.1)
		(layers "F.Cu" "B.Cu")
		(remove_unused_layers yes)
		(keep_end_layers yes)
		(zone_layer_connections "In1.Cu" "In4.Cu" "In6.Cu")
		(teardrops
			(best_length_ratio 0.4)
			(max_length 1)
			(best_width_ratio 0.9)
			(max_width 2)
			(curved_edges yes)
			(filter_ratio 0.9)
			(enabled yes)
			(allow_two_segments yes)
			(prefer_zone_connections yes)
		)
		(net 1)
	)
	(via
		(at 121.95 158.81)
		(size 0.45)
		(drill 0.1)
		(layers "F.Cu" "B.Cu")
		(remove_unused_layers yes)
		(keep_end_layers yes)
		(zone_layer_connections "In1.Cu" "In4.Cu" "In6.Cu")
		(teardrops
			(best_length_ratio 0.4)
			(max_length 1)
			(best_width_ratio 0.9)
			(max_width 2)
			(curved_edges yes)
			(filter_ratio 0.9)
			(enabled yes)
			(allow_two_segments yes)
			(prefer_zone_connections yes)
		)
		(net 1)
	)
	(via
		(at 139.95 146.31)
		(size 0.45)
		(drill 0.1)
		(layers "F.Cu" "B.Cu")
		(remove_unused_layers yes)
		(keep_end_layers yes)
		(zone_layer_connections "In1.Cu" "In4.Cu" "In6.Cu")
		(teardrops
			(best_length_ratio 0.4)
			(max_length 1)
			(best_width_ratio 0.9)
			(max_width 2)
			(curved_edges yes)
			(filter_ratio 0.9)
			(enabled yes)
			(allow_two_segments yes)
			(prefer_zone_connections yes)
		)
		(net 1)
	)
	(via
		(at 98 144.6)
		(size 0.45)
		(drill 0.1)
		(layers "F.Cu" "B.Cu")
		(remove_unused_layers yes)
		(keep_end_layers yes)
		(zone_layer_connections "In1.Cu" "In4.Cu" "In6.Cu")
		(teardrops
			(best_length_ratio 0.4)
			(max_length 1)
			(best_width_ratio 0.9)
			(max_width 2)
			(curved_edges yes)
			(filter_ratio 0.9)
			(enabled yes)
			(allow_two_segments yes)
			(prefer_zone_connections yes)
		)
		(net 1)
	)
	(via
		(at 134.45 88.81)
		(size 0.45)
		(drill 0.1)
		(layers "F.Cu" "B.Cu")
		(remove_unused_layers yes)
		(keep_end_layers yes)
		(zone_layer_connections "In1.Cu" "In4.Cu" "In6.Cu")
		(teardrops
			(best_length_ratio 0.4)
			(max_length 1)
			(best_width_ratio 0.9)
			(max_width 2)
			(curved_edges yes)
			(filter_ratio 0.9)
			(enabled yes)
			(allow_two_segments yes)
			(prefer_zone_connections yes)
		)
		(net 1)
	)
	(via
		(at 98.45 92.81)
		(size 0.45)
		(drill 0.1)
		(layers "F.Cu" "B.Cu")
		(remove_unused_layers yes)
		(keep_end_layers yes)
		(zone_layer_connections "In1.Cu" "In4.Cu" "In6.Cu")
		(teardrops
			(best_length_ratio 0.4)
			(max_length 1)
			(best_width_ratio 0.9)
			(max_width 2)
			(curved_edges yes)
			(filter_ratio 0.9)
			(enabled yes)
			(allow_two_segments yes)
			(prefer_zone_connections yes)
		)
		(net 1)
	)
	(via
		(at 311.4645 115.4465)
		(size 0.45)
		(drill 0.1)
		(layers "F.Cu" "B.Cu")
		(remove_unused_layers yes)
		(keep_end_layers yes)
		(free yes)
		(zone_layer_connections "In1.Cu" "In4.Cu" "In6.Cu")
		(teardrops
			(best_length_ratio 0.4)
			(max_length 1)
			(best_width_ratio 0.9)
			(max_width 2)
			(curved_edges yes)
			(filter_ratio 0.9)
			(enabled yes)
			(allow_two_segments yes)
			(prefer_zone_connections yes)
		)
		(net 1)
	)
	(via
		(at 162.45 71.81)
		(size 0.45)
		(drill 0.1)
		(layers "F.Cu" "B.Cu")
		(remove_unused_layers yes)
		(keep_end_layers yes)
		(zone_layer_connections "In1.Cu" "In4.Cu" "In6.Cu")
		(teardrops
			(best_length_ratio 0.4)
			(max_length 1)
			(best_width_ratio 0.9)
			(max_width 2)
			(curved_edges yes)
			(filter_ratio 0.9)
			(enabled yes)
			(allow_two_segments yes)
			(prefer_zone_connections yes)
		)
		(net 1)
	)
	(via
		(at 135.95 81.31)
		(size 0.45)
		(drill 0.1)
		(layers "F.Cu" "B.Cu")
		(remove_unused_layers yes)
		(keep_end_layers yes)
		(zone_layer_connections "In1.Cu" "In4.Cu" "In6.Cu")
		(teardrops
			(best_length_ratio 0.4)
			(max_length 1)
			(best_width_ratio 0.9)
			(max_width 2)
			(curved_edges yes)
			(filter_ratio 0.9)
			(enabled yes)
			(allow_two_segments yes)
			(prefer_zone_connections yes)
		)
		(net 1)
	)
	(via
		(at 260.95 112.81)
		(size 0.45)
		(drill 0.1)
		(layers "F.Cu" "B.Cu")
		(remove_unused_layers yes)
		(keep_end_layers yes)
		(zone_layer_connections "In1.Cu" "In4.Cu" "In6.Cu")
		(teardrops
			(best_length_ratio 0.4)
			(max_length 1)
			(best_width_ratio 0.9)
			(max_width 2)
			(curved_edges yes)
			(filter_ratio 0.9)
			(enabled yes)
			(allow_two_segments yes)
			(prefer_zone_connections yes)
		)
		(net 1)
	)
	(via
		(at 172.95 70.31)
		(size 0.45)
		(drill 0.1)
		(layers "F.Cu" "B.Cu")
		(remove_unused_layers yes)
		(keep_end_layers yes)
		(zone_layer_connections "In1.Cu" "In4.Cu" "In6.Cu")
		(teardrops
			(best_length_ratio 0.4)
			(max_length 1)
			(best_width_ratio 0.9)
			(max_width 2)
			(curved_edges yes)
			(filter_ratio 0.9)
			(enabled yes)
			(allow_two_segments yes)
			(prefer_zone_connections yes)
		)
		(net 1)
	)
	(via
		(at 197.95 85.06)
		(size 0.45)
		(drill 0.1)
		(layers "F.Cu" "B.Cu")
		(remove_unused_layers yes)
		(keep_end_layers yes)
		(zone_layer_connections "In1.Cu" "In4.Cu" "In6.Cu")
		(teardrops
			(best_length_ratio 0.4)
			(max_length 1)
			(best_width_ratio 0.9)
			(max_width 2)
			(curved_edges yes)
			(filter_ratio 0.9)
			(enabled yes)
			(allow_two_segments yes)
			(prefer_zone_connections yes)
		)
		(net 1)
	)
	(via
		(at 124.3475 104.3)
		(size 0.45)
		(drill 0.1)
		(layers "F.Cu" "B.Cu")
		(remove_unused_layers yes)
		(keep_end_layers yes)
		(zone_layer_connections "In1.Cu" "In4.Cu" "In6.Cu")
		(teardrops
			(best_length_ratio 0.4)
			(max_length 1)
			(best_width_ratio 0.9)
			(max_width 2)
			(curved_edges yes)
			(filter_ratio 0.9)
			(enabled yes)
			(allow_two_segments yes)
			(prefer_zone_connections yes)
		)
		(net 1)
	)
	(via
		(at 312.074999 120.86)
		(size 0.45)
		(drill 0.1)
		(layers "F.Cu" "B.Cu")
		(remove_unused_layers yes)
		(keep_end_layers yes)
		(zone_layer_connections "In1.Cu" "In4.Cu" "In6.Cu")
		(teardrops
			(best_length_ratio 0.4)
			(max_length 1)
			(best_width_ratio 0.9)
			(max_width 2)
			(curved_edges yes)
			(filter_ratio 0.9)
			(enabled yes)
			(allow_two_segments yes)
			(prefer_zone_connections yes)
		)
		(net 1)
	)
	(via
		(at 133.29 138.86)
		(size 0.45)
		(drill 0.1)
		(layers "F.Cu" "B.Cu")
		(remove_unused_layers yes)
		(keep_end_layers yes)
		(zone_layer_connections "In1.Cu" "In4.Cu" "In6.Cu")
		(teardrops
			(best_length_ratio 0.4)
			(max_length 1)
			(best_width_ratio 0.9)
			(max_width 2)
			(curved_edges yes)
			(filter_ratio 0.9)
			(enabled yes)
			(allow_two_segments yes)
			(prefer_zone_connections yes)
		)
		(net 1)
	)
	(via
		(at 99.46 166.6)
		(size 0.45)
		(drill 0.1)
		(layers "F.Cu" "B.Cu")
		(remove_unused_layers yes)
		(keep_end_layers yes)
		(zone_layer_connections "In1.Cu" "In4.Cu" "In6.Cu")
		(teardrops
			(best_length_ratio 0.4)
			(max_length 1)
			(best_width_ratio 0.9)
			(max_width 2)
			(curved_edges yes)
			(filter_ratio 0.9)
			(enabled yes)
			(allow_two_segments yes)
			(prefer_zone_connections yes)
		)
		(net 1)
	)
	(via
		(at 205.6 165)
		(size 0.45)
		(drill 0.1)
		(layers "F.Cu" "B.Cu")
		(teardrops
			(best_length_ratio 0.4)
			(max_length 1)
			(best_width_ratio 0.9)
			(max_width 2)
			(curved_edges yes)
			(filter_ratio 0.9)
			(enabled yes)
			(allow_two_segments yes)
			(prefer_zone_connections yes)
		)
		(net 1)
	)
	(via
		(at 250.95 166.41)
		(size 0.45)
		(drill 0.1)
		(layers "F.Cu" "B.Cu")
		(remove_unused_layers yes)
		(keep_end_layers yes)
		(zone_layer_connections "In1.Cu" "In4.Cu" "In6.Cu")
		(teardrops
			(best_length_ratio 0.4)
			(max_length 1)
			(best_width_ratio 0.9)
			(max_width 2)
			(curved_edges yes)
			(filter_ratio 0.9)
			(enabled yes)
			(allow_two_segments yes)
			(prefer_zone_connections yes)
		)
		(net 1)
	)
	(via
		(at 195.95 95.81)
		(size 0.45)
		(drill 0.1)
		(layers "F.Cu" "B.Cu")
		(remove_unused_layers yes)
		(keep_end_layers yes)
		(zone_layer_connections "In1.Cu" "In4.Cu" "In6.Cu")
		(teardrops
			(best_length_ratio 0.4)
			(max_length 1)
			(best_width_ratio 0.9)
			(max_width 2)
			(curved_edges yes)
			(filter_ratio 0.9)
			(enabled yes)
			(allow_two_segments yes)
			(prefer_zone_connections yes)
		)
		(net 1)
	)
	(via
		(at 300.45 105.31)
		(size 0.45)
		(drill 0.1)
		(layers "F.Cu" "B.Cu")
		(remove_unused_layers yes)
		(keep_end_layers yes)
		(zone_layer_connections "In1.Cu" "In4.Cu" "In6.Cu")
		(teardrops
			(best_length_ratio 0.4)
			(max_length 1)
			(best_width_ratio 0.9)
			(max_width 2)
			(curved_edges yes)
			(filter_ratio 0.9)
			(enabled yes)
			(allow_two_segments yes)
			(prefer_zone_connections yes)
		)
		(net 1)
	)
	(via
		(at 298.950001 170.81)
		(size 0.45)
		(drill 0.1)
		(layers "F.Cu" "B.Cu")
		(remove_unused_layers yes)
		(keep_end_layers yes)
		(zone_layer_connections "In1.Cu" "In4.Cu" "In6.Cu")
		(teardrops
			(best_length_ratio 0.4)
			(max_length 1)
			(best_width_ratio 0.9)
			(max_width 2)
			(curved_edges yes)
			(filter_ratio 0.9)
			(enabled yes)
			(allow_two_segments yes)
			(prefer_zone_connections yes)
		)
		(net 1)
	)
	(via
		(at 201.45 70.31)
		(size 0.45)
		(drill 0.1)
		(layers "F.Cu" "B.Cu")
		(remove_unused_layers yes)
		(keep_end_layers yes)
		(free yes)
		(zone_layer_connections "In1.Cu" "In4.Cu" "In6.Cu")
		(teardrops
			(best_length_ratio 0.4)
			(max_length 1)
			(best_width_ratio 0.9)
			(max_width 2)
			(curved_edges yes)
			(filter_ratio 0.9)
			(enabled yes)
			(allow_two_segments yes)
			(prefer_zone_connections yes)
		)
		(net 1)
	)
	(via
		(at 202.95 93.31)
		(size 0.45)
		(drill 0.1)
		(layers "F.Cu" "B.Cu")
		(remove_unused_layers yes)
		(keep_end_layers yes)
		(zone_layer_connections "In1.Cu" "In4.Cu" "In6.Cu")
		(teardrops
			(best_length_ratio 0.4)
			(max_length 1)
			(best_width_ratio 0.9)
			(max_width 2)
			(curved_edges yes)
			(filter_ratio 0.9)
			(enabled yes)
			(allow_two_segments yes)
			(prefer_zone_connections yes)
		)
		(net 1)
	)
	(via
		(at 98.45 135.81)
		(size 0.45)
		(drill 0.1)
		(layers "F.Cu" "B.Cu")
		(remove_unused_layers yes)
		(keep_end_layers yes)
		(zone_layer_connections "In1.Cu" "In4.Cu" "In6.Cu")
		(teardrops
			(best_length_ratio 0.4)
			(max_length 1)
			(best_width_ratio 0.9)
			(max_width 2)
			(curved_edges yes)
			(filter_ratio 0.9)
			(enabled yes)
			(allow_two_segments yes)
			(prefer_zone_connections yes)
		)
		(net 1)
	)
	(via
		(at 212.95 159.9)
		(size 0.45)
		(drill 0.1)
		(layers "F.Cu" "B.Cu")
		(teardrops
			(best_length_ratio 0.4)
			(max_length 1)
			(best_width_ratio 0.9)
			(max_width 2)
			(curved_edges yes)
			(filter_ratio 0.9)
			(enabled yes)
			(allow_two_segments yes)
			(prefer_zone_connections yes)
		)
		(net 1)
	)
	(via
		(at 297.45 134.81)
		(size 0.45)
		(drill 0.1)
		(layers "F.Cu" "B.Cu")
		(remove_unused_layers yes)
		(keep_end_layers yes)
		(zone_layer_connections "In1.Cu" "In4.Cu" "In6.Cu")
		(teardrops
			(best_length_ratio 0.4)
			(max_length 1)
			(best_width_ratio 0.9)
			(max_width 2)
			(curved_edges yes)
			(filter_ratio 0.9)
			(enabled yes)
			(allow_two_segments yes)
			(prefer_zone_connections yes)
		)
		(net 1)
	)
	(via
		(at 294.95 109.81)
		(size 0.45)
		(drill 0.1)
		(layers "F.Cu" "B.Cu")
		(remove_unused_layers yes)
		(keep_end_layers yes)
		(zone_layer_connections "In1.Cu" "In4.Cu" "In6.Cu")
		(teardrops
			(best_length_ratio 0.4)
			(max_length 1)
			(best_width_ratio 0.9)
			(max_width 2)
			(curved_edges yes)
			(filter_ratio 0.9)
			(enabled yes)
			(allow_two_segments yes)
			(prefer_zone_connections yes)
		)
		(net 1)
	)
	(via
		(at 126.45 81.81)
		(size 0.45)
		(drill 0.1)
		(layers "F.Cu" "B.Cu")
		(remove_unused_layers yes)
		(keep_end_layers yes)
		(zone_layer_connections "In1.Cu" "In4.Cu" "In6.Cu")
		(teardrops
			(best_length_ratio 0.4)
			(max_length 1)
			(best_width_ratio 0.9)
			(max_width 2)
			(curved_edges yes)
			(filter_ratio 0.9)
			(enabled yes)
			(allow_two_segments yes)
			(prefer_zone_connections yes)
		)
		(net 1)
	)
	(via
		(at 280.45 145.81)
		(size 0.45)
		(drill 0.1)
		(layers "F.Cu" "B.Cu")
		(remove_unused_layers yes)
		(keep_end_layers yes)
		(zone_layer_connections "In1.Cu" "In4.Cu" "In6.Cu")
		(teardrops
			(best_length_ratio 0.4)
			(max_length 1)
			(best_width_ratio 0.9)
			(max_width 2)
			(curved_edges yes)
			(filter_ratio 0.9)
			(enabled yes)
			(allow_two_segments yes)
			(prefer_zone_connections yes)
		)
		(net 1)
	)
	(via
		(at 315.4645 116.4465)
		(size 0.45)
		(drill 0.1)
		(layers "F.Cu" "B.Cu")
		(remove_unused_layers yes)
		(keep_end_layers yes)
		(free yes)
		(zone_layer_connections "In1.Cu" "In4.Cu" "In6.Cu")
		(teardrops
			(best_length_ratio 0.4)
			(max_length 1)
			(best_width_ratio 0.9)
			(max_width 2)
			(curved_edges yes)
			(filter_ratio 0.9)
			(enabled yes)
			(allow_two_segments yes)
			(prefer_zone_connections yes)
		)
		(net 1)
	)
	(via
		(at 150.175 72.485)
		(size 0.45)
		(drill 0.1)
		(layers "F.Cu" "B.Cu")
		(remove_unused_layers yes)
		(keep_end_layers yes)
		(free yes)
		(zone_layer_connections "In1.Cu" "In4.Cu" "In6.Cu")
		(teardrops
			(best_length_ratio 0.4)
			(max_length 1)
			(best_width_ratio 0.9)
			(max_width 2)
			(curved_edges yes)
			(filter_ratio 0.9)
			(enabled yes)
			(allow_two_segments yes)
			(prefer_zone_connections yes)
		)
		(net 1)
	)
	(via
		(at 173.2 160.8)
		(size 0.45)
		(drill 0.1)
		(layers "F.Cu" "B.Cu")
		(teardrops
			(best_length_ratio 0.4)
			(max_length 1)
			(best_width_ratio 0.9)
			(max_width 2)
			(curved_edges yes)
			(filter_ratio 0.9)
			(enabled yes)
			(allow_two_segments yes)
			(prefer_zone_connections yes)
		)
		(net 1)
	)
	(via
		(at 289.45 134.81)
		(size 0.45)
		(drill 0.1)
		(layers "F.Cu" "B.Cu")
		(remove_unused_layers yes)
		(keep_end_layers yes)
		(zone_layer_connections "In1.Cu" "In4.Cu" "In6.Cu")
		(teardrops
			(best_length_ratio 0.4)
			(max_length 1)
			(best_width_ratio 0.9)
			(max_width 2)
			(curved_edges yes)
			(filter_ratio 0.9)
			(enabled yes)
			(allow_two_segments yes)
			(prefer_zone_connections yes)
		)
		(net 1)
	)
	(via
		(at 96.45 129.81)
		(size 0.45)
		(drill 0.1)
		(layers "F.Cu" "B.Cu")
		(remove_unused_layers yes)
		(keep_end_layers yes)
		(zone_layer_connections "In1.Cu" "In4.Cu" "In6.Cu")
		(teardrops
			(best_length_ratio 0.4)
			(max_length 1)
			(best_width_ratio 0.9)
			(max_width 2)
			(curved_edges yes)
			(filter_ratio 0.9)
			(enabled yes)
			(allow_two_segments yes)
			(prefer_zone_connections yes)
		)
		(net 1)
	)
	(via
		(at 317.7 168.11)
		(size 0.45)
		(drill 0.1)
		(layers "F.Cu" "B.Cu")
		(remove_unused_layers yes)
		(keep_end_layers yes)
		(zone_layer_connections "In1.Cu" "In4.Cu" "In6.Cu")
		(teardrops
			(best_length_ratio 0.4)
			(max_length 1)
			(best_width_ratio 0.9)
			(max_width 2)
			(curved_edges yes)
			(filter_ratio 0.9)
			(enabled yes)
			(allow_two_segments yes)
			(prefer_zone_connections yes)
		)
		(net 1)
	)
	(via
		(at 105.45 170.81)
		(size 0.45)
		(drill 0.1)
		(layers "F.Cu" "B.Cu")
		(remove_unused_layers yes)
		(keep_end_layers yes)
		(zone_layer_connections "In1.Cu" "In4.Cu" "In6.Cu")
		(teardrops
			(best_length_ratio 0.4)
			(max_length 1)
			(best_width_ratio 0.9)
			(max_width 2)
			(curved_edges yes)
			(filter_ratio 0.9)
			(enabled yes)
			(allow_two_segments yes)
			(prefer_zone_connections yes)
		)
		(net 1)
	)
	(via
		(at 282.45 113.81)
		(size 0.45)
		(drill 0.1)
		(layers "F.Cu" "B.Cu")
		(remove_unused_layers yes)
		(keep_end_layers yes)
		(zone_layer_connections "In1.Cu" "In4.Cu" "In6.Cu")
		(teardrops
			(best_length_ratio 0.4)
			(max_length 1)
			(best_width_ratio 0.9)
			(max_width 2)
			(curved_edges yes)
			(filter_ratio 0.9)
			(enabled yes)
			(allow_two_segments yes)
			(prefer_zone_connections yes)
		)
		(net 1)
	)
	(via
		(at 200.45 100.31)
		(size 0.45)
		(drill 0.1)
		(layers "F.Cu" "B.Cu")
		(remove_unused_layers yes)
		(keep_end_layers yes)
		(zone_layer_connections "In1.Cu" "In4.Cu" "In6.Cu")
		(teardrops
			(best_length_ratio 0.4)
			(max_length 1)
			(best_width_ratio 0.9)
			(max_width 2)
			(curved_edges yes)
			(filter_ratio 0.9)
			(enabled yes)
			(allow_two_segments yes)
			(prefer_zone_connections yes)
		)
		(net 1)
	)
	(via
		(at 229.95 86.31)
		(size 0.45)
		(drill 0.1)
		(layers "F.Cu" "B.Cu")
		(remove_unused_layers yes)
		(keep_end_layers yes)
		(zone_layer_connections "In1.Cu" "In4.Cu" "In6.Cu")
		(teardrops
			(best_length_ratio 0.4)
			(max_length 1)
			(best_width_ratio 0.9)
			(max_width 2)
			(curved_edges yes)
			(filter_ratio 0.9)
			(enabled yes)
			(allow_two_segments yes)
			(prefer_zone_connections yes)
		)
		(net 1)
	)
	(via
		(at 314.4645 117.4465)
		(size 0.45)
		(drill 0.1)
		(layers "F.Cu" "B.Cu")
		(remove_unused_layers yes)
		(keep_end_layers yes)
		(free yes)
		(zone_layer_connections "In1.Cu" "In4.Cu" "In6.Cu")
		(teardrops
			(best_length_ratio 0.4)
			(max_length 1)
			(best_width_ratio 0.9)
			(max_width 2)
			(curved_edges yes)
			(filter_ratio 0.9)
			(enabled yes)
			(allow_two_segments yes)
			(prefer_zone_connections yes)
		)
		(net 1)
	)
	(via
		(at 317.4895 135.71)
		(size 0.45)
		(drill 0.1)
		(layers "F.Cu" "B.Cu")
		(remove_unused_layers yes)
		(keep_end_layers yes)
		(zone_layer_connections "In1.Cu" "In4.Cu" "In6.Cu")
		(teardrops
			(best_length_ratio 0.4)
			(max_length 1)
			(best_width_ratio 0.9)
			(max_width 2)
			(curved_edges yes)
			(filter_ratio 0.9)
			(enabled yes)
			(allow_two_segments yes)
			(prefer_zone_connections yes)
		)
		(net 1)
	)
	(via
		(at 155.45 73.31)
		(size 0.45)
		(drill 0.1)
		(layers "F.Cu" "B.Cu")
		(remove_unused_layers yes)
		(keep_end_layers yes)
		(zone_layer_connections "In1.Cu" "In4.Cu" "In6.Cu")
		(teardrops
			(best_length_ratio 0.4)
			(max_length 1)
			(best_width_ratio 0.9)
			(max_width 2)
			(curved_edges yes)
			(filter_ratio 0.9)
			(enabled yes)
			(allow_two_segments yes)
			(prefer_zone_connections yes)
		)
		(net 1)
	)
	(via
		(at 142.45 86.31)
		(size 0.45)
		(drill 0.1)
		(layers "F.Cu" "B.Cu")
		(remove_unused_layers yes)
		(keep_end_layers yes)
		(zone_layer_connections "In1.Cu" "In4.Cu" "In6.Cu")
		(teardrops
			(best_length_ratio 0.4)
			(max_length 1)
			(best_width_ratio 0.9)
			(max_width 2)
			(curved_edges yes)
			(filter_ratio 0.9)
			(enabled yes)
			(allow_two_segments yes)
			(prefer_zone_connections yes)
		)
		(net 1)
	)
	(via
		(at 317.45 75.31)
		(size 0.45)
		(drill 0.1)
		(layers "F.Cu" "B.Cu")
		(remove_unused_layers yes)
		(keep_end_layers yes)
		(zone_layer_connections "In1.Cu" "In4.Cu" "In6.Cu")
		(teardrops
			(best_length_ratio 0.4)
			(max_length 1)
			(best_width_ratio 0.9)
			(max_width 2)
			(curved_edges yes)
			(filter_ratio 0.9)
			(enabled yes)
			(allow_two_segments yes)
			(prefer_zone_connections yes)
		)
		(net 1)
	)
	(via
		(at 284.95 141.31)
		(size 0.45)
		(drill 0.1)
		(layers "F.Cu" "B.Cu")
		(remove_unused_layers yes)
		(keep_end_layers yes)
		(zone_layer_connections "In1.Cu" "In4.Cu" "In6.Cu")
		(teardrops
			(best_length_ratio 0.4)
			(max_length 1)
			(best_width_ratio 0.9)
			(max_width 2)
			(curved_edges yes)
			(filter_ratio 0.9)
			(enabled yes)
			(allow_two_segments yes)
			(prefer_zone_connections yes)
		)
		(net 1)
	)
	(via
		(at 151.45 140.86)
		(size 0.45)
		(drill 0.1)
		(layers "F.Cu" "B.Cu")
		(remove_unused_layers yes)
		(keep_end_layers yes)
		(zone_layer_connections "In1.Cu" "In4.Cu" "In6.Cu")
		(teardrops
			(best_length_ratio 0.4)
			(max_length 1)
			(best_width_ratio 0.9)
			(max_width 2)
			(curved_edges yes)
			(filter_ratio 0.9)
			(enabled yes)
			(allow_two_segments yes)
			(prefer_zone_connections yes)
		)
		(net 1)
	)
	(via
		(at 189.3 157.9)
		(size 0.45)
		(drill 0.1)
		(layers "F.Cu" "B.Cu")
		(teardrops
			(best_length_ratio 0.4)
			(max_length 1)
			(best_width_ratio 0.9)
			(max_width 2)
			(curved_edges yes)
			(filter_ratio 0.9)
			(enabled yes)
			(allow_two_segments yes)
			(prefer_zone_connections yes)
		)
		(net 1)
	)
	(via
		(at 121.45 170.81)
		(size 0.45)
		(drill 0.1)
		(layers "F.Cu" "B.Cu")
		(remove_unused_layers yes)
		(keep_end_layers yes)
		(zone_layer_connections "In1.Cu" "In4.Cu" "In6.Cu")
		(teardrops
			(best_length_ratio 0.4)
			(max_length 1)
			(best_width_ratio 0.9)
			(max_width 2)
			(curved_edges yes)
			(filter_ratio 0.9)
			(enabled yes)
			(allow_two_segments yes)
			(prefer_zone_connections yes)
		)
		(net 1)
	)
	(via
		(at 104.45 127.81)
		(size 0.45)
		(drill 0.1)
		(layers "F.Cu" "B.Cu")
		(remove_unused_layers yes)
		(keep_end_layers yes)
		(zone_layer_connections "In1.Cu" "In4.Cu" "In6.Cu")
		(teardrops
			(best_length_ratio 0.4)
			(max_length 1)
			(best_width_ratio 0.9)
			(max_width 2)
			(curved_edges yes)
			(filter_ratio 0.9)
			(enabled yes)
			(allow_two_segments yes)
			(prefer_zone_connections yes)
		)
		(net 1)
	)
	(via
		(at 203.95 161.7)
		(size 0.45)
		(drill 0.1)
		(layers "F.Cu" "B.Cu")
		(teardrops
			(best_length_ratio 0.4)
			(max_length 1)
			(best_width_ratio 0.9)
			(max_width 2)
			(curved_edges yes)
			(filter_ratio 0.9)
			(enabled yes)
			(allow_two_segments yes)
			(prefer_zone_connections yes)
		)
		(net 1)
	)
	(via
		(at 108.95 85.81)
		(size 0.45)
		(drill 0.1)
		(layers "F.Cu" "B.Cu")
		(remove_unused_layers yes)
		(keep_end_layers yes)
		(zone_layer_connections "In1.Cu" "In4.Cu" "In6.Cu")
		(teardrops
			(best_length_ratio 0.4)
			(max_length 1)
			(best_width_ratio 0.9)
			(max_width 2)
			(curved_edges yes)
			(filter_ratio 0.9)
			(enabled yes)
			(allow_two_segments yes)
			(prefer_zone_connections yes)
		)
		(net 1)
	)
	(via
		(at 151.45 92.31)
		(size 0.45)
		(drill 0.1)
		(layers "F.Cu" "B.Cu")
		(remove_unused_layers yes)
		(keep_end_layers yes)
		(zone_layer_connections "In1.Cu" "In4.Cu" "In6.Cu")
		(teardrops
			(best_length_ratio 0.4)
			(max_length 1)
			(best_width_ratio 0.9)
			(max_width 2)
			(curved_edges yes)
			(filter_ratio 0.9)
			(enabled yes)
			(allow_two_segments yes)
			(prefer_zone_connections yes)
		)
		(net 1)
	)
	(via
		(at 151.45 135.86)
		(size 0.45)
		(drill 0.1)
		(layers "F.Cu" "B.Cu")
		(remove_unused_layers yes)
		(keep_end_layers yes)
		(zone_layer_connections "In1.Cu" "In4.Cu" "In6.Cu")
		(teardrops
			(best_length_ratio 0.4)
			(max_length 1)
			(best_width_ratio 0.9)
			(max_width 2)
			(curved_edges yes)
			(filter_ratio 0.9)
			(enabled yes)
			(allow_two_segments yes)
			(prefer_zone_connections yes)
		)
		(net 1)
	)
	(via
		(at 215.925 137.43)
		(size 0.45)
		(drill 0.1)
		(layers "F.Cu" "B.Cu")
		(remove_unused_layers yes)
		(keep_end_layers yes)
		(zone_layer_connections "In1.Cu" "In4.Cu" "In6.Cu")
		(teardrops
			(best_length_ratio 0.4)
			(max_length 1)
			(best_width_ratio 0.9)
			(max_width 2)
			(curved_edges yes)
			(filter_ratio 0.9)
			(enabled yes)
			(allow_two_segments yes)
			(prefer_zone_connections yes)
		)
		(net 1)
	)
	(via
		(at 293.45 127.31)
		(size 0.45)
		(drill 0.1)
		(layers "F.Cu" "B.Cu")
		(remove_unused_layers yes)
		(keep_end_layers yes)
		(zone_layer_connections "In1.Cu" "In4.Cu" "In6.Cu")
		(teardrops
			(best_length_ratio 0.4)
			(max_length 1)
			(best_width_ratio 0.9)
			(max_width 2)
			(curved_edges yes)
			(filter_ratio 0.9)
			(enabled yes)
			(allow_two_segments yes)
			(prefer_zone_connections yes)
		)
		(net 1)
	)
	(via
		(at 267.45 166.41)
		(size 0.45)
		(drill 0.1)
		(layers "F.Cu" "B.Cu")
		(remove_unused_layers yes)
		(keep_end_layers yes)
		(zone_layer_connections "In1.Cu" "In4.Cu" "In6.Cu")
		(teardrops
			(best_length_ratio 0.4)
			(max_length 1)
			(best_width_ratio 0.9)
			(max_width 2)
			(curved_edges yes)
			(filter_ratio 0.9)
			(enabled yes)
			(allow_two_segments yes)
			(prefer_zone_connections yes)
		)
		(net 1)
	)
	(via
		(at 193.442657 136.85656)
		(size 0.45)
		(drill 0.1)
		(layers "F.Cu" "B.Cu")
		(remove_unused_layers yes)
		(keep_end_layers yes)
		(zone_layer_connections "In1.Cu" "In4.Cu" "In6.Cu")
		(teardrops
			(best_length_ratio 0.4)
			(max_length 1)
			(best_width_ratio 0.9)
			(max_width 2)
			(curved_edges yes)
			(filter_ratio 0.9)
			(enabled yes)
			(allow_two_segments yes)
			(prefer_zone_connections yes)
		)
		(net 1)
	)
	(via
		(at 120.35 163.21)
		(size 0.45)
		(drill 0.1)
		(layers "F.Cu" "B.Cu")
		(remove_unused_layers yes)
		(keep_end_layers yes)
		(zone_layer_connections "In1.Cu" "In4.Cu" "In6.Cu")
		(teardrops
			(best_length_ratio 0.4)
			(max_length 1)
			(best_width_ratio 0.9)
			(max_width 2)
			(curved_edges yes)
			(filter_ratio 0.9)
			(enabled yes)
			(allow_two_segments yes)
			(prefer_zone_connections yes)
		)
		(net 1)
	)
	(via
		(at 126.3 71.51)
		(size 0.45)
		(drill 0.1)
		(layers "F.Cu" "B.Cu")
		(remove_unused_layers yes)
		(keep_end_layers yes)
		(free yes)
		(zone_layer_connections "In1.Cu" "In4.Cu" "In6.Cu")
		(teardrops
			(best_length_ratio 0.4)
			(max_length 1)
			(best_width_ratio 0.9)
			(max_width 2)
			(curved_edges yes)
			(filter_ratio 0.9)
			(enabled yes)
			(allow_two_segments yes)
			(prefer_zone_connections yes)
		)
		(net 1)
	)
	(via
		(at 154.45 131.86)
		(size 0.45)
		(drill 0.1)
		(layers "F.Cu" "B.Cu")
		(remove_unused_layers yes)
		(keep_end_layers yes)
		(zone_layer_connections "In1.Cu" "In4.Cu" "In6.Cu")
		(teardrops
			(best_length_ratio 0.4)
			(max_length 1)
			(best_width_ratio 0.9)
			(max_width 2)
			(curved_edges yes)
			(filter_ratio 0.9)
			(enabled yes)
			(allow_two_segments yes)
			(prefer_zone_connections yes)
		)
		(net 1)
	)
	(via
		(at 243.95 166.31)
		(size 0.45)
		(drill 0.1)
		(layers "F.Cu" "B.Cu")
		(remove_unused_layers yes)
		(keep_end_layers yes)
		(zone_layer_connections "In1.Cu" "In4.Cu" "In6.Cu")
		(teardrops
			(best_length_ratio 0.4)
			(max_length 1)
			(best_width_ratio 0.9)
			(max_width 2)
			(curved_edges yes)
			(filter_ratio 0.9)
			(enabled yes)
			(allow_two_segments yes)
			(prefer_zone_connections yes)
		)
		(net 1)
	)
	(via
		(at 283.45 133.81)
		(size 0.45)
		(drill 0.1)
		(layers "F.Cu" "B.Cu")
		(remove_unused_layers yes)
		(keep_end_layers yes)
		(zone_layer_connections "In1.Cu" "In4.Cu" "In6.Cu")
		(teardrops
			(best_length_ratio 0.4)
			(max_length 1)
			(best_width_ratio 0.9)
			(max_width 2)
			(curved_edges yes)
			(filter_ratio 0.9)
			(enabled yes)
			(allow_two_segments yes)
			(prefer_zone_connections yes)
		)
		(net 1)
	)
	(via
		(at 152.84 160.37)
		(size 0.45)
		(drill 0.1)
		(layers "F.Cu" "B.Cu")
		(remove_unused_layers yes)
		(keep_end_layers yes)
		(zone_layer_connections "In1.Cu" "In4.Cu" "In6.Cu")
		(teardrops
			(best_length_ratio 0.4)
			(max_length 1)
			(best_width_ratio 0.9)
			(max_width 2)
			(curved_edges yes)
			(filter_ratio 0.9)
			(enabled yes)
			(allow_two_segments yes)
			(prefer_zone_connections yes)
		)
		(net 1)
	)
	(via
		(at 113.449999 170.81)
		(size 0.45)
		(drill 0.1)
		(layers "F.Cu" "B.Cu")
		(remove_unused_layers yes)
		(keep_end_layers yes)
		(zone_layer_connections "In1.Cu" "In4.Cu" "In6.Cu")
		(teardrops
			(best_length_ratio 0.4)
			(max_length 1)
			(best_width_ratio 0.9)
			(max_width 2)
			(curved_edges yes)
			(filter_ratio 0.9)
			(enabled yes)
			(allow_two_segments yes)
			(prefer_zone_connections yes)
		)
		(net 1)
	)
	(via
		(at 285.45 122.81)
		(size 0.45)
		(drill 0.1)
		(layers "F.Cu" "B.Cu")
		(remove_unused_layers yes)
		(keep_end_layers yes)
		(zone_layer_connections "In1.Cu" "In4.Cu" "In6.Cu")
		(teardrops
			(best_length_ratio 0.4)
			(max_length 1)
			(best_width_ratio 0.9)
			(max_width 2)
			(curved_edges yes)
			(filter_ratio 0.9)
			(enabled yes)
			(allow_two_segments yes)
			(prefer_zone_connections yes)
		)
		(net 1)
	)
	(via
		(at 133.29 135.86)
		(size 0.45)
		(drill 0.1)
		(layers "F.Cu" "B.Cu")
		(remove_unused_layers yes)
		(keep_end_layers yes)
		(zone_layer_connections "In1.Cu" "In4.Cu" "In6.Cu")
		(teardrops
			(best_length_ratio 0.4)
			(max_length 1)
			(best_width_ratio 0.9)
			(max_width 2)
			(curved_edges yes)
			(filter_ratio 0.9)
			(enabled yes)
			(allow_two_segments yes)
			(prefer_zone_connections yes)
		)
		(net 1)
	)
	(via
		(at 150.450002 137.86)
		(size 0.45)
		(drill 0.1)
		(layers "F.Cu" "B.Cu")
		(remove_unused_layers yes)
		(keep_end_layers yes)
		(zone_layer_connections "In1.Cu" "In4.Cu" "In6.Cu")
		(teardrops
			(best_length_ratio 0.4)
			(max_length 1)
			(best_width_ratio 0.9)
			(max_width 2)
			(curved_edges yes)
			(filter_ratio 0.9)
			(enabled yes)
			(allow_two_segments yes)
			(prefer_zone_connections yes)
		)
		(net 1)
	)
	(via
		(at 179.5 157.9)
		(size 0.45)
		(drill 0.1)
		(layers "F.Cu" "B.Cu")
		(teardrops
			(best_length_ratio 0.4)
			(max_length 1)
			(best_width_ratio 0.9)
			(max_width 2)
			(curved_edges yes)
			(filter_ratio 0.9)
			(enabled yes)
			(allow_two_segments yes)
			(prefer_zone_connections yes)
		)
		(net 1)
	)
	(via
		(at 114.45 169.81)
		(size 0.45)
		(drill 0.1)
		(layers "F.Cu" "B.Cu")
		(remove_unused_layers yes)
		(keep_end_layers yes)
		(zone_layer_connections "In1.Cu" "In4.Cu" "In6.Cu")
		(teardrops
			(best_length_ratio 0.4)
			(max_length 1)
			(best_width_ratio 0.9)
			(max_width 2)
			(curved_edges yes)
			(filter_ratio 0.9)
			(enabled yes)
			(allow_two_segments yes)
			(prefer_zone_connections yes)
		)
		(net 1)
	)
	(via
		(at 220.38093 126.756635)
		(size 0.45)
		(drill 0.1)
		(layers "F.Cu" "B.Cu")
		(remove_unused_layers yes)
		(keep_end_layers yes)
		(free yes)
		(zone_layer_connections "In1.Cu" "In4.Cu" "In6.Cu")
		(teardrops
			(best_length_ratio 0.4)
			(max_length 1)
			(best_width_ratio 0.9)
			(max_width 2)
			(curved_edges yes)
			(filter_ratio 0.9)
			(enabled yes)
			(allow_two_segments yes)
			(prefer_zone_connections yes)
		)
		(net 1)
	)
	(via
		(at 310.175 82.32)
		(size 0.45)
		(drill 0.1)
		(layers "F.Cu" "B.Cu")
		(remove_unused_layers yes)
		(keep_end_layers yes)
		(zone_layer_connections "In1.Cu" "In4.Cu" "In6.Cu")
		(teardrops
			(best_length_ratio 0.4)
			(max_length 1)
			(best_width_ratio 0.9)
			(max_width 2)
			(curved_edges yes)
			(filter_ratio 0.9)
			(enabled yes)
			(allow_two_segments yes)
			(prefer_zone_connections yes)
		)
		(net 1)
	)
	(via
		(at 113.45 168.81)
		(size 0.45)
		(drill 0.1)
		(layers "F.Cu" "B.Cu")
		(remove_unused_layers yes)
		(keep_end_layers yes)
		(zone_layer_connections "In1.Cu" "In4.Cu" "In6.Cu")
		(teardrops
			(best_length_ratio 0.4)
			(max_length 1)
			(best_width_ratio 0.9)
			(max_width 2)
			(curved_edges yes)
			(filter_ratio 0.9)
			(enabled yes)
			(allow_two_segments yes)
			(prefer_zone_connections yes)
		)
		(net 1)
	)
	(via
		(at 289.45 125.81)
		(size 0.45)
		(drill 0.1)
		(layers "F.Cu" "B.Cu")
		(remove_unused_layers yes)
		(keep_end_layers yes)
		(zone_layer_connections "In1.Cu" "In4.Cu" "In6.Cu")
		(teardrops
			(best_length_ratio 0.4)
			(max_length 1)
			(best_width_ratio 0.9)
			(max_width 2)
			(curved_edges yes)
			(filter_ratio 0.9)
			(enabled yes)
			(allow_two_segments yes)
			(prefer_zone_connections yes)
		)
		(net 1)
	)
	(via
		(at 198.1 159.8)
		(size 0.45)
		(drill 0.1)
		(layers "F.Cu" "B.Cu")
		(teardrops
			(best_length_ratio 0.4)
			(max_length 1)
			(best_width_ratio 0.9)
			(max_width 2)
			(curved_edges yes)
			(filter_ratio 0.9)
			(enabled yes)
			(allow_two_segments yes)
			(prefer_zone_connections yes)
		)
		(net 1)
	)
	(via
		(at 233.4 152.4)
		(size 0.45)
		(drill 0.1)
		(layers "F.Cu" "B.Cu")
		(teardrops
			(best_length_ratio 0.4)
			(max_length 1)
			(best_width_ratio 0.9)
			(max_width 2)
			(curved_edges yes)
			(filter_ratio 0.9)
			(enabled yes)
			(allow_two_segments yes)
			(prefer_zone_connections yes)
		)
		(net 1)
	)
	(via
		(at 184.70861 72.802163)
		(size 0.45)
		(drill 0.1)
		(layers "F.Cu" "B.Cu")
		(remove_unused_layers yes)
		(keep_end_layers yes)
		(zone_layer_connections "In1.Cu" "In4.Cu" "In6.Cu")
		(teardrops
			(best_length_ratio 0.4)
			(max_length 1)
			(best_width_ratio 0.9)
			(max_width 2)
			(curved_edges yes)
			(filter_ratio 0.9)
			(enabled yes)
			(allow_two_segments yes)
			(prefer_zone_connections yes)
		)
		(net 1)
	)
	(via
		(at 242.6 159)
		(size 0.45)
		(drill 0.1)
		(layers "F.Cu" "B.Cu")
		(teardrops
			(best_length_ratio 0.4)
			(max_length 1)
			(best_width_ratio 0.9)
			(max_width 2)
			(curved_edges yes)
			(filter_ratio 0.9)
			(enabled yes)
			(allow_two_segments yes)
			(prefer_zone_connections yes)
		)
		(net 1)
	)
	(via
		(at 95.45 155.31)
		(size 0.45)
		(drill 0.1)
		(layers "F.Cu" "B.Cu")
		(remove_unused_layers yes)
		(keep_end_layers yes)
		(zone_layer_connections "In1.Cu" "In4.Cu" "In6.Cu")
		(teardrops
			(best_length_ratio 0.4)
			(max_length 1)
			(best_width_ratio 0.9)
			(max_width 2)
			(curved_edges yes)
			(filter_ratio 0.9)
			(enabled yes)
			(allow_two_segments yes)
			(prefer_zone_connections yes)
		)
		(net 1)
	)
	(via
		(at 130.95 157.81)
		(size 0.45)
		(drill 0.1)
		(layers "F.Cu" "B.Cu")
		(remove_unused_layers yes)
		(keep_end_layers yes)
		(zone_layer_connections "In1.Cu" "In4.Cu" "In6.Cu")
		(teardrops
			(best_length_ratio 0.4)
			(max_length 1)
			(best_width_ratio 0.9)
			(max_width 2)
			(curved_edges yes)
			(filter_ratio 0.9)
			(enabled yes)
			(allow_two_segments yes)
			(prefer_zone_connections yes)
		)
		(net 1)
	)
	(via
		(at 99.450001 170.81)
		(size 0.45)
		(drill 0.1)
		(layers "F.Cu" "B.Cu")
		(remove_unused_layers yes)
		(keep_end_layers yes)
		(zone_layer_connections "In1.Cu" "In4.Cu" "In6.Cu")
		(teardrops
			(best_length_ratio 0.4)
			(max_length 1)
			(best_width_ratio 0.9)
			(max_width 2)
			(curved_edges yes)
			(filter_ratio 0.9)
			(enabled yes)
			(allow_two_segments yes)
			(prefer_zone_connections yes)
		)
		(net 1)
	)
	(via
		(at 225.55 169.75)
		(size 0.45)
		(drill 0.1)
		(layers "F.Cu" "B.Cu")
		(teardrops
			(best_length_ratio 0.4)
			(max_length 1)
			(best_width_ratio 0.9)
			(max_width 2)
			(curved_edges yes)
			(filter_ratio 0.9)
			(enabled yes)
			(allow_two_segments yes)
			(prefer_zone_connections yes)
		)
		(net 1)
	)
	(via
		(at 281.95 144.31)
		(size 0.45)
		(drill 0.1)
		(layers "F.Cu" "B.Cu")
		(remove_unused_layers yes)
		(keep_end_layers yes)
		(zone_layer_connections "In1.Cu" "In4.Cu" "In6.Cu")
		(teardrops
			(best_length_ratio 0.4)
			(max_length 1)
			(best_width_ratio 0.9)
			(max_width 2)
			(curved_edges yes)
			(filter_ratio 0.9)
			(enabled yes)
			(allow_two_segments yes)
			(prefer_zone_connections yes)
		)
		(net 1)
	)
	(via
		(at 317.45 90.81)
		(size 0.45)
		(drill 0.1)
		(layers "F.Cu" "B.Cu")
		(remove_unused_layers yes)
		(keep_end_layers yes)
		(zone_layer_connections "In1.Cu" "In4.Cu" "In6.Cu")
		(teardrops
			(best_length_ratio 0.4)
			(max_length 1)
			(best_width_ratio 0.9)
			(max_width 2)
			(curved_edges yes)
			(filter_ratio 0.9)
			(enabled yes)
			(allow_two_segments yes)
			(prefer_zone_connections yes)
		)
		(net 1)
	)
	(via
		(at 129.5 111.67)
		(size 0.45)
		(drill 0.1)
		(layers "F.Cu" "B.Cu")
		(remove_unused_layers yes)
		(keep_end_layers yes)
		(zone_layer_connections "In1.Cu" "In4.Cu" "In6.Cu")
		(teardrops
			(best_length_ratio 0.4)
			(max_length 1)
			(best_width_ratio 0.9)
			(max_width 2)
			(curved_edges yes)
			(filter_ratio 0.9)
			(enabled yes)
			(allow_two_segments yes)
			(prefer_zone_connections yes)
		)
		(net 1)
	)
	(via
		(at 245.000709 77.655)
		(size 0.45)
		(drill 0.1)
		(layers "F.Cu" "B.Cu")
		(remove_unused_layers yes)
		(keep_end_layers yes)
		(zone_layer_connections "In1.Cu" "In4.Cu" "In6.Cu")
		(teardrops
			(best_length_ratio 0.4)
			(max_length 1)
			(best_width_ratio 0.9)
			(max_width 2)
			(curved_edges yes)
			(filter_ratio 0.9)
			(enabled yes)
			(allow_two_segments yes)
			(prefer_zone_connections yes)
		)
		(net 1)
	)
	(via
		(at 252.135 82.174999)
		(size 0.45)
		(drill 0.1)
		(layers "F.Cu" "B.Cu")
		(remove_unused_layers yes)
		(keep_end_layers yes)
		(zone_layer_connections "In1.Cu" "In4.Cu" "In6.Cu")
		(teardrops
			(best_length_ratio 0.4)
			(max_length 1)
			(best_width_ratio 0.9)
			(max_width 2)
			(curved_edges yes)
			(filter_ratio 0.9)
			(enabled yes)
			(allow_two_segments yes)
			(prefer_zone_connections yes)
		)
		(net 1)
	)
	(via
		(at 127.45 91.81)
		(size 0.45)
		(drill 0.1)
		(layers "F.Cu" "B.Cu")
		(remove_unused_layers yes)
		(keep_end_layers yes)
		(zone_layer_connections "In1.Cu" "In4.Cu" "In6.Cu")
		(teardrops
			(best_length_ratio 0.4)
			(max_length 1)
			(best_width_ratio 0.9)
			(max_width 2)
			(curved_edges yes)
			(filter_ratio 0.9)
			(enabled yes)
			(allow_two_segments yes)
			(prefer_zone_connections yes)
		)
		(net 1)
	)
	(via
		(at 317.7 156.91)
		(size 0.45)
		(drill 0.1)
		(layers "F.Cu" "B.Cu")
		(remove_unused_layers yes)
		(keep_end_layers yes)
		(zone_layer_connections "In1.Cu" "In4.Cu" "In6.Cu")
		(teardrops
			(best_length_ratio 0.4)
			(max_length 1)
			(best_width_ratio 0.9)
			(max_width 2)
			(curved_edges yes)
			(filter_ratio 0.9)
			(enabled yes)
			(allow_two_segments yes)
			(prefer_zone_connections yes)
		)
		(net 1)
	)
	(via
		(at 242.95 170.81)
		(size 0.45)
		(drill 0.1)
		(layers "F.Cu" "B.Cu")
		(remove_unused_layers yes)
		(keep_end_layers yes)
		(zone_layer_connections "In1.Cu" "In4.Cu" "In6.Cu")
		(teardrops
			(best_length_ratio 0.4)
			(max_length 1)
			(best_width_ratio 0.9)
			(max_width 2)
			(curved_edges yes)
			(filter_ratio 0.9)
			(enabled yes)
			(allow_two_segments yes)
			(prefer_zone_connections yes)
		)
		(net 1)
	)
	(via
		(at 161.95 86.81)
		(size 0.45)
		(drill 0.1)
		(layers "F.Cu" "B.Cu")
		(remove_unused_layers yes)
		(keep_end_layers yes)
		(zone_layer_connections "In1.Cu" "In4.Cu" "In6.Cu")
		(teardrops
			(best_length_ratio 0.4)
			(max_length 1)
			(best_width_ratio 0.9)
			(max_width 2)
			(curved_edges yes)
			(filter_ratio 0.9)
			(enabled yes)
			(allow_two_segments yes)
			(prefer_zone_connections yes)
		)
		(net 1)
	)
	(via
		(at 187.3 126.6)
		(size 0.45)
		(drill 0.1)
		(layers "F.Cu" "B.Cu")
		(remove_unused_layers yes)
		(keep_end_layers yes)
		(zone_layer_connections "In1.Cu" "In4.Cu" "In6.Cu")
		(teardrops
			(best_length_ratio 0.4)
			(max_length 1)
			(best_width_ratio 0.9)
			(max_width 2)
			(curved_edges yes)
			(filter_ratio 0.9)
			(enabled yes)
			(allow_two_segments yes)
			(prefer_zone_connections yes)
		)
		(net 1)
	)
	(via
		(at 98.45 127.81)
		(size 0.45)
		(drill 0.1)
		(layers "F.Cu" "B.Cu")
		(remove_unused_layers yes)
		(keep_end_layers yes)
		(zone_layer_connections "In1.Cu" "In4.Cu" "In6.Cu")
		(teardrops
			(best_length_ratio 0.4)
			(max_length 1)
			(best_width_ratio 0.9)
			(max_width 2)
			(curved_edges yes)
			(filter_ratio 0.9)
			(enabled yes)
			(allow_two_segments yes)
			(prefer_zone_connections yes)
		)
		(net 1)
	)
	(via
		(at 209.95 135.31)
		(size 0.45)
		(drill 0.1)
		(layers "F.Cu" "B.Cu")
		(remove_unused_layers yes)
		(keep_end_layers yes)
		(zone_layer_connections "In1.Cu" "In4.Cu" "In6.Cu")
		(teardrops
			(best_length_ratio 0.4)
			(max_length 1)
			(best_width_ratio 0.9)
			(max_width 2)
			(curved_edges yes)
			(filter_ratio 0.9)
			(enabled yes)
			(allow_two_segments yes)
			(prefer_zone_connections yes)
		)
		(net 1)
	)
	(via
		(at 270.45 166.41)
		(size 0.45)
		(drill 0.1)
		(layers "F.Cu" "B.Cu")
		(remove_unused_layers yes)
		(keep_end_layers yes)
		(zone_layer_connections "In1.Cu" "In4.Cu" "In6.Cu")
		(teardrops
			(best_length_ratio 0.4)
			(max_length 1)
			(best_width_ratio 0.9)
			(max_width 2)
			(curved_edges yes)
			(filter_ratio 0.9)
			(enabled yes)
			(allow_two_segments yes)
			(prefer_zone_connections yes)
		)
		(net 1)
	)
	(via
		(at 97.323777 104.459365)
		(size 0.45)
		(drill 0.1)
		(layers "F.Cu" "B.Cu")
		(remove_unused_layers yes)
		(keep_end_layers yes)
		(zone_layer_connections "In1.Cu" "In4.Cu" "In6.Cu")
		(teardrops
			(best_length_ratio 0.4)
			(max_length 1)
			(best_width_ratio 0.9)
			(max_width 2)
			(curved_edges yes)
			(filter_ratio 0.9)
			(enabled yes)
			(allow_two_segments yes)
			(prefer_zone_connections yes)
		)
		(net 1)
	)
	(via
		(at 223.16 127.195)
		(size 0.45)
		(drill 0.1)
		(layers "F.Cu" "B.Cu")
		(remove_unused_layers yes)
		(keep_end_layers yes)
		(zone_layer_connections "In1.Cu" "In4.Cu" "In6.Cu")
		(teardrops
			(best_length_ratio 0.4)
			(max_length 1)
			(best_width_ratio 0.9)
			(max_width 2)
			(curved_edges yes)
			(filter_ratio 0.9)
			(enabled yes)
			(allow_two_segments yes)
			(prefer_zone_connections yes)
		)
		(net 1)
	)
	(via
		(at 137.45 88.81)
		(size 0.45)
		(drill 0.1)
		(layers "F.Cu" "B.Cu")
		(remove_unused_layers yes)
		(keep_end_layers yes)
		(free yes)
		(zone_layer_connections "In1.Cu" "In4.Cu" "In6.Cu")
		(teardrops
			(best_length_ratio 0.4)
			(max_length 1)
			(best_width_ratio 0.9)
			(max_width 2)
			(curved_edges yes)
			(filter_ratio 0.9)
			(enabled yes)
			(allow_two_segments yes)
			(prefer_zone_connections yes)
		)
		(net 1)
	)
	(via
		(at 308.45 70.81)
		(size 0.45)
		(drill 0.1)
		(layers "F.Cu" "B.Cu")
		(remove_unused_layers yes)
		(keep_end_layers yes)
		(zone_layer_connections "In1.Cu" "In4.Cu" "In6.Cu")
		(teardrops
			(best_length_ratio 0.4)
			(max_length 1)
			(best_width_ratio 0.9)
			(max_width 2)
			(curved_edges yes)
			(filter_ratio 0.9)
			(enabled yes)
			(allow_two_segments yes)
			(prefer_zone_connections yes)
		)
		(net 1)
	)
	(via
		(at 227.78 74.15)
		(size 0.45)
		(drill 0.1)
		(layers "F.Cu" "B.Cu")
		(remove_unused_layers yes)
		(keep_end_layers yes)
		(zone_layer_connections "In1.Cu" "In4.Cu" "In6.Cu")
		(teardrops
			(best_length_ratio 0.4)
			(max_length 1)
			(best_width_ratio 0.9)
			(max_width 2)
			(curved_edges yes)
			(filter_ratio 0.9)
			(enabled yes)
			(allow_two_segments yes)
			(prefer_zone_connections yes)
		)
		(net 1)
	)
	(via
		(at 290.45 133.31)
		(size 0.45)
		(drill 0.1)
		(layers "F.Cu" "B.Cu")
		(remove_unused_layers yes)
		(keep_end_layers yes)
		(zone_layer_connections "In1.Cu" "In4.Cu" "In6.Cu")
		(teardrops
			(best_length_ratio 0.4)
			(max_length 1)
			(best_width_ratio 0.9)
			(max_width 2)
			(curved_edges yes)
			(filter_ratio 0.9)
			(enabled yes)
			(allow_two_segments yes)
			(prefer_zone_connections yes)
		)
		(net 1)
	)
	(via
		(at 103.45 126.81)
		(size 0.45)
		(drill 0.1)
		(layers "F.Cu" "B.Cu")
		(remove_unused_layers yes)
		(keep_end_layers yes)
		(zone_layer_connections "In1.Cu" "In4.Cu" "In6.Cu")
		(teardrops
			(best_length_ratio 0.4)
			(max_length 1)
			(best_width_ratio 0.9)
			(max_width 2)
			(curved_edges yes)
			(filter_ratio 0.9)
			(enabled yes)
			(allow_two_segments yes)
			(prefer_zone_connections yes)
		)
		(net 1)
	)
	(via
		(at 206.375 169.95)
		(size 0.45)
		(drill 0.1)
		(layers "F.Cu" "B.Cu")
		(teardrops
			(best_length_ratio 0.4)
			(max_length 1)
			(best_width_ratio 0.9)
			(max_width 2)
			(curved_edges yes)
			(filter_ratio 0.9)
			(enabled yes)
			(allow_two_segments yes)
			(prefer_zone_connections yes)
		)
		(net 1)
	)
	(via
		(at 286.45 136.81)
		(size 0.45)
		(drill 0.1)
		(layers "F.Cu" "B.Cu")
		(remove_unused_layers yes)
		(keep_end_layers yes)
		(zone_layer_connections "In1.Cu" "In4.Cu" "In6.Cu")
		(teardrops
			(best_length_ratio 0.4)
			(max_length 1)
			(best_width_ratio 0.9)
			(max_width 2)
			(curved_edges yes)
			(filter_ratio 0.9)
			(enabled yes)
			(allow_two_segments yes)
			(prefer_zone_connections yes)
		)
		(net 1)
	)
	(via
		(at 109.38 79)
		(size 0.45)
		(drill 0.1)
		(layers "F.Cu" "B.Cu")
		(remove_unused_layers yes)
		(keep_end_layers yes)
		(zone_layer_connections "In1.Cu" "In4.Cu" "In6.Cu")
		(teardrops
			(best_length_ratio 0.4)
			(max_length 1)
			(best_width_ratio 0.9)
			(max_width 2)
			(curved_edges yes)
			(filter_ratio 0.9)
			(enabled yes)
			(allow_two_segments yes)
			(prefer_zone_connections yes)
		)
		(net 1)
	)
	(via
		(at 124.45 162.81)
		(size 0.45)
		(drill 0.1)
		(layers "F.Cu" "B.Cu")
		(remove_unused_layers yes)
		(keep_end_layers yes)
		(zone_layer_connections "In1.Cu" "In4.Cu" "In6.Cu")
		(teardrops
			(best_length_ratio 0.4)
			(max_length 1)
			(best_width_ratio 0.9)
			(max_width 2)
			(curved_edges yes)
			(filter_ratio 0.9)
			(enabled yes)
			(allow_two_segments yes)
			(prefer_zone_connections yes)
		)
		(net 1)
	)
	(via
		(at 187.65 157.95)
		(size 0.45)
		(drill 0.1)
		(layers "F.Cu" "B.Cu")
		(teardrops
			(best_length_ratio 0.4)
			(max_length 1)
			(best_width_ratio 0.9)
			(max_width 2)
			(curved_edges yes)
			(filter_ratio 0.9)
			(enabled yes)
			(allow_two_segments yes)
			(prefer_zone_connections yes)
		)
		(net 1)
	)
	(via
		(at 145.45 132.86)
		(size 0.45)
		(drill 0.1)
		(layers "F.Cu" "B.Cu")
		(remove_unused_layers yes)
		(keep_end_layers yes)
		(zone_layer_connections "In1.Cu" "In4.Cu" "In6.Cu")
		(teardrops
			(best_length_ratio 0.4)
			(max_length 1)
			(best_width_ratio 0.9)
			(max_width 2)
			(curved_edges yes)
			(filter_ratio 0.9)
			(enabled yes)
			(allow_two_segments yes)
			(prefer_zone_connections yes)
		)
		(net 1)
	)
	(via
		(at 245.95 123.31)
		(size 0.45)
		(drill 0.1)
		(layers "F.Cu" "B.Cu")
		(remove_unused_layers yes)
		(keep_end_layers yes)
		(free yes)
		(zone_layer_connections "In1.Cu" "In4.Cu" "In6.Cu")
		(teardrops
			(best_length_ratio 0.4)
			(max_length 1)
			(best_width_ratio 0.9)
			(max_width 2)
			(curved_edges yes)
			(filter_ratio 0.9)
			(enabled yes)
			(allow_two_segments yes)
			(prefer_zone_connections yes)
		)
		(net 1)
	)
	(via
		(at 194.275 159.075)
		(size 0.45)
		(drill 0.1)
		(layers "F.Cu" "B.Cu")
		(teardrops
			(best_length_ratio 0.4)
			(max_length 1)
			(best_width_ratio 0.9)
			(max_width 2)
			(curved_edges yes)
			(filter_ratio 0.9)
			(enabled yes)
			(allow_two_segments yes)
			(prefer_zone_connections yes)
		)
		(net 1)
	)
	(via
		(at 111.275 161.125)
		(size 0.45)
		(drill 0.1)
		(layers "F.Cu" "B.Cu")
		(remove_unused_layers yes)
		(keep_end_layers yes)
		(free yes)
		(zone_layer_connections "In1.Cu" "In4.Cu" "In6.Cu")
		(teardrops
			(best_length_ratio 0.4)
			(max_length 1)
			(best_width_ratio 0.9)
			(max_width 2)
			(curved_edges yes)
			(filter_ratio 0.9)
			(enabled yes)
			(allow_two_segments yes)
			(prefer_zone_connections yes)
		)
		(net 1)
	)
	(via
		(at 133.450001 170.81)
		(size 0.45)
		(drill 0.1)
		(layers "F.Cu" "B.Cu")
		(remove_unused_layers yes)
		(keep_end_layers yes)
		(zone_layer_connections "In1.Cu" "In4.Cu" "In6.Cu")
		(teardrops
			(best_length_ratio 0.4)
			(max_length 1)
			(best_width_ratio 0.9)
			(max_width 2)
			(curved_edges yes)
			(filter_ratio 0.9)
			(enabled yes)
			(allow_two_segments yes)
			(prefer_zone_connections yes)
		)
		(net 1)
	)
	(via
		(at 300.64 131.04)
		(size 0.45)
		(drill 0.1)
		(layers "F.Cu" "B.Cu")
		(remove_unused_layers yes)
		(keep_end_layers yes)
		(zone_layer_connections "In1.Cu" "In4.Cu" "In6.Cu")
		(teardrops
			(best_length_ratio 0.4)
			(max_length 1)
			(best_width_ratio 0.9)
			(max_width 2)
			(curved_edges yes)
			(filter_ratio 0.9)
			(enabled yes)
			(allow_two_segments yes)
			(prefer_zone_connections yes)
		)
		(net 1)
	)
	(via
		(at 301.45 106.31)
		(size 0.45)
		(drill 0.1)
		(layers "F.Cu" "B.Cu")
		(remove_unused_layers yes)
		(keep_end_layers yes)
		(zone_layer_connections "In1.Cu" "In4.Cu" "In6.Cu")
		(teardrops
			(best_length_ratio 0.4)
			(max_length 1)
			(best_width_ratio 0.9)
			(max_width 2)
			(curved_edges yes)
			(filter_ratio 0.9)
			(enabled yes)
			(allow_two_segments yes)
			(prefer_zone_connections yes)
		)
		(net 1)
	)
	(via
		(at 293.95 141.31)
		(size 0.45)
		(drill 0.1)
		(layers "F.Cu" "B.Cu")
		(remove_unused_layers yes)
		(keep_end_layers yes)
		(zone_layer_connections "In1.Cu" "In4.Cu" "In6.Cu")
		(teardrops
			(best_length_ratio 0.4)
			(max_length 1)
			(best_width_ratio 0.9)
			(max_width 2)
			(curved_edges yes)
			(filter_ratio 0.9)
			(enabled yes)
			(allow_two_segments yes)
			(prefer_zone_connections yes)
		)
		(net 1)
	)
	(via
		(at 279.45 110.81)
		(size 0.45)
		(drill 0.1)
		(layers "F.Cu" "B.Cu")
		(remove_unused_layers yes)
		(keep_end_layers yes)
		(zone_layer_connections "In1.Cu" "In4.Cu" "In6.Cu")
		(teardrops
			(best_length_ratio 0.4)
			(max_length 1)
			(best_width_ratio 0.9)
			(max_width 2)
			(curved_edges yes)
			(filter_ratio 0.9)
			(enabled yes)
			(allow_two_segments yes)
			(prefer_zone_connections yes)
		)
		(net 1)
	)
	(via
		(at 311.474999 105.05)
		(size 0.45)
		(drill 0.1)
		(layers "F.Cu" "B.Cu")
		(remove_unused_layers yes)
		(keep_end_layers yes)
		(zone_layer_connections "In1.Cu" "In4.Cu" "In6.Cu")
		(teardrops
			(best_length_ratio 0.4)
			(max_length 1)
			(best_width_ratio 0.9)
			(max_width 2)
			(curved_edges yes)
			(filter_ratio 0.9)
			(enabled yes)
			(allow_two_segments yes)
			(prefer_zone_connections yes)
		)
		(net 1)
	)
	(via
		(at 96.45 135.81)
		(size 0.45)
		(drill 0.1)
		(layers "F.Cu" "B.Cu")
		(remove_unused_layers yes)
		(keep_end_layers yes)
		(zone_layer_connections "In1.Cu" "In4.Cu" "In6.Cu")
		(teardrops
			(best_length_ratio 0.4)
			(max_length 1)
			(best_width_ratio 0.9)
			(max_width 2)
			(curved_edges yes)
			(filter_ratio 0.9)
			(enabled yes)
			(allow_two_segments yes)
			(prefer_zone_connections yes)
		)
		(net 1)
	)
	(via
		(at 95.45 136.81)
		(size 0.45)
		(drill 0.1)
		(layers "F.Cu" "B.Cu")
		(remove_unused_layers yes)
		(keep_end_layers yes)
		(zone_layer_connections "In1.Cu" "In4.Cu" "In6.Cu")
		(teardrops
			(best_length_ratio 0.4)
			(max_length 1)
			(best_width_ratio 0.9)
			(max_width 2)
			(curved_edges yes)
			(filter_ratio 0.9)
			(enabled yes)
			(allow_two_segments yes)
			(prefer_zone_connections yes)
		)
		(net 1)
	)
	(via
		(at 124.45 157.62)
		(size 0.45)
		(drill 0.1)
		(layers "F.Cu" "B.Cu")
		(remove_unused_layers yes)
		(keep_end_layers yes)
		(zone_layer_connections "In1.Cu" "In4.Cu" "In6.Cu")
		(teardrops
			(best_length_ratio 0.4)
			(max_length 1)
			(best_width_ratio 0.9)
			(max_width 2)
			(curved_edges yes)
			(filter_ratio 0.9)
			(enabled yes)
			(allow_two_segments yes)
			(prefer_zone_connections yes)
		)
		(net 1)
	)
	(via
		(at 115.599 86.864)
		(size 0.45)
		(drill 0.1)
		(layers "F.Cu" "B.Cu")
		(remove_unused_layers yes)
		(keep_end_layers yes)
		(zone_layer_connections "In1.Cu" "In4.Cu" "In6.Cu")
		(teardrops
			(best_length_ratio 0.4)
			(max_length 1)
			(best_width_ratio 0.9)
			(max_width 2)
			(curved_edges yes)
			(filter_ratio 0.9)
			(enabled yes)
			(allow_two_segments yes)
			(prefer_zone_connections yes)
		)
		(net 1)
	)
	(via
		(at 315.4645 100.6365)
		(size 0.45)
		(drill 0.1)
		(layers "F.Cu" "B.Cu")
		(remove_unused_layers yes)
		(keep_end_layers yes)
		(free yes)
		(zone_layer_connections "In1.Cu" "In4.Cu" "In6.Cu")
		(teardrops
			(best_length_ratio 0.4)
			(max_length 1)
			(best_width_ratio 0.9)
			(max_width 2)
			(curved_edges yes)
			(filter_ratio 0.9)
			(enabled yes)
			(allow_two_segments yes)
			(prefer_zone_connections yes)
		)
		(net 1)
	)
	(via
		(at 218.8 149.8)
		(size 0.45)
		(drill 0.1)
		(layers "F.Cu" "B.Cu")
		(teardrops
			(best_length_ratio 0.4)
			(max_length 1)
			(best_width_ratio 0.9)
			(max_width 2)
			(curved_edges yes)
			(filter_ratio 0.9)
			(enabled yes)
			(allow_two_segments yes)
			(prefer_zone_connections yes)
		)
		(net 1)
	)
	(via
		(at 277.95 109.31)
		(size 0.45)
		(drill 0.1)
		(layers "F.Cu" "B.Cu")
		(remove_unused_layers yes)
		(keep_end_layers yes)
		(zone_layer_connections "In1.Cu" "In4.Cu" "In6.Cu")
		(teardrops
			(best_length_ratio 0.4)
			(max_length 1)
			(best_width_ratio 0.9)
			(max_width 2)
			(curved_edges yes)
			(filter_ratio 0.9)
			(enabled yes)
			(allow_two_segments yes)
			(prefer_zone_connections yes)
		)
		(net 1)
	)
	(via
		(at 214.45 74.96)
		(size 0.45)
		(drill 0.1)
		(layers "F.Cu" "B.Cu")
		(remove_unused_layers yes)
		(keep_end_layers yes)
		(zone_layer_connections "In1.Cu" "In4.Cu" "In6.Cu")
		(teardrops
			(best_length_ratio 0.4)
			(max_length 1)
			(best_width_ratio 0.9)
			(max_width 2)
			(curved_edges yes)
			(filter_ratio 0.9)
			(enabled yes)
			(allow_two_segments yes)
			(prefer_zone_connections yes)
		)
		(net 1)
	)
	(via
		(at 115.15 147.901)
		(size 0.45)
		(drill 0.1)
		(layers "F.Cu" "B.Cu")
		(remove_unused_layers yes)
		(keep_end_layers yes)
		(zone_layer_connections "In1.Cu" "In4.Cu" "In6.Cu")
		(teardrops
			(best_length_ratio 0.4)
			(max_length 1)
			(best_width_ratio 0.9)
			(max_width 2)
			(curved_edges yes)
			(filter_ratio 0.9)
			(enabled yes)
			(allow_two_segments yes)
			(prefer_zone_connections yes)
		)
		(net 1)
	)
	(via
		(at 286.425 78.42)
		(size 0.45)
		(drill 0.1)
		(layers "F.Cu" "B.Cu")
		(remove_unused_layers yes)
		(keep_end_layers yes)
		(free yes)
		(zone_layer_connections "In1.Cu" "In4.Cu" "In6.Cu")
		(teardrops
			(best_length_ratio 0.4)
			(max_length 1)
			(best_width_ratio 0.9)
			(max_width 2)
			(curved_edges yes)
			(filter_ratio 0.9)
			(enabled yes)
			(allow_two_segments yes)
			(prefer_zone_connections yes)
		)
		(net 1)
	)
	(via
		(at 120.4 147.361)
		(size 0.45)
		(drill 0.1)
		(layers "F.Cu" "B.Cu")
		(remove_unused_layers yes)
		(keep_end_layers yes)
		(zone_layer_connections "In1.Cu" "In4.Cu" "In6.Cu")
		(teardrops
			(best_length_ratio 0.4)
			(max_length 1)
			(best_width_ratio 0.9)
			(max_width 2)
			(curved_edges yes)
			(filter_ratio 0.9)
			(enabled yes)
			(allow_two_segments yes)
			(prefer_zone_connections yes)
		)
		(net 1)
	)
	(via
		(at 117.401 147.361)
		(size 0.45)
		(drill 0.1)
		(layers "F.Cu" "B.Cu")
		(remove_unused_layers yes)
		(keep_end_layers yes)
		(zone_layer_connections "In1.Cu" "In4.Cu" "In6.Cu")
		(teardrops
			(best_length_ratio 0.4)
			(max_length 1)
			(best_width_ratio 0.9)
			(max_width 2)
			(curved_edges yes)
			(filter_ratio 0.9)
			(enabled yes)
			(allow_two_segments yes)
			(prefer_zone_connections yes)
		)
		(net 1)
	)
	(via
		(at 108.95 83.81)
		(size 0.45)
		(drill 0.1)
		(layers "F.Cu" "B.Cu")
		(remove_unused_layers yes)
		(keep_end_layers yes)
		(zone_layer_connections "In1.Cu" "In4.Cu" "In6.Cu")
		(teardrops
			(best_length_ratio 0.4)
			(max_length 1)
			(best_width_ratio 0.9)
			(max_width 2)
			(curved_edges yes)
			(filter_ratio 0.9)
			(enabled yes)
			(allow_two_segments yes)
			(prefer_zone_connections yes)
		)
		(net 1)
	)
	(via
		(at 101.45 128.81)
		(size 0.45)
		(drill 0.1)
		(layers "F.Cu" "B.Cu")
		(remove_unused_layers yes)
		(keep_end_layers yes)
		(zone_layer_connections "In1.Cu" "In4.Cu" "In6.Cu")
		(teardrops
			(best_length_ratio 0.4)
			(max_length 1)
			(best_width_ratio 0.9)
			(max_width 2)
			(curved_edges yes)
			(filter_ratio 0.9)
			(enabled yes)
			(allow_two_segments yes)
			(prefer_zone_connections yes)
		)
		(net 1)
	)
	(via
		(at 246.95 170.81)
		(size 0.45)
		(drill 0.1)
		(layers "F.Cu" "B.Cu")
		(remove_unused_layers yes)
		(keep_end_layers yes)
		(zone_layer_connections "In1.Cu" "In4.Cu" "In6.Cu")
		(teardrops
			(best_length_ratio 0.4)
			(max_length 1)
			(best_width_ratio 0.9)
			(max_width 2)
			(curved_edges yes)
			(filter_ratio 0.9)
			(enabled yes)
			(allow_two_segments yes)
			(prefer_zone_connections yes)
		)
		(net 1)
	)
	(via
		(at 125.22 148.78)
		(size 0.45)
		(drill 0.1)
		(layers "F.Cu" "B.Cu")
		(remove_unused_layers yes)
		(keep_end_layers yes)
		(zone_layer_connections "In1.Cu" "In4.Cu" "In6.Cu")
		(teardrops
			(best_length_ratio 0.4)
			(max_length 1)
			(best_width_ratio 0.9)
			(max_width 2)
			(curved_edges yes)
			(filter_ratio 0.9)
			(enabled yes)
			(allow_two_segments yes)
			(prefer_zone_connections yes)
		)
		(net 1)
	)
	(via
		(at 211.95 89.31)
		(size 0.45)
		(drill 0.1)
		(layers "F.Cu" "B.Cu")
		(remove_unused_layers yes)
		(keep_end_layers yes)
		(free yes)
		(zone_layer_connections "In1.Cu" "In4.Cu" "In6.Cu")
		(teardrops
			(best_length_ratio 0.4)
			(max_length 1)
			(best_width_ratio 0.9)
			(max_width 2)
			(curved_edges yes)
			(filter_ratio 0.9)
			(enabled yes)
			(allow_two_segments yes)
			(prefer_zone_connections yes)
		)
		(net 1)
	)
	(via
		(at 121.5 73.13)
		(size 0.45)
		(drill 0.1)
		(layers "F.Cu" "B.Cu")
		(remove_unused_layers yes)
		(keep_end_layers yes)
		(zone_layer_connections "In1.Cu" "In4.Cu" "In6.Cu")
		(teardrops
			(best_length_ratio 0.4)
			(max_length 1)
			(best_width_ratio 0.9)
			(max_width 2)
			(curved_edges yes)
			(filter_ratio 0.9)
			(enabled yes)
			(allow_two_segments yes)
			(prefer_zone_connections yes)
		)
		(net 1)
	)
	(via
		(at 254.95 117.31)
		(size 0.45)
		(drill 0.1)
		(layers "F.Cu" "B.Cu")
		(remove_unused_layers yes)
		(keep_end_layers yes)
		(zone_layer_connections "In1.Cu" "In4.Cu" "In6.Cu")
		(teardrops
			(best_length_ratio 0.4)
			(max_length 1)
			(best_width_ratio 0.9)
			(max_width 2)
			(curved_edges yes)
			(filter_ratio 0.9)
			(enabled yes)
			(allow_two_segments yes)
			(prefer_zone_connections yes)
		)
		(net 1)
	)
	(via
		(at 160.45 85.31)
		(size 0.45)
		(drill 0.1)
		(layers "F.Cu" "B.Cu")
		(remove_unused_layers yes)
		(keep_end_layers yes)
		(zone_layer_connections "In1.Cu" "In4.Cu" "In6.Cu")
		(teardrops
			(best_length_ratio 0.4)
			(max_length 1)
			(best_width_ratio 0.9)
			(max_width 2)
			(curved_edges yes)
			(filter_ratio 0.9)
			(enabled yes)
			(allow_two_segments yes)
			(prefer_zone_connections yes)
		)
		(net 1)
	)
	(via
		(at 301.95 71.81)
		(size 0.45)
		(drill 0.1)
		(layers "F.Cu" "B.Cu")
		(remove_unused_layers yes)
		(keep_end_layers yes)
		(zone_layer_connections "In1.Cu" "In4.Cu" "In6.Cu")
		(teardrops
			(best_length_ratio 0.4)
			(max_length 1)
			(best_width_ratio 0.9)
			(max_width 2)
			(curved_edges yes)
			(filter_ratio 0.9)
			(enabled yes)
			(allow_two_segments yes)
			(prefer_zone_connections yes)
		)
		(net 1)
	)
	(via
		(at 181 169.899)
		(size 0.45)
		(drill 0.1)
		(layers "F.Cu" "B.Cu")
		(teardrops
			(best_length_ratio 0.4)
			(max_length 1)
			(best_width_ratio 0.9)
			(max_width 2)
			(curved_edges yes)
			(filter_ratio 0.9)
			(enabled yes)
			(allow_two_segments yes)
			(prefer_zone_connections yes)
		)
		(net 1)
	)
	(via
		(at 135.719999 147.62)
		(size 0.45)
		(drill 0.1)
		(layers "F.Cu" "B.Cu")
		(remove_unused_layers yes)
		(keep_end_layers yes)
		(zone_layer_connections "In1.Cu" "In4.Cu" "In6.Cu")
		(teardrops
			(best_length_ratio 0.4)
			(max_length 1)
			(best_width_ratio 0.9)
			(max_width 2)
			(curved_edges yes)
			(filter_ratio 0.9)
			(enabled yes)
			(allow_two_segments yes)
			(prefer_zone_connections yes)
		)
		(net 1)
	)
	(via
		(at 105.35 154.46)
		(size 0.45)
		(drill 0.1)
		(layers "F.Cu" "B.Cu")
		(remove_unused_layers yes)
		(keep_end_layers yes)
		(zone_layer_connections "In1.Cu" "In4.Cu" "In6.Cu")
		(teardrops
			(best_length_ratio 0.4)
			(max_length 1)
			(best_width_ratio 0.9)
			(max_width 2)
			(curved_edges yes)
			(filter_ratio 0.9)
			(enabled yes)
			(allow_two_segments yes)
			(prefer_zone_connections yes)
		)
		(net 1)
	)
	(via
		(at 144.95 69.81)
		(size 0.45)
		(drill 0.1)
		(layers "F.Cu" "B.Cu")
		(remove_unused_layers yes)
		(keep_end_layers yes)
		(zone_layer_connections "In1.Cu" "In4.Cu" "In6.Cu")
		(teardrops
			(best_length_ratio 0.4)
			(max_length 1)
			(best_width_ratio 0.9)
			(max_width 2)
			(curved_edges yes)
			(filter_ratio 0.9)
			(enabled yes)
			(allow_two_segments yes)
			(prefer_zone_connections yes)
		)
		(net 1)
	)
	(via
		(at 128.45 164.81)
		(size 0.45)
		(drill 0.1)
		(layers "F.Cu" "B.Cu")
		(remove_unused_layers yes)
		(keep_end_layers yes)
		(zone_layer_connections "In1.Cu" "In4.Cu" "In6.Cu")
		(teardrops
			(best_length_ratio 0.4)
			(max_length 1)
			(best_width_ratio 0.9)
			(max_width 2)
			(curved_edges yes)
			(filter_ratio 0.9)
			(enabled yes)
			(allow_two_segments yes)
			(prefer_zone_connections yes)
		)
		(net 1)
	)
	(via
		(at 214.95 89.31)
		(size 0.45)
		(drill 0.1)
		(layers "F.Cu" "B.Cu")
		(remove_unused_layers yes)
		(keep_end_layers yes)
		(zone_layer_connections "In1.Cu" "In4.Cu" "In6.Cu")
		(teardrops
			(best_length_ratio 0.4)
			(max_length 1)
			(best_width_ratio 0.9)
			(max_width 2)
			(curved_edges yes)
			(filter_ratio 0.9)
			(enabled yes)
			(allow_two_segments yes)
			(prefer_zone_connections yes)
		)
		(net 1)
	)
	(via
		(at 284.95 135.31)
		(size 0.45)
		(drill 0.1)
		(layers "F.Cu" "B.Cu")
		(remove_unused_layers yes)
		(keep_end_layers yes)
		(zone_layer_connections "In1.Cu" "In4.Cu" "In6.Cu")
		(teardrops
			(best_length_ratio 0.4)
			(max_length 1)
			(best_width_ratio 0.9)
			(max_width 2)
			(curved_edges yes)
			(filter_ratio 0.9)
			(enabled yes)
			(allow_two_segments yes)
			(prefer_zone_connections yes)
		)
		(net 1)
	)
	(via
		(at 200.45 106.31)
		(size 0.45)
		(drill 0.1)
		(layers "F.Cu" "B.Cu")
		(remove_unused_layers yes)
		(keep_end_layers yes)
		(zone_layer_connections "In1.Cu" "In4.Cu" "In6.Cu")
		(teardrops
			(best_length_ratio 0.4)
			(max_length 1)
			(best_width_ratio 0.9)
			(max_width 2)
			(curved_edges yes)
			(filter_ratio 0.9)
			(enabled yes)
			(allow_two_segments yes)
			(prefer_zone_connections yes)
		)
		(net 1)
	)
	(via
		(at 145.0705 75.3085)
		(size 0.45)
		(drill 0.1)
		(layers "F.Cu" "B.Cu")
		(remove_unused_layers yes)
		(keep_end_layers yes)
		(zone_layer_connections "In1.Cu" "In4.Cu" "In6.Cu")
		(teardrops
			(best_length_ratio 0.4)
			(max_length 1)
			(best_width_ratio 0.9)
			(max_width 2)
			(curved_edges yes)
			(filter_ratio 0.9)
			(enabled yes)
			(allow_two_segments yes)
			(prefer_zone_connections yes)
		)
		(net 1)
	)
	(via
		(at 106.95 74.31)
		(size 0.45)
		(drill 0.1)
		(layers "F.Cu" "B.Cu")
		(remove_unused_layers yes)
		(keep_end_layers yes)
		(zone_layer_connections "In1.Cu" "In4.Cu" "In6.Cu")
		(teardrops
			(best_length_ratio 0.4)
			(max_length 1)
			(best_width_ratio 0.9)
			(max_width 2)
			(curved_edges yes)
			(filter_ratio 0.9)
			(enabled yes)
			(allow_two_segments yes)
			(prefer_zone_connections yes)
		)
		(net 1)
	)
	(via
		(at 205.55 155.4)
		(size 0.45)
		(drill 0.1)
		(layers "F.Cu" "B.Cu")
		(teardrops
			(best_length_ratio 0.4)
			(max_length 1)
			(best_width_ratio 0.9)
			(max_width 2)
			(curved_edges yes)
			(filter_ratio 0.9)
			(enabled yes)
			(allow_two_segments yes)
			(prefer_zone_connections yes)
		)
		(net 1)
	)
	(via
		(at 124.45 79.81)
		(size 0.45)
		(drill 0.1)
		(layers "F.Cu" "B.Cu")
		(remove_unused_layers yes)
		(keep_end_layers yes)
		(zone_layer_connections "In1.Cu" "In4.Cu" "In6.Cu")
		(teardrops
			(best_length_ratio 0.4)
			(max_length 1)
			(best_width_ratio 0.9)
			(max_width 2)
			(curved_edges yes)
			(filter_ratio 0.9)
			(enabled yes)
			(allow_two_segments yes)
			(prefer_zone_connections yes)
		)
		(net 1)
	)
	(via
		(at 316.489499 135.71)
		(size 0.45)
		(drill 0.1)
		(layers "F.Cu" "B.Cu")
		(remove_unused_layers yes)
		(keep_end_layers yes)
		(zone_layer_connections "In1.Cu" "In4.Cu" "In6.Cu")
		(teardrops
			(best_length_ratio 0.4)
			(max_length 1)
			(best_width_ratio 0.9)
			(max_width 2)
			(curved_edges yes)
			(filter_ratio 0.9)
			(enabled yes)
			(allow_two_segments yes)
			(prefer_zone_connections yes)
		)
		(net 1)
	)
	(via
		(at 173.38 103.975)
		(size 0.45)
		(drill 0.1)
		(layers "F.Cu" "B.Cu")
		(remove_unused_layers yes)
		(keep_end_layers yes)
		(zone_layer_connections "In1.Cu" "In4.Cu" "In6.Cu")
		(teardrops
			(best_length_ratio 0.4)
			(max_length 1)
			(best_width_ratio 0.9)
			(max_width 2)
			(curved_edges yes)
			(filter_ratio 0.9)
			(enabled yes)
			(allow_two_segments yes)
			(prefer_zone_connections yes)
		)
		(net 1)
	)
	(via
		(at 131.45 88.81)
		(size 0.45)
		(drill 0.1)
		(layers "F.Cu" "B.Cu")
		(remove_unused_layers yes)
		(keep_end_layers yes)
		(zone_layer_connections "In1.Cu" "In4.Cu" "In6.Cu")
		(teardrops
			(best_length_ratio 0.4)
			(max_length 1)
			(best_width_ratio 0.9)
			(max_width 2)
			(curved_edges yes)
			(filter_ratio 0.9)
			(enabled yes)
			(allow_two_segments yes)
			(prefer_zone_connections yes)
		)
		(net 1)
	)
	(via
		(at 301.95 146.31)
		(size 0.45)
		(drill 0.1)
		(layers "F.Cu" "B.Cu")
		(remove_unused_layers yes)
		(keep_end_layers yes)
		(zone_layer_connections "In1.Cu" "In4.Cu" "In6.Cu")
		(teardrops
			(best_length_ratio 0.4)
			(max_length 1)
			(best_width_ratio 0.9)
			(max_width 2)
			(curved_edges yes)
			(filter_ratio 0.9)
			(enabled yes)
			(allow_two_segments yes)
			(prefer_zone_connections yes)
		)
		(net 1)
	)
	(via
		(at 308.5 150.96)
		(size 0.45)
		(drill 0.1)
		(layers "F.Cu" "B.Cu")
		(remove_unused_layers yes)
		(keep_end_layers yes)
		(zone_layer_connections "In1.Cu" "In4.Cu" "In6.Cu")
		(teardrops
			(best_length_ratio 0.4)
			(max_length 1)
			(best_width_ratio 0.9)
			(max_width 2)
			(curved_edges yes)
			(filter_ratio 0.9)
			(enabled yes)
			(allow_two_segments yes)
			(prefer_zone_connections yes)
		)
		(net 1)
	)
	(via
		(at 283.45 91.81)
		(size 0.45)
		(drill 0.1)
		(layers "F.Cu" "B.Cu")
		(remove_unused_layers yes)
		(keep_end_layers yes)
		(zone_layer_connections "In1.Cu" "In4.Cu" "In6.Cu")
		(teardrops
			(best_length_ratio 0.4)
			(max_length 1)
			(best_width_ratio 0.9)
			(max_width 2)
			(curved_edges yes)
			(filter_ratio 0.9)
			(enabled yes)
			(allow_two_segments yes)
			(prefer_zone_connections yes)
		)
		(net 1)
	)
	(via
		(at 265.45 127.81)
		(size 0.45)
		(drill 0.1)
		(layers "F.Cu" "B.Cu")
		(remove_unused_layers yes)
		(keep_end_layers yes)
		(zone_layer_connections "In1.Cu" "In4.Cu" "In6.Cu")
		(teardrops
			(best_length_ratio 0.4)
			(max_length 1)
			(best_width_ratio 0.9)
			(max_width 2)
			(curved_edges yes)
			(filter_ratio 0.9)
			(enabled yes)
			(allow_two_segments yes)
			(prefer_zone_connections yes)
		)
		(net 1)
	)
	(via
		(at 112.849 135.71)
		(size 0.45)
		(drill 0.1)
		(layers "F.Cu" "B.Cu")
		(remove_unused_layers yes)
		(keep_end_layers yes)
		(zone_layer_connections "In1.Cu" "In4.Cu" "In6.Cu")
		(teardrops
			(best_length_ratio 0.4)
			(max_length 1)
			(best_width_ratio 0.9)
			(max_width 2)
			(curved_edges yes)
			(filter_ratio 0.9)
			(enabled yes)
			(allow_two_segments yes)
			(prefer_zone_connections yes)
		)
		(net 1)
	)
	(via
		(at 99.46 163.6)
		(size 0.45)
		(drill 0.1)
		(layers "F.Cu" "B.Cu")
		(remove_unused_layers yes)
		(keep_end_layers yes)
		(zone_layer_connections "In1.Cu" "In4.Cu" "In6.Cu")
		(teardrops
			(best_length_ratio 0.4)
			(max_length 1)
			(best_width_ratio 0.9)
			(max_width 2)
			(curved_edges yes)
			(filter_ratio 0.9)
			(enabled yes)
			(allow_two_segments yes)
			(prefer_zone_connections yes)
		)
		(net 1)
	)
	(via
		(at 162.45 153.31)
		(size 0.45)
		(drill 0.1)
		(layers "F.Cu" "B.Cu")
		(remove_unused_layers yes)
		(keep_end_layers yes)
		(zone_layer_connections "In1.Cu" "In4.Cu" "In6.Cu")
		(teardrops
			(best_length_ratio 0.4)
			(max_length 1)
			(best_width_ratio 0.9)
			(max_width 2)
			(curved_edges yes)
			(filter_ratio 0.9)
			(enabled yes)
			(allow_two_segments yes)
			(prefer_zone_connections yes)
		)
		(net 1)
	)
	(via
		(at 189.45 71.81)
		(size 0.45)
		(drill 0.1)
		(layers "F.Cu" "B.Cu")
		(remove_unused_layers yes)
		(keep_end_layers yes)
		(free yes)
		(zone_layer_connections "In1.Cu" "In4.Cu" "In6.Cu")
		(teardrops
			(best_length_ratio 0.4)
			(max_length 1)
			(best_width_ratio 0.9)
			(max_width 2)
			(curved_edges yes)
			(filter_ratio 0.9)
			(enabled yes)
			(allow_two_segments yes)
			(prefer_zone_connections yes)
		)
		(net 1)
	)
	(via
		(at 231.270707 77.635)
		(size 0.45)
		(drill 0.1)
		(layers "F.Cu" "B.Cu")
		(remove_unused_layers yes)
		(keep_end_layers yes)
		(zone_layer_connections "In1.Cu" "In4.Cu" "In6.Cu")
		(teardrops
			(best_length_ratio 0.4)
			(max_length 1)
			(best_width_ratio 0.9)
			(max_width 2)
			(curved_edges yes)
			(filter_ratio 0.9)
			(enabled yes)
			(allow_two_segments yes)
			(prefer_zone_connections yes)
		)
		(net 1)
	)
	(via
		(at 113.95 136.15)
		(size 0.45)
		(drill 0.1)
		(layers "F.Cu" "B.Cu")
		(remove_unused_layers yes)
		(keep_end_layers yes)
		(zone_layer_connections "In1.Cu" "In4.Cu" "In6.Cu")
		(teardrops
			(best_length_ratio 0.4)
			(max_length 1)
			(best_width_ratio 0.9)
			(max_width 2)
			(curved_edges yes)
			(filter_ratio 0.9)
			(enabled yes)
			(allow_two_segments yes)
			(prefer_zone_connections yes)
		)
		(net 1)
	)
	(via
		(at 145.45 135.86)
		(size 0.45)
		(drill 0.1)
		(layers "F.Cu" "B.Cu")
		(remove_unused_layers yes)
		(keep_end_layers yes)
		(zone_layer_connections "In1.Cu" "In4.Cu" "In6.Cu")
		(teardrops
			(best_length_ratio 0.4)
			(max_length 1)
			(best_width_ratio 0.9)
			(max_width 2)
			(curved_edges yes)
			(filter_ratio 0.9)
			(enabled yes)
			(allow_two_segments yes)
			(prefer_zone_connections yes)
		)
		(net 1)
	)
	(via
		(at 99.45 68.81)
		(size 0.45)
		(drill 0.1)
		(layers "F.Cu" "B.Cu")
		(remove_unused_layers yes)
		(keep_end_layers yes)
		(zone_layer_connections "In1.Cu" "In4.Cu" "In6.Cu")
		(teardrops
			(best_length_ratio 0.4)
			(max_length 1)
			(best_width_ratio 0.9)
			(max_width 2)
			(curved_edges yes)
			(filter_ratio 0.9)
			(enabled yes)
			(allow_two_segments yes)
			(prefer_zone_connections yes)
		)
		(net 1)
	)
	(via
		(at 217 161.6)
		(size 0.45)
		(drill 0.1)
		(layers "F.Cu" "B.Cu")
		(teardrops
			(best_length_ratio 0.4)
			(max_length 1)
			(best_width_ratio 0.9)
			(max_width 2)
			(curved_edges yes)
			(filter_ratio 0.9)
			(enabled yes)
			(allow_two_segments yes)
			(prefer_zone_connections yes)
		)
		(net 1)
	)
	(via
		(at 154.45 136.86)
		(size 0.45)
		(drill 0.1)
		(layers "F.Cu" "B.Cu")
		(remove_unused_layers yes)
		(keep_end_layers yes)
		(zone_layer_connections "In1.Cu" "In4.Cu" "In6.Cu")
		(teardrops
			(best_length_ratio 0.4)
			(max_length 1)
			(best_width_ratio 0.9)
			(max_width 2)
			(curved_edges yes)
			(filter_ratio 0.9)
			(enabled yes)
			(allow_two_segments yes)
			(prefer_zone_connections yes)
		)
		(net 1)
	)
	(via
		(at 112.45 114.81)
		(size 0.45)
		(drill 0.1)
		(layers "F.Cu" "B.Cu")
		(remove_unused_layers yes)
		(keep_end_layers yes)
		(zone_layer_connections "In1.Cu" "In4.Cu" "In6.Cu")
		(teardrops
			(best_length_ratio 0.4)
			(max_length 1)
			(best_width_ratio 0.9)
			(max_width 2)
			(curved_edges yes)
			(filter_ratio 0.9)
			(enabled yes)
			(allow_two_segments yes)
			(prefer_zone_connections yes)
		)
		(net 1)
	)
	(via
		(at 95.45 88.81)
		(size 0.45)
		(drill 0.1)
		(layers "F.Cu" "B.Cu")
		(remove_unused_layers yes)
		(keep_end_layers yes)
		(zone_layer_connections "In1.Cu" "In4.Cu" "In6.Cu")
		(teardrops
			(best_length_ratio 0.4)
			(max_length 1)
			(best_width_ratio 0.9)
			(max_width 2)
			(curved_edges yes)
			(filter_ratio 0.9)
			(enabled yes)
			(allow_two_segments yes)
			(prefer_zone_connections yes)
		)
		(net 1)
	)
	(via
		(at 279.45 125.31)
		(size 0.45)
		(drill 0.1)
		(layers "F.Cu" "B.Cu")
		(remove_unused_layers yes)
		(keep_end_layers yes)
		(zone_layer_connections "In1.Cu" "In4.Cu" "In6.Cu")
		(teardrops
			(best_length_ratio 0.4)
			(max_length 1)
			(best_width_ratio 0.9)
			(max_width 2)
			(curved_edges yes)
			(filter_ratio 0.9)
			(enabled yes)
			(allow_two_segments yes)
			(prefer_zone_connections yes)
		)
		(net 1)
	)
	(via
		(at 129.5 99.97)
		(size 0.45)
		(drill 0.1)
		(layers "F.Cu" "B.Cu")
		(remove_unused_layers yes)
		(keep_end_layers yes)
		(zone_layer_connections "In1.Cu" "In4.Cu" "In6.Cu")
		(teardrops
			(best_length_ratio 0.4)
			(max_length 1)
			(best_width_ratio 0.9)
			(max_width 2)
			(curved_edges yes)
			(filter_ratio 0.9)
			(enabled yes)
			(allow_two_segments yes)
			(prefer_zone_connections yes)
		)
		(net 1)
	)
	(via
		(at 133.29 142.86)
		(size 0.45)
		(drill 0.1)
		(layers "F.Cu" "B.Cu")
		(remove_unused_layers yes)
		(keep_end_layers yes)
		(zone_layer_connections "In1.Cu" "In4.Cu" "In6.Cu")
		(teardrops
			(best_length_ratio 0.4)
			(max_length 1)
			(best_width_ratio 0.9)
			(max_width 2)
			(curved_edges yes)
			(filter_ratio 0.9)
			(enabled yes)
			(allow_two_segments yes)
			(prefer_zone_connections yes)
		)
		(net 1)
	)
	(via
		(at 112.45 82.31)
		(size 0.45)
		(drill 0.1)
		(layers "F.Cu" "B.Cu")
		(remove_unused_layers yes)
		(keep_end_layers yes)
		(zone_layer_connections "In1.Cu" "In4.Cu" "In6.Cu")
		(teardrops
			(best_length_ratio 0.4)
			(max_length 1)
			(best_width_ratio 0.9)
			(max_width 2)
			(curved_edges yes)
			(filter_ratio 0.9)
			(enabled yes)
			(allow_two_segments yes)
			(prefer_zone_connections yes)
		)
		(net 1)
	)
	(via
		(at 149.02 147.63)
		(size 0.45)
		(drill 0.1)
		(layers "F.Cu" "B.Cu")
		(remove_unused_layers yes)
		(keep_end_layers yes)
		(zone_layer_connections "In1.Cu" "In4.Cu" "In6.Cu")
		(teardrops
			(best_length_ratio 0.4)
			(max_length 1)
			(best_width_ratio 0.9)
			(max_width 2)
			(curved_edges yes)
			(filter_ratio 0.9)
			(enabled yes)
			(allow_two_segments yes)
			(prefer_zone_connections yes)
		)
		(net 1)
	)
	(via
		(at 249.245 131.51)
		(size 0.45)
		(drill 0.1)
		(layers "F.Cu" "B.Cu")
		(remove_unused_layers yes)
		(keep_end_layers yes)
		(zone_layer_connections "In1.Cu" "In4.Cu" "In6.Cu")
		(teardrops
			(best_length_ratio 0.4)
			(max_length 1)
			(best_width_ratio 0.9)
			(max_width 2)
			(curved_edges yes)
			(filter_ratio 0.9)
			(enabled yes)
			(allow_two_segments yes)
			(prefer_zone_connections yes)
		)
		(net 1)
	)
	(via
		(at 219.45 131.31)
		(size 0.45)
		(drill 0.1)
		(layers "F.Cu" "B.Cu")
		(remove_unused_layers yes)
		(keep_end_layers yes)
		(zone_layer_connections "In1.Cu" "In4.Cu" "In6.Cu")
		(teardrops
			(best_length_ratio 0.4)
			(max_length 1)
			(best_width_ratio 0.9)
			(max_width 2)
			(curved_edges yes)
			(filter_ratio 0.9)
			(enabled yes)
			(allow_two_segments yes)
			(prefer_zone_connections yes)
		)
		(net 1)
	)
	(via
		(at 192.66484 136.078743)
		(size 0.45)
		(drill 0.1)
		(layers "F.Cu" "B.Cu")
		(remove_unused_layers yes)
		(keep_end_layers yes)
		(zone_layer_connections "In1.Cu" "In4.Cu" "In6.Cu")
		(teardrops
			(best_length_ratio 0.4)
			(max_length 1)
			(best_width_ratio 0.9)
			(max_width 2)
			(curved_edges yes)
			(filter_ratio 0.9)
			(enabled yes)
			(allow_two_segments yes)
			(prefer_zone_connections yes)
		)
		(net 1)
	)
	(via
		(at 222.95 123.81)
		(size 0.45)
		(drill 0.1)
		(layers "F.Cu" "B.Cu")
		(remove_unused_layers yes)
		(keep_end_layers yes)
		(zone_layer_connections "In1.Cu" "In4.Cu" "In6.Cu")
		(teardrops
			(best_length_ratio 0.4)
			(max_length 1)
			(best_width_ratio 0.9)
			(max_width 2)
			(curved_edges yes)
			(filter_ratio 0.9)
			(enabled yes)
			(allow_two_segments yes)
			(prefer_zone_connections yes)
		)
		(net 1)
	)
	(via
		(at 142.95 69.81)
		(size 0.45)
		(drill 0.1)
		(layers "F.Cu" "B.Cu")
		(remove_unused_layers yes)
		(keep_end_layers yes)
		(zone_layer_connections "In1.Cu" "In4.Cu" "In6.Cu")
		(teardrops
			(best_length_ratio 0.4)
			(max_length 1)
			(best_width_ratio 0.9)
			(max_width 2)
			(curved_edges yes)
			(filter_ratio 0.9)
			(enabled yes)
			(allow_two_segments yes)
			(prefer_zone_connections yes)
		)
		(net 1)
	)
	(via
		(at 233.4 164.4)
		(size 0.45)
		(drill 0.1)
		(layers "F.Cu" "B.Cu")
		(teardrops
			(best_length_ratio 0.4)
			(max_length 1)
			(best_width_ratio 0.9)
			(max_width 2)
			(curved_edges yes)
			(filter_ratio 0.9)
			(enabled yes)
			(allow_two_segments yes)
			(prefer_zone_connections yes)
		)
		(net 1)
	)
	(via
		(at 119.4 112.31)
		(size 0.45)
		(drill 0.1)
		(layers "F.Cu" "B.Cu")
		(remove_unused_layers yes)
		(keep_end_layers yes)
		(zone_layer_connections "In1.Cu" "In4.Cu" "In6.Cu")
		(teardrops
			(best_length_ratio 0.4)
			(max_length 1)
			(best_width_ratio 0.9)
			(max_width 2)
			(curved_edges yes)
			(filter_ratio 0.9)
			(enabled yes)
			(allow_two_segments yes)
			(prefer_zone_connections yes)
		)
		(net 1)
	)
	(via
		(at 153.88 147.634077)
		(size 0.45)
		(drill 0.1)
		(layers "F.Cu" "B.Cu")
		(remove_unused_layers yes)
		(keep_end_layers yes)
		(zone_layer_connections "In1.Cu" "In4.Cu" "In6.Cu")
		(teardrops
			(best_length_ratio 0.4)
			(max_length 1)
			(best_width_ratio 0.9)
			(max_width 2)
			(curved_edges yes)
			(filter_ratio 0.9)
			(enabled yes)
			(allow_two_segments yes)
			(prefer_zone_connections yes)
		)
		(net 1)
	)
	(via
		(at 169.9 164.5)
		(size 0.45)
		(drill 0.1)
		(layers "F.Cu" "B.Cu")
		(teardrops
			(best_length_ratio 0.4)
			(max_length 1)
			(best_width_ratio 0.9)
			(max_width 2)
			(curved_edges yes)
			(filter_ratio 0.9)
			(enabled yes)
			(allow_two_segments yes)
			(prefer_zone_connections yes)
		)
		(net 1)
	)
	(via
		(at 258.325 127.181748)
		(size 0.45)
		(drill 0.1)
		(layers "F.Cu" "B.Cu")
		(remove_unused_layers yes)
		(keep_end_layers yes)
		(zone_layer_connections "In1.Cu" "In4.Cu" "In6.Cu")
		(teardrops
			(best_length_ratio 0.4)
			(max_length 1)
			(best_width_ratio 0.9)
			(max_width 2)
			(curved_edges yes)
			(filter_ratio 0.9)
			(enabled yes)
			(allow_two_segments yes)
			(prefer_zone_connections yes)
		)
		(net 1)
	)
	(via
		(at 230.7 158.2)
		(size 0.45)
		(drill 0.1)
		(layers "F.Cu" "B.Cu")
		(teardrops
			(best_length_ratio 0.4)
			(max_length 1)
			(best_width_ratio 0.9)
			(max_width 2)
			(curved_edges yes)
			(filter_ratio 0.9)
			(enabled yes)
			(allow_two_segments yes)
			(prefer_zone_connections yes)
		)
		(net 1)
	)
	(via
		(at 96.45 131.81)
		(size 0.45)
		(drill 0.1)
		(layers "F.Cu" "B.Cu")
		(remove_unused_layers yes)
		(keep_end_layers yes)
		(zone_layer_connections "In1.Cu" "In4.Cu" "In6.Cu")
		(teardrops
			(best_length_ratio 0.4)
			(max_length 1)
			(best_width_ratio 0.9)
			(max_width 2)
			(curved_edges yes)
			(filter_ratio 0.9)
			(enabled yes)
			(allow_two_segments yes)
			(prefer_zone_connections yes)
		)
		(net 1)
	)
	(via
		(at 282.45 80.31)
		(size 0.45)
		(drill 0.1)
		(layers "F.Cu" "B.Cu")
		(remove_unused_layers yes)
		(keep_end_layers yes)
		(zone_layer_connections "In1.Cu" "In4.Cu" "In6.Cu")
		(teardrops
			(best_length_ratio 0.4)
			(max_length 1)
			(best_width_ratio 0.9)
			(max_width 2)
			(curved_edges yes)
			(filter_ratio 0.9)
			(enabled yes)
			(allow_two_segments yes)
			(prefer_zone_connections yes)
		)
		(net 1)
	)
	(via
		(at 289.95 117.31)
		(size 0.45)
		(drill 0.1)
		(layers "F.Cu" "B.Cu")
		(remove_unused_layers yes)
		(keep_end_layers yes)
		(zone_layer_connections "In1.Cu" "In4.Cu" "In6.Cu")
		(teardrops
			(best_length_ratio 0.4)
			(max_length 1)
			(best_width_ratio 0.9)
			(max_width 2)
			(curved_edges yes)
			(filter_ratio 0.9)
			(enabled yes)
			(allow_two_segments yes)
			(prefer_zone_connections yes)
		)
		(net 1)
	)
	(via
		(at 283.45 136.81)
		(size 0.45)
		(drill 0.1)
		(layers "F.Cu" "B.Cu")
		(remove_unused_layers yes)
		(keep_end_layers yes)
		(zone_layer_connections "In1.Cu" "In4.Cu" "In6.Cu")
		(teardrops
			(best_length_ratio 0.4)
			(max_length 1)
			(best_width_ratio 0.9)
			(max_width 2)
			(curved_edges yes)
			(filter_ratio 0.9)
			(enabled yes)
			(allow_two_segments yes)
			(prefer_zone_connections yes)
		)
		(net 1)
	)
	(via
		(at 95.45 140.81)
		(size 0.45)
		(drill 0.1)
		(layers "F.Cu" "B.Cu")
		(remove_unused_layers yes)
		(keep_end_layers yes)
		(zone_layer_connections "In1.Cu" "In4.Cu" "In6.Cu")
		(teardrops
			(best_length_ratio 0.4)
			(max_length 1)
			(best_width_ratio 0.9)
			(max_width 2)
			(curved_edges yes)
			(filter_ratio 0.9)
			(enabled yes)
			(allow_two_segments yes)
			(prefer_zone_connections yes)
		)
		(net 1)
	)
	(via
		(at 240.95 90.81)
		(size 0.45)
		(drill 0.1)
		(layers "F.Cu" "B.Cu")
		(remove_unused_layers yes)
		(keep_end_layers yes)
		(zone_layer_connections "In1.Cu" "In4.Cu" "In6.Cu")
		(teardrops
			(best_length_ratio 0.4)
			(max_length 1)
			(best_width_ratio 0.9)
			(max_width 2)
			(curved_edges yes)
			(filter_ratio 0.9)
			(enabled yes)
			(allow_two_segments yes)
			(prefer_zone_connections yes)
		)
		(net 1)
	)
	(via
		(at 118.45 95.31)
		(size 0.45)
		(drill 0.1)
		(layers "F.Cu" "B.Cu")
		(remove_unused_layers yes)
		(keep_end_layers yes)
		(zone_layer_connections "In1.Cu" "In4.Cu" "In6.Cu")
		(teardrops
			(best_length_ratio 0.4)
			(max_length 1)
			(best_width_ratio 0.9)
			(max_width 2)
			(curved_edges yes)
			(filter_ratio 0.9)
			(enabled yes)
			(allow_two_segments yes)
			(prefer_zone_connections yes)
		)
		(net 1)
	)
	(via
		(at 128.45 162.81)
		(size 0.45)
		(drill 0.1)
		(layers "F.Cu" "B.Cu")
		(remove_unused_layers yes)
		(keep_end_layers yes)
		(zone_layer_connections "In1.Cu" "In4.Cu" "In6.Cu")
		(teardrops
			(best_length_ratio 0.4)
			(max_length 1)
			(best_width_ratio 0.9)
			(max_width 2)
			(curved_edges yes)
			(filter_ratio 0.9)
			(enabled yes)
			(allow_two_segments yes)
			(prefer_zone_connections yes)
		)
		(net 1)
	)
	(via
		(at 253.45 118.81)
		(size 0.45)
		(drill 0.1)
		(layers "F.Cu" "B.Cu")
		(remove_unused_layers yes)
		(keep_end_layers yes)
		(zone_layer_connections "In1.Cu" "In4.Cu" "In6.Cu")
		(teardrops
			(best_length_ratio 0.4)
			(max_length 1)
			(best_width_ratio 0.9)
			(max_width 2)
			(curved_edges yes)
			(filter_ratio 0.9)
			(enabled yes)
			(allow_two_segments yes)
			(prefer_zone_connections yes)
		)
		(net 1)
	)
	(via
		(at 220.6 159.2)
		(size 0.45)
		(drill 0.1)
		(layers "F.Cu" "B.Cu")
		(teardrops
			(best_length_ratio 0.4)
			(max_length 1)
			(best_width_ratio 0.9)
			(max_width 2)
			(curved_edges yes)
			(filter_ratio 0.9)
			(enabled yes)
			(allow_two_segments yes)
			(prefer_zone_connections yes)
		)
		(net 1)
	)
	(via
		(at 306.65 154.31)
		(size 0.45)
		(drill 0.1)
		(layers "F.Cu" "B.Cu")
		(remove_unused_layers yes)
		(keep_end_layers yes)
		(zone_layer_connections "In1.Cu" "In4.Cu" "In6.Cu")
		(teardrops
			(best_length_ratio 0.4)
			(max_length 1)
			(best_width_ratio 0.9)
			(max_width 2)
			(curved_edges yes)
			(filter_ratio 0.9)
			(enabled yes)
			(allow_two_segments yes)
			(prefer_zone_connections yes)
		)
		(net 1)
	)
	(via
		(at 95.45 132.81)
		(size 0.45)
		(drill 0.1)
		(layers "F.Cu" "B.Cu")
		(remove_unused_layers yes)
		(keep_end_layers yes)
		(zone_layer_connections "In1.Cu" "In4.Cu" "In6.Cu")
		(teardrops
			(best_length_ratio 0.4)
			(max_length 1)
			(best_width_ratio 0.9)
			(max_width 2)
			(curved_edges yes)
			(filter_ratio 0.9)
			(enabled yes)
			(allow_two_segments yes)
			(prefer_zone_connections yes)
		)
		(net 1)
	)
	(via
		(at 109.95 72.81)
		(size 0.45)
		(drill 0.1)
		(layers "F.Cu" "B.Cu")
		(remove_unused_layers yes)
		(keep_end_layers yes)
		(zone_layer_connections "In1.Cu" "In4.Cu" "In6.Cu")
		(teardrops
			(best_length_ratio 0.4)
			(max_length 1)
			(best_width_ratio 0.9)
			(max_width 2)
			(curved_edges yes)
			(filter_ratio 0.9)
			(enabled yes)
			(allow_two_segments yes)
			(prefer_zone_connections yes)
		)
		(net 1)
	)
	(via
		(at 202.6 164.85)
		(size 0.45)
		(drill 0.1)
		(layers "F.Cu" "B.Cu")
		(teardrops
			(best_length_ratio 0.4)
			(max_length 1)
			(best_width_ratio 0.9)
			(max_width 2)
			(curved_edges yes)
			(filter_ratio 0.9)
			(enabled yes)
			(allow_two_segments yes)
			(prefer_zone_connections yes)
		)
		(net 1)
	)
	(via
		(at 306.95 170.81)
		(size 0.45)
		(drill 0.1)
		(layers "F.Cu" "B.Cu")
		(remove_unused_layers yes)
		(keep_end_layers yes)
		(zone_layer_connections "In1.Cu" "In4.Cu" "In6.Cu")
		(teardrops
			(best_length_ratio 0.4)
			(max_length 1)
			(best_width_ratio 0.9)
			(max_width 2)
			(curved_edges yes)
			(filter_ratio 0.9)
			(enabled yes)
			(allow_two_segments yes)
			(prefer_zone_connections yes)
		)
		(net 1)
	)
	(via
		(at 307.518 83.287)
		(size 0.45)
		(drill 0.1)
		(layers "F.Cu" "B.Cu")
		(remove_unused_layers yes)
		(keep_end_layers yes)
		(zone_layer_connections "In1.Cu" "In4.Cu" "In6.Cu")
		(teardrops
			(best_length_ratio 0.4)
			(max_length 1)
			(best_width_ratio 0.9)
			(max_width 2)
			(curved_edges yes)
			(filter_ratio 0.9)
			(enabled yes)
			(allow_two_segments yes)
			(prefer_zone_connections yes)
		)
		(net 1)
	)
	(via
		(at 315.95 77.31)
		(size 0.45)
		(drill 0.1)
		(layers "F.Cu" "B.Cu")
		(remove_unused_layers yes)
		(keep_end_layers yes)
		(zone_layer_connections "In1.Cu" "In4.Cu" "In6.Cu")
		(teardrops
			(best_length_ratio 0.4)
			(max_length 1)
			(best_width_ratio 0.9)
			(max_width 2)
			(curved_edges yes)
			(filter_ratio 0.9)
			(enabled yes)
			(allow_two_segments yes)
			(prefer_zone_connections yes)
		)
		(net 1)
	)
	(via
		(at 217.05 164.3)
		(size 0.45)
		(drill 0.1)
		(layers "F.Cu" "B.Cu")
		(teardrops
			(best_length_ratio 0.4)
			(max_length 1)
			(best_width_ratio 0.9)
			(max_width 2)
			(curved_edges yes)
			(filter_ratio 0.9)
			(enabled yes)
			(allow_two_segments yes)
			(prefer_zone_connections yes)
		)
		(net 1)
	)
	(via
		(at 197.45 97.31)
		(size 0.45)
		(drill 0.1)
		(layers "F.Cu" "B.Cu")
		(remove_unused_layers yes)
		(keep_end_layers yes)
		(zone_layer_connections "In1.Cu" "In4.Cu" "In6.Cu")
		(teardrops
			(best_length_ratio 0.4)
			(max_length 1)
			(best_width_ratio 0.9)
			(max_width 2)
			(curved_edges yes)
			(filter_ratio 0.9)
			(enabled yes)
			(allow_two_segments yes)
			(prefer_zone_connections yes)
		)
		(net 1)
	)
	(via
		(at 265.95 166.41)
		(size 0.45)
		(drill 0.1)
		(layers "F.Cu" "B.Cu")
		(remove_unused_layers yes)
		(keep_end_layers yes)
		(zone_layer_connections "In1.Cu" "In4.Cu" "In6.Cu")
		(teardrops
			(best_length_ratio 0.4)
			(max_length 1)
			(best_width_ratio 0.9)
			(max_width 2)
			(curved_edges yes)
			(filter_ratio 0.9)
			(enabled yes)
			(allow_two_segments yes)
			(prefer_zone_connections yes)
		)
		(net 1)
	)
	(via
		(at 99.45 126.81)
		(size 0.45)
		(drill 0.1)
		(layers "F.Cu" "B.Cu")
		(remove_unused_layers yes)
		(keep_end_layers yes)
		(zone_layer_connections "In1.Cu" "In4.Cu" "In6.Cu")
		(teardrops
			(best_length_ratio 0.4)
			(max_length 1)
			(best_width_ratio 0.9)
			(max_width 2)
			(curved_edges yes)
			(filter_ratio 0.9)
			(enabled yes)
			(allow_two_segments yes)
			(prefer_zone_connections yes)
		)
		(net 1)
	)
	(via
		(at 309.257 155.76)
		(size 0.45)
		(drill 0.1)
		(layers "F.Cu" "B.Cu")
		(remove_unused_layers yes)
		(keep_end_layers yes)
		(zone_layer_connections "In1.Cu" "In4.Cu" "In6.Cu")
		(teardrops
			(best_length_ratio 0.4)
			(max_length 1)
			(best_width_ratio 0.9)
			(max_width 2)
			(curved_edges yes)
			(filter_ratio 0.9)
			(enabled yes)
			(allow_two_segments yes)
			(prefer_zone_connections yes)
		)
		(net 1)
	)
	(via
		(at 96.95 77.81)
		(size 0.45)
		(drill 0.1)
		(layers "F.Cu" "B.Cu")
		(remove_unused_layers yes)
		(keep_end_layers yes)
		(zone_layer_connections "In1.Cu" "In4.Cu" "In6.Cu")
		(teardrops
			(best_length_ratio 0.4)
			(max_length 1)
			(best_width_ratio 0.9)
			(max_width 2)
			(curved_edges yes)
			(filter_ratio 0.9)
			(enabled yes)
			(allow_two_segments yes)
			(prefer_zone_connections yes)
		)
		(net 1)
	)
	(via
		(at 315.95 86.31)
		(size 0.45)
		(drill 0.1)
		(layers "F.Cu" "B.Cu")
		(remove_unused_layers yes)
		(keep_end_layers yes)
		(zone_layer_connections "In1.Cu" "In4.Cu" "In6.Cu")
		(teardrops
			(best_length_ratio 0.4)
			(max_length 1)
			(best_width_ratio 0.9)
			(max_width 2)
			(curved_edges yes)
			(filter_ratio 0.9)
			(enabled yes)
			(allow_two_segments yes)
			(prefer_zone_connections yes)
		)
		(net 1)
	)
	(via
		(at 263.95 129.31)
		(size 0.45)
		(drill 0.1)
		(layers "F.Cu" "B.Cu")
		(remove_unused_layers yes)
		(keep_end_layers yes)
		(zone_layer_connections "In1.Cu" "In4.Cu" "In6.Cu")
		(teardrops
			(best_length_ratio 0.4)
			(max_length 1)
			(best_width_ratio 0.9)
			(max_width 2)
			(curved_edges yes)
			(filter_ratio 0.9)
			(enabled yes)
			(allow_two_segments yes)
			(prefer_zone_connections yes)
		)
		(net 1)
	)
	(via
		(at 107.45 85.81)
		(size 0.45)
		(drill 0.1)
		(layers "F.Cu" "B.Cu")
		(remove_unused_layers yes)
		(keep_end_layers yes)
		(zone_layer_connections "In1.Cu" "In4.Cu" "In6.Cu")
		(teardrops
			(best_length_ratio 0.4)
			(max_length 1)
			(best_width_ratio 0.9)
			(max_width 2)
			(curved_edges yes)
			(filter_ratio 0.9)
			(enabled yes)
			(allow_two_segments yes)
			(prefer_zone_connections yes)
		)
		(net 1)
	)
	(via
		(at 263.95 112.81)
		(size 0.45)
		(drill 0.1)
		(layers "F.Cu" "B.Cu")
		(remove_unused_layers yes)
		(keep_end_layers yes)
		(zone_layer_connections "In1.Cu" "In4.Cu" "In6.Cu")
		(teardrops
			(best_length_ratio 0.4)
			(max_length 1)
			(best_width_ratio 0.9)
			(max_width 2)
			(curved_edges yes)
			(filter_ratio 0.9)
			(enabled yes)
			(allow_two_segments yes)
			(prefer_zone_connections yes)
		)
		(net 1)
	)
	(via
		(at 199.95 90.31)
		(size 0.45)
		(drill 0.1)
		(layers "F.Cu" "B.Cu")
		(remove_unused_layers yes)
		(keep_end_layers yes)
		(zone_layer_connections "In1.Cu" "In4.Cu" "In6.Cu")
		(teardrops
			(best_length_ratio 0.4)
			(max_length 1)
			(best_width_ratio 0.9)
			(max_width 2)
			(curved_edges yes)
			(filter_ratio 0.9)
			(enabled yes)
			(allow_two_segments yes)
			(prefer_zone_connections yes)
		)
		(net 1)
	)
	(via
		(at 121.95 153.81)
		(size 0.45)
		(drill 0.1)
		(layers "F.Cu" "B.Cu")
		(remove_unused_layers yes)
		(keep_end_layers yes)
		(zone_layer_connections "In1.Cu" "In4.Cu" "In6.Cu")
		(teardrops
			(best_length_ratio 0.4)
			(max_length 1)
			(best_width_ratio 0.9)
			(max_width 2)
			(curved_edges yes)
			(filter_ratio 0.9)
			(enabled yes)
			(allow_two_segments yes)
			(prefer_zone_connections yes)
		)
		(net 1)
	)
	(via
		(at 126.95 157.81)
		(size 0.45)
		(drill 0.1)
		(layers "F.Cu" "B.Cu")
		(remove_unused_layers yes)
		(keep_end_layers yes)
		(zone_layer_connections "In1.Cu" "In4.Cu" "In6.Cu")
		(teardrops
			(best_length_ratio 0.4)
			(max_length 1)
			(best_width_ratio 0.9)
			(max_width 2)
			(curved_edges yes)
			(filter_ratio 0.9)
			(enabled yes)
			(allow_two_segments yes)
			(prefer_zone_connections yes)
		)
		(net 1)
	)
	(via
		(at 177.18 92.86)
		(size 0.45)
		(drill 0.1)
		(layers "F.Cu" "B.Cu")
		(remove_unused_layers yes)
		(keep_end_layers yes)
		(zone_layer_connections "In1.Cu" "In4.Cu" "In6.Cu")
		(teardrops
			(best_length_ratio 0.4)
			(max_length 1)
			(best_width_ratio 0.9)
			(max_width 2)
			(curved_edges yes)
			(filter_ratio 0.9)
			(enabled yes)
			(allow_two_segments yes)
			(prefer_zone_connections yes)
		)
		(net 1)
	)
	(via
		(at 96.45 143.81)
		(size 0.45)
		(drill 0.1)
		(layers "F.Cu" "B.Cu")
		(remove_unused_layers yes)
		(keep_end_layers yes)
		(zone_layer_connections "In1.Cu" "In4.Cu" "In6.Cu")
		(teardrops
			(best_length_ratio 0.4)
			(max_length 1)
			(best_width_ratio 0.9)
			(max_width 2)
			(curved_edges yes)
			(filter_ratio 0.9)
			(enabled yes)
			(allow_two_segments yes)
			(prefer_zone_connections yes)
		)
		(net 1)
	)
	(via
		(at 206.988027 130.706208)
		(size 0.45)
		(drill 0.1)
		(layers "F.Cu" "B.Cu")
		(remove_unused_layers yes)
		(keep_end_layers yes)
		(zone_layer_connections "In1.Cu" "In4.Cu" "In6.Cu")
		(teardrops
			(best_length_ratio 0.4)
			(max_length 1)
			(best_width_ratio 0.9)
			(max_width 2)
			(curved_edges yes)
			(filter_ratio 0.9)
			(enabled yes)
			(allow_two_segments yes)
			(prefer_zone_connections yes)
		)
		(net 1)
	)
	(via
		(at 120.35 160.96)
		(size 0.45)
		(drill 0.1)
		(layers "F.Cu" "B.Cu")
		(remove_unused_layers yes)
		(keep_end_layers yes)
		(zone_layer_connections "In1.Cu" "In4.Cu" "In6.Cu")
		(teardrops
			(best_length_ratio 0.4)
			(max_length 1)
			(best_width_ratio 0.9)
			(max_width 2)
			(curved_edges yes)
			(filter_ratio 0.9)
			(enabled yes)
			(allow_two_segments yes)
			(prefer_zone_connections yes)
		)
		(net 1)
	)
	(via
		(at 127.45 89.81)
		(size 0.45)
		(drill 0.1)
		(layers "F.Cu" "B.Cu")
		(remove_unused_layers yes)
		(keep_end_layers yes)
		(zone_layer_connections "In1.Cu" "In4.Cu" "In6.Cu")
		(teardrops
			(best_length_ratio 0.4)
			(max_length 1)
			(best_width_ratio 0.9)
			(max_width 2)
			(curved_edges yes)
			(filter_ratio 0.9)
			(enabled yes)
			(allow_two_segments yes)
			(prefer_zone_connections yes)
		)
		(net 1)
	)
	(via
		(at 292.95 111.31)
		(size 0.45)
		(drill 0.1)
		(layers "F.Cu" "B.Cu")
		(remove_unused_layers yes)
		(keep_end_layers yes)
		(zone_layer_connections "In1.Cu" "In4.Cu" "In6.Cu")
		(teardrops
			(best_length_ratio 0.4)
			(max_length 1)
			(best_width_ratio 0.9)
			(max_width 2)
			(curved_edges yes)
			(filter_ratio 0.9)
			(enabled yes)
			(allow_two_segments yes)
			(prefer_zone_connections yes)
		)
		(net 1)
	)
	(via
		(at 207.65 166.35)
		(size 0.45)
		(drill 0.1)
		(layers "F.Cu" "B.Cu")
		(teardrops
			(best_length_ratio 0.4)
			(max_length 1)
			(best_width_ratio 0.9)
			(max_width 2)
			(curved_edges yes)
			(filter_ratio 0.9)
			(enabled yes)
			(allow_two_segments yes)
			(prefer_zone_connections yes)
		)
		(net 1)
	)
	(via
		(at 144.45 90.31)
		(size 0.45)
		(drill 0.1)
		(layers "F.Cu" "B.Cu")
		(remove_unused_layers yes)
		(keep_end_layers yes)
		(zone_layer_connections "In1.Cu" "In4.Cu" "In6.Cu")
		(teardrops
			(best_length_ratio 0.4)
			(max_length 1)
			(best_width_ratio 0.9)
			(max_width 2)
			(curved_edges yes)
			(filter_ratio 0.9)
			(enabled yes)
			(allow_two_segments yes)
			(prefer_zone_connections yes)
		)
		(net 1)
	)
	(via
		(at 212 167.5)
		(size 0.45)
		(drill 0.1)
		(layers "F.Cu" "B.Cu")
		(teardrops
			(best_length_ratio 0.4)
			(max_length 1)
			(best_width_ratio 0.9)
			(max_width 2)
			(curved_edges yes)
			(filter_ratio 0.9)
			(enabled yes)
			(allow_two_segments yes)
			(prefer_zone_connections yes)
		)
		(net 1)
	)
	(via
		(at 127.86 147.625077)
		(size 0.45)
		(drill 0.1)
		(layers "F.Cu" "B.Cu")
		(remove_unused_layers yes)
		(keep_end_layers yes)
		(zone_layer_connections "In1.Cu" "In4.Cu" "In6.Cu")
		(teardrops
			(best_length_ratio 0.4)
			(max_length 1)
			(best_width_ratio 0.9)
			(max_width 2)
			(curved_edges yes)
			(filter_ratio 0.9)
			(enabled yes)
			(allow_two_segments yes)
			(prefer_zone_connections yes)
		)
		(net 1)
	)
	(via
		(at 125.45 168.31)
		(size 0.45)
		(drill 0.1)
		(layers "F.Cu" "B.Cu")
		(remove_unused_layers yes)
		(keep_end_layers yes)
		(zone_layer_connections "In1.Cu" "In4.Cu" "In6.Cu")
		(teardrops
			(best_length_ratio 0.4)
			(max_length 1)
			(best_width_ratio 0.9)
			(max_width 2)
			(curved_edges yes)
			(filter_ratio 0.9)
			(enabled yes)
			(allow_two_segments yes)
			(prefer_zone_connections yes)
		)
		(net 1)
	)
	(via
		(at 225.4 160.6)
		(size 0.45)
		(drill 0.1)
		(layers "F.Cu" "B.Cu")
		(teardrops
			(best_length_ratio 0.4)
			(max_length 1)
			(best_width_ratio 0.9)
			(max_width 2)
			(curved_edges yes)
			(filter_ratio 0.9)
			(enabled yes)
			(allow_two_segments yes)
			(prefer_zone_connections yes)
		)
		(net 1)
	)
	(via
		(at 133.29 146.81)
		(size 0.45)
		(drill 0.1)
		(layers "F.Cu" "B.Cu")
		(remove_unused_layers yes)
		(keep_end_layers yes)
		(zone_layer_connections "In1.Cu" "In4.Cu" "In6.Cu")
		(teardrops
			(best_length_ratio 0.4)
			(max_length 1)
			(best_width_ratio 0.9)
			(max_width 2)
			(curved_edges yes)
			(filter_ratio 0.9)
			(enabled yes)
			(allow_two_segments yes)
			(prefer_zone_connections yes)
		)
		(net 1)
	)
	(via
		(at 147.45 136.86)
		(size 0.45)
		(drill 0.1)
		(layers "F.Cu" "B.Cu")
		(remove_unused_layers yes)
		(keep_end_layers yes)
		(zone_layer_connections "In1.Cu" "In4.Cu" "In6.Cu")
		(teardrops
			(best_length_ratio 0.4)
			(max_length 1)
			(best_width_ratio 0.9)
			(max_width 2)
			(curved_edges yes)
			(filter_ratio 0.9)
			(enabled yes)
			(allow_two_segments yes)
			(prefer_zone_connections yes)
		)
		(net 1)
	)
	(via
		(at 163.95 90.31)
		(size 0.45)
		(drill 0.1)
		(layers "F.Cu" "B.Cu")
		(remove_unused_layers yes)
		(keep_end_layers yes)
		(zone_layer_connections "In1.Cu" "In4.Cu" "In6.Cu")
		(teardrops
			(best_length_ratio 0.4)
			(max_length 1)
			(best_width_ratio 0.9)
			(max_width 2)
			(curved_edges yes)
			(filter_ratio 0.9)
			(enabled yes)
			(allow_two_segments yes)
			(prefer_zone_connections yes)
		)
		(net 1)
	)
	(via
		(at 260.95 123.31)
		(size 0.45)
		(drill 0.1)
		(layers "F.Cu" "B.Cu")
		(remove_unused_layers yes)
		(keep_end_layers yes)
		(zone_layer_connections "In1.Cu" "In4.Cu" "In6.Cu")
		(teardrops
			(best_length_ratio 0.4)
			(max_length 1)
			(best_width_ratio 0.9)
			(max_width 2)
			(curved_edges yes)
			(filter_ratio 0.9)
			(enabled yes)
			(allow_two_segments yes)
			(prefer_zone_connections yes)
		)
		(net 1)
	)
	(via
		(at 197.8 165.9)
		(size 0.45)
		(drill 0.1)
		(layers "F.Cu" "B.Cu")
		(teardrops
			(best_length_ratio 0.4)
			(max_length 1)
			(best_width_ratio 0.9)
			(max_width 2)
			(curved_edges yes)
			(filter_ratio 0.9)
			(enabled yes)
			(allow_two_segments yes)
			(prefer_zone_connections yes)
		)
		(net 1)
	)
	(via
		(at 238.45 115.81)
		(size 0.45)
		(drill 0.1)
		(layers "F.Cu" "B.Cu")
		(remove_unused_layers yes)
		(keep_end_layers yes)
		(zone_layer_connections "In1.Cu" "In4.Cu" "In6.Cu")
		(teardrops
			(best_length_ratio 0.4)
			(max_length 1)
			(best_width_ratio 0.9)
			(max_width 2)
			(curved_edges yes)
			(filter_ratio 0.9)
			(enabled yes)
			(allow_two_segments yes)
			(prefer_zone_connections yes)
		)
		(net 1)
	)
	(via
		(at 296.45 108.31)
		(size 0.45)
		(drill 0.1)
		(layers "F.Cu" "B.Cu")
		(remove_unused_layers yes)
		(keep_end_layers yes)
		(zone_layer_connections "In1.Cu" "In4.Cu" "In6.Cu")
		(teardrops
			(best_length_ratio 0.4)
			(max_length 1)
			(best_width_ratio 0.9)
			(max_width 2)
			(curved_edges yes)
			(filter_ratio 0.9)
			(enabled yes)
			(allow_two_segments yes)
			(prefer_zone_connections yes)
		)
		(net 1)
	)
	(segment
		(start 308.824999 105.335001)
		(end 309.05 105.11)
		(width 0.125)
		(layer "B.Cu")
		(net 1)
	)
	(segment
		(start 99.46 162.1)
		(end 100.21 162.1)
		(width 0.3)
		(layer "B.Cu")
		(net 1)
	)
	(segment
		(start 115.809999 76.475)
		(end 115.809999 77.709999)
		(width 0.5)
		(layer "B.Cu")
		(net 1)
	)
	(segment
		(start 152.5 160.71)
		(end 152.25 160.71)
		(width 0.3)
		(layer "B.Cu")
		(net 1)
	)
	(segment
		(start 309.05 105.11)
		(end 311.414999 105.11)
		(width 0.125)
		(layer "B.Cu")
		(net 1)
	)
	(segment
		(start 198.942533 133.432467)
		(end 199.35 133.025)
		(width 0.125)
		(layer "B.Cu")
		(net 1)
	)
	(segment
		(start 105.155 165.61)
		(end 104.383 165.61)
		(width 0.125)
		(layer "B.Cu")
		(net 1)
	)
	(segment
		(start 319.45 158.51)
		(end 317.7 158.51)
		(width 0.55)
		(layer "B.Cu")
		(net 1)
	)
	(segment
		(start 176.2 111.36)
		(end 177.18 111.36)
		(width 0.3)
		(layer "B.Cu")
		(net 1)
	)
	(segment
		(start 142.397 149.738)
		(end 143.357 148.778)
		(width 0.2)
		(layer "B.Cu")
		(net 1)
	)
	(segment
		(start 101.325 105.365)
		(end 102.275 105.365)
		(width 0.2)
		(layer "B.Cu")
		(net 1)
	)
	(segment
		(start 98.608352 159.100249)
		(end 98.260083 159.100249)
		(width 0.4)
		(layer "B.Cu")
		(net 1)
	)
	(segment
		(start 101.8 124.554)
		(end 100.89 125.464)
		(width 0.3)
		(layer "B.Cu")
		(net 1)
	)
	(segment
		(start 176.2 100.86)
		(end 177.18 100.86)
		(width 0.3)
		(layer "B.Cu")
		(net 1)
	)
	(segment
		(start 112.875 103.825)
		(end 112.89 103.81)
		(width 0.2)
		(layer "B.Cu")
		(net 1)
	)
	(segment
		(start 125.61 138.06)
		(end 125.61 142.06)
		(width 0.125)
		(layer "B.Cu")
		(net 1)
	)
	(segment
		(start 124.88 96.86)
		(end 123.88 95.86)
		(width 0.125)
		(layer "B.Cu")
		(net 1)
	)
	(segment
		(start 124.841744 142.510263)
		(end 124.841744 142.278256)
		(width 0.125)
		(layer "B.Cu")
		(net 1)
	)
	(segment
		(start 314.365 160.91)
		(end 315.137 160.91)
		(width 0.2)
		(layer "B.Cu")
		(net 1)
	)
	(segment
		(start 127.69 135.86)
		(end 127.89 136.06)
		(width 0.125)
		(layer "B.Cu")
		(net 1)
	)
	(segment
		(start 124.88 99.86)
		(end 124.88 96.86)
		(width 0.125)
		(layer "B.Cu")
		(net 1)
	)
	(segment
		(start 99.458 160.6)
		(end 100.21 160.6)
		(width 0.3)
		(layer "B.Cu")
		(net 1)
	)
	(segment
		(start 100.553 105.365)
		(end 101.325 105.365)
		(width 0.2)
		(layer "B.Cu")
		(net 1)
	)
	(segment
		(start 146.05 136.06)
		(end 146.47 136.06)
		(width 0.125)
		(layer "B.Cu")
		(net 1)
	)
	(segment
		(start 112.963 146.611)
		(end 114.96 146.611)
		(width 0.125)
		(layer "B.Cu")
		(net 1)
	)
	(segment
		(start 311.424999 120.91)
		(end 311.474999 120.86)
		(width 0.125)
		(layer "B.Cu")
		(net 1)
	)
	(segment
		(start 252.50071 73.485)
		(end 252.50071 71.869999)
		(width 0.5)
		(layer "B.Cu")
		(net 1)
	)
	(segment
		(start 176.2 94.86)
		(end 177.18 94.86)
		(width 0.3)
		(layer "B.Cu")
		(net 1)
	)
	(segment
		(start 154.45 131.443884)
		(end 154.45 131.86)
		(width 0.5)
		(layer "B.Cu")
		(net 1)
	)
	(segment
		(start 266.230709 73.485)
		(end 266.230709 71.869999)
		(width 0.5)
		(layer "B.Cu")
		(net 1)
	)
	(segment
		(start 195.535339 132.231728)
		(end 195.535339 133.645941)
		(width 0.125)
		(layer "B.Cu")
		(net 1)
	)
	(segment
		(start 176.2 105.36)
		(end 177.18 105.36)
		(width 0.3)
		(layer "B.Cu")
		(net 1)
	)
	(segment
		(start 251.92571 74.06)
		(end 252.50071 73.485)
		(width 0.5)
		(layer "B.Cu")
		(net 1)
	)
	(segment
		(start 102.49 167.11)
		(end 103.19 167.11)
		(width 0.3)
		(layer "B.Cu")
		(net 1)
	)
	(segment
		(start 136.29 131.443884)
		(end 136.29 131.86)
		(width 0.5)
		(layer "B.Cu")
		(net 1)
	)
	(segment
		(start 265.655709 74.06)
		(end 266.230709 73.485)
		(width 0.5)
		(layer "B.Cu")
		(net 1)
	)
	(segment
		(start 315.137 165.71)
		(end 319.45 165.71)
		(width 0.2)
		(layer "B.Cu")
		(net 1)
	)
	(segment
		(start 121.4 146.110499)
		(end 120.4 147.110499)
		(width 0.125)
		(layer "B.Cu")
		(net 1)
	)
	(segment
		(start 124.841744 142.278256)
		(end 125.06 142.06)
		(width 0.125)
		(layer "B.Cu")
		(net 1)
	)
	(segment
		(start 101.855 165.605)
		(end 101.35 165.1)
		(width 0.2)
		(layer "B.Cu")
		(net 1)
	)
	(segment
		(start 98.610008 160.601739)
		(end 98.261739 160.601739)
		(width 0.4)
		(layer "B.Cu")
		(net 1)
	)
	(segment
		(start 123.26 137.985)
		(end 122.68 137.405)
		(width 0.3)
		(layer "B.Cu")
		(net 1)
	)
	(segment
		(start 176.2 93.36)
		(end 177.18 93.36)
		(width 0.3)
		(layer "B.Cu")
		(net 1)
	)
	(segment
		(start 314.365 165.71)
		(end 315.137 165.71)
		(width 0.2)
		(layer "B.Cu")
		(net 1)
	)
	(segment
		(start 176.2 110.36)
		(end 177.18 110.36)
		(width 0.3)
		(layer "B.Cu")
		(net 1)
	)
	(segment
		(start 308.824999 121.135001)
		(end 309.05 120.91)
		(width 0.125)
		(layer "B.Cu")
		(net 1)
	)
	(segment
		(start 147.55 169.64)
		(end 147.55 170.31)
		(width 0.125)
		(layer "B.Cu")
		(net 1)
	)
	(segment
		(start 147.45 131.86)
		(end 147.45 131.528)
		(width 0.5)
		(layer "B.Cu")
		(net 1)
	)
	(segment
		(start 143.0449 142.2351)
		(end 143.22 142.06)
		(width 0.125)
		(layer "B.Cu")
		(net 1)
	)
	(segment
		(start 176.2 97.86)
		(end 177.18 97.86)
		(width 0.3)
		(layer "B.Cu")
		(net 1)
	)
	(segment
		(start 125.182 147.8)
		(end 125.182 148.742)
		(width 0.2)
		(layer "B.Cu")
		(net 1)
	)
	(segment
		(start 107.53 157.32)
		(end 107.8 157.32)
		(width 0.3)
		(layer "B.Cu")
		(net 1)
	)
	(segment
		(start 104.383 159.61)
		(end 102.47 159.61)
		(width 0.2)
		(layer "B.Cu")
		(net 1)
	)
	(segment
		(start 129.29 131.86)
		(end 129.29 131.528)
		(width 0.5)
		(layer "B.Cu")
		(net 1)
	)
	(segment
		(start 102.49 162.61)
		(end 103.19 162.61)
		(width 0.3)
		(layer "B.Cu")
		(net 1)
	)
	(segment
		(start 190.27694 138.905049)
		(end 191.116276 138.065713)
		(width 0.125)
		(layer "B.Cu")
		(net 1)
	)
	(segment
		(start 319.45 157.71)
		(end 317.7 157.71)
		(width 0.55)
		(layer "B.Cu")
		(net 1)
	)
	(segment
		(start 99.62 85.46)
		(end 99.6 85.48)
		(width 0.2)
		(layer "B.Cu")
		(net 1)
	)
	(segment
		(start 219.5 166.18)
		(end 219.5 166.8)
		(width 0.2)
		(layer "B.Cu")
		(net 1)
	)
	(segment
		(start 112.89 103.81)
		(end 113.55 103.81)
		(width 0.2)
		(layer "B.Cu")
		(net 1)
	)
	(segment
		(start 145.45 135.86)
		(end 145.85 135.86)
		(width 0.125)
		(layer "B.Cu")
		(net 1)
	)
	(segment
		(start 102.465 165.605)
		(end 101.855 165.605)
		(width 0.2)
		(layer "B.Cu")
		(net 1)
	)
	(segment
		(start 238.770708 73.485)
		(end 238.770708 71.869999)
		(width 0.5)
		(layer "B.Cu")
		(net 1)
	)
	(segment
		(start 98.608195 165.099903)
		(end 98.259926 165.099903)
		(width 0.4)
		(layer "B.Cu")
		(net 1)
	)
	(segment
		(start 101.8 121.96)
		(end 101.8 124.554)
		(width 0.3)
		(layer "B.Cu")
		(net 1)
	)
	(segment
		(start 99.6 85.48)
		(end 99.6 86.084)
		(width 0.2)
		(layer "B.Cu")
		(net 1)
	)
	(segment
		(start 137.55 169.64)
		(end 137.55 170.31)
		(width 0.125)
		(layer "B.Cu")
		(net 1)
	)
	(segment
		(start 105.915 165.61)
		(end 105.925 165.6)
		(width 0.125)
		(layer "B.Cu")
		(net 1)
	)
	(segment
		(start 127.89 136.06)
		(end 128.31 136.06)
		(width 0.125)
		(layer "B.Cu")
		(net 1)
	)
	(segment
		(start 176.2 96.36)
		(end 177.18 96.36)
		(width 0.3)
		(layer "B.Cu")
		(net 1)
	)
	(segment
		(start 105.155 165.61)
		(end 105.915 165.61)
		(width 0.125)
		(layer "B.Cu")
		(net 1)
	)
	(segment
		(start 100.21 157.6)
		(end 99.46 157.6)
		(width 0.3)
		(layer "B.Cu")
		(net 1)
	)
	(segment
		(start 176.2 103.86)
		(end 177.18 103.86)
		(width 0.3)
		(layer "B.Cu")
		(net 1)
	)
	(segment
		(start 141.42 137.985)
		(end 140.84 137.405)
		(width 0.3)
		(layer "B.Cu")
		(net 1)
	)
	(segment
		(start 176.2 99.36)
		(end 177.18 99.36)
		(width 0.3)
		(layer "B.Cu")
		(net 1)
	)
	(segment
		(start 107.3 156.54)
		(end 107.3 157.09)
		(width 0.3)
		(layer "B.Cu")
		(net 1)
	)
	(segment
		(start 102.49 159.61)
		(end 104.383 159.61)
		(width 0.125)
		(layer "B.Cu")
		(net 1)
	)
	(segment
		(start 241.420708 78.135)
		(end 242.140708 78.135)
		(width 0.5)
		(layer "B.Cu")
		(net 1)
	)
	(segment
		(start 176.2 110.86)
		(end 177.18 110.86)
		(width 0.3)
		(layer "B.Cu")
		(net 1)
	)
	(segment
		(start 152.84 160.37)
		(end 152.5 160.71)
		(width 0.3)
		(layer "B.Cu")
		(net 1)
	)
	(segment
		(start 100.21 159.1)
		(end 99.458 159.1)
		(width 0.3)
		(layer "B.Cu")
		(net 1)
	)
	(segment
		(start 176.2 92.86)
		(end 177.18 92.86)
		(width 0.3)
		(layer "B.Cu")
		(net 1)
	)
	(segment
		(start 100.21 163.6)
		(end 99.46 163.6)
		(width 0.3)
		(layer "B.Cu")
		(net 1)
	)
	(segment
		(start 123.88 100.86)
		(end 124.88 99.86)
		(width 0.125)
		(layer "B.Cu")
		(net 1)
	)
	(segment
		(start 127.29 135.86)
		(end 127.69 135.86)
		(width 0.125)
		(layer "B.Cu")
		(net 1)
	)
	(segment
		(start 308.824999 102.634999)
		(end 309.07 102.88)
		(width 0.125)
		(layer "B.Cu")
		(net 1)
	)
	(segment
		(start 104.380002 162.61)
		(end 103.19 162.61)
		(width 0.2)
		(layer "B.Cu")
		(net 1)
	)
	(segment
		(start 315.137 160.91)
		(end 319.45 160.91)
		(width 0.2)
		(layer "B.Cu")
		(net 1)
	)
	(segment
		(start 189.923387 138.551495)
		(end 191.335479 137.139403)
		(width 0.125)
		(layer "B.Cu")
		(net 1)
	)
	(segment
		(start 99.46 165.1)
		(end 100.21 165.1)
		(width 0.3)
		(layer "B.Cu")
		(net 1)
	)
	(segment
		(start 198.942533 133.445477)
		(end 198.942533 133.432467)
		(width 0.125)
		(layer "B.Cu")
		(net 1)
	)
	(segment
		(start 112.963 147.111)
		(end 114.15 147.111)
		(width 0.125)
		(layer "B.Cu")
		(net 1)
	)
	(segment
		(start 99.62 84.46)
		(end 99.6 84.44)
		(width 0.2)
		(layer "B.Cu")
		(net 1)
	)
	(segment
		(start 255.870707 78.135)
		(end 255.150707 78.135)
		(width 0.5)
		(layer "B.Cu")
		(net 1)
	)
	(segment
		(start 105.152002 162.61)
		(end 104.380002 162.61)
		(width 0.2)
		(layer "B.Cu")
		(net 1)
	)
	(segment
		(start 319.45 163.31)
		(end 317.7 163.31)
		(width 0.55)
		(layer "B.Cu")
		(net 1)
	)
	(segment
		(start 319.45 160.91)
		(end 317.7 160.91)
		(width 0.55)
		(layer "B.Cu")
		(net 1)
	)
	(segment
		(start 309.07 102.88)
		(end 309.174999 102.88)
		(width 0.125)
		(layer "B.Cu")
		(net 1)
	)
	(segment
		(start 137.05 169.64)
		(end 137.6 169.64)
		(width 0.125)
		(layer "B.Cu")
		(net 1)
	)
	(segment
		(start 123.013 104.3)
		(end 123.785 104.3)
		(width 0.2)
		(layer "B.Cu")
		(net 1)
	)
	(segment
		(start 137.6 169.64)
		(end 138.05 169.64)
		(width 0.125)
		(layer "B.Cu")
		(net 1)
	)
	(segment
		(start 107.3 157.09)
		(end 107.53 157.32)
		(width 0.3)
		(layer "B.Cu")
		(net 1)
	)
	(segment
		(start 125.06 142.06)
		(end 125.61 142.06)
		(width 0.125)
		(layer "B.Cu")
		(net 1)
	)
	(segment
		(start 114.509999 76.475)
		(end 114.259999 76.725)
		(width 0.5)
		(layer "B.Cu")
		(net 1)
	)
	(segment
		(start 145.85 135.86)
		(end 146.05 136.06)
		(width 0.125)
		(layer "B.Cu")
		(net 1)
	)
	(segment
		(start 147.05 169.64)
		(end 148.05 169.64)
		(width 0.125)
		(layer "B.Cu")
		(net 1)
	)
	(segment
		(start 99.6 84.44)
		(end 99.6 83.81)
		(width 0.2)
		(layer "B.Cu")
		(net 1)
	)
	(segment
		(start 102.49 161.11)
		(end 103.19 161.11)
		(width 0.3)
		(layer "B.Cu")
		(net 1)
	)
	(segment
		(start 176.2 102.36)
		(end 177.18 102.36)
		(width 0.3)
		(layer "B.Cu")
		(net 1)
	)
	(segment
		(start 238.195708 74.06)
		(end 238.770708 73.485)
		(width 0.5)
		(layer "B.Cu")
		(net 1)
	)
	(segment
		(start 195.22598 131.922369)
		(end 195.535339 132.231728)
		(width 0.125)
		(layer "B.Cu")
		(net 1)
	)
	(segment
		(start 319.45 168.11)
		(end 317.7 168.11)
		(width 0.55)
		(layer "B.Cu")
		(net 1)
	)
	(segment
		(start 121.4 145.673)
		(end 121.4 146.110499)
		(width 0.125)
		(layer "B.Cu")
		(net 1)
	)
	(segment
		(start 176.2 106.86)
		(end 177.18 106.86)
		(width 0.3)
		(layer "B.Cu")
		(net 1)
	)
	(segment
		(start 140.84 137.405)
		(end 140.84 137.38)
		(width 0.3)
		(layer "B.Cu")
		(net 1)
	)
	(segment
		(start 311.414999 105.11)
		(end 311.474999 105.05)
		(width 0.125)
		(layer "B.Cu")
		(net 1)
	)
	(segment
		(start 308.824999 121.48)
		(end 308.824999 121.135001)
		(width 0.125)
		(layer "B.Cu")
		(net 1)
	)
	(segment
		(start 308.824999 102.24)
		(end 308.824999 102.634999)
		(width 0.125)
		(layer "B.Cu")
		(net 1)
	)
	(segment
		(start 105.155 159.61)
		(end 104.383 159.61)
		(width 0.125)
		(layer "B.Cu")
		(net 1)
	)
	(segment
		(start 316.35 165.71)
		(end 314.365 165.71)
		(width 0.2)
		(layer "B.Cu")
		(net 1)
	)
	(segment
		(start 122.68 137.405)
		(end 122.68 137.38)
		(width 0.3)
		(layer "B.Cu")
		(net 1)
	)
	(segment
		(start 309.05 120.91)
		(end 311.424999 120.91)
		(width 0.125)
		(layer "B.Cu")
		(net 1)
	)
	(segment
		(start 124.3475 104.3)
		(end 123.785 104.3)
		(width 0.2)
		(layer "B.Cu")
		(net 1)
	)
	(segment
		(start 140.22 138.36)
		(end 140.22 137.94)
		(width 0.125)
		(layer "B.Cu")
		(net 1)
	)
	(segment
		(start 319.45 156.91)
		(end 317.7 156.91)
		(width 0.55)
		(layer "B.Cu")
		(net 1)
	)
	(segment
		(start 143.77 138.06)
		(end 143.77 142.06)
		(width 0.125)
		(layer "B.Cu")
		(net 1)
	)
	(segment
		(start 124.24 149.74)
		(end 125.2 148.78)
		(width 0.2)
		(layer "B.Cu")
		(net 1)
	)
	(segment
		(start 102.275 105.365)
		(end 103.3 105.365)
		(width 0.2)
		(layer "B.Cu")
		(net 1)
	)
	(segment
		(start 140.22 137.94)
		(end 140.78 137.38)
		(width 0.125)
		(layer "B.Cu")
		(net 1)
	)
	(segment
		(start 99.46 166.6)
		(end 100.21 166.6)
		(width 0.3)
		(layer "B.Cu")
		(net 1)
	)
	(segment
		(start 308.824999 105.67)
		(end 308.824999 105.335001)
		(width 0.125)
		(layer "B.Cu")
		(net 1)
	)
	(segment
		(start 140.78 137.38)
		(end 140.84 137.38)
		(width 0.125)
		(layer "B.Cu")
		(net 1)
	)
	(segment
		(start 102.49 165.61)
		(end 104.383 165.61)
		(width 0.125)
		(layer "B.Cu")
		(net 1)
	)
	(segment
		(start 143.22 142.06)
		(end 143.77 142.06)
		(width 0.125)
		(layer "B.Cu")
		(net 1)
	)
	(segment
		(start 143.0449 142.504698)
		(end 143.0449 142.2351)
		(width 0.125)
		(layer "B.Cu")
		(net 1)
	)
	(segment
		(start 121.95 73.64)
		(end 121.5 74.09)
		(width 0.125)
		(layer "F.Cu")
		(net 2)
	)
	(segment
		(start 239.04 78.02)
		(end 240 78.98)
		(width 0.2)
		(layer "F.Cu")
		(net 2)
	)
	(segment
		(start 145.79 168.44)
		(end 145.79 169.38)
		(width 0.125)
		(layer "F.Cu")
		(net 2)
	)
	(segment
		(start 143.48 135.88)
		(end 143.87 135.88)
		(width 0.125)
		(layer "F.Cu")
		(net 2)
	)
	(segment
		(start 309.975 83.959999)
		(end 309.225 83.959999)
		(width 0.3)
		(layer "F.Cu")
		(net 2)
	)
	(segment
		(start 239.000001 78.02)
		(end 239.04 78.02)
		(width 0.2)
		(layer "F.Cu")
		(net 2)
	)
	(segment
		(start 245.192709 78.423)
		(end 245.000709 78.615)
		(width 0.3)
		(layer "F.Cu")
		(net 2)
	)
	(segment
		(start 309.225 83.959999)
		(end 309.017 83.752)
		(width 0.3)
		(layer "F.Cu")
		(net 2)
	)
	(segment
		(start 125.71 135.88)
		(end 125.87 136.04)
		(width 0.125)
		(layer "F.Cu")
		(net 2)
	)
	(segment
		(start 147.0805 71.808499)
		(end 146.0755 71.808499)
		(width 0.3)
		(layer "F.Cu")
		(net 2)
	)
	(segment
		(start 196.447154 136.680491)
		(end 195.704692 135.938029)
		(width 0.5)
		(layer "F.Cu")
		(net 2)
	)
	(segment
		(start 212.63 129.12)
		(end 212.825 128.925)
		(width 0.2)
		(layer "F.Cu")
		(net 2)
	)
	(segment
		(start 212.833 129.323)
		(end 213.203 129.323)
		(width 0.2)
		(layer "F.Cu")
		(net 2)
	)
	(segment
		(start 178.85 159.55)
		(end 176.7 159.55)
		(width 0.125)
		(layer "F.Cu")
		(net 2)
	)
	(segment
		(start 264.581708 78.423)
		(end 260.282708 78.423)
		(width 0.125)
		(layer "F.Cu")
		(net 2)
	)
	(segment
		(start 145.79 169.38)
		(end 146.05 169.64)
		(width 0.125)
		(layer "F.Cu")
		(net 2)
	)
	(segment
		(start 144.03 136.04)
		(end 144.03 138.03)
		(width 0.125)
		(layer "F.Cu")
		(net 2)
	)
	(segment
		(start 190.735145 135.209709)
		(end 190.735145 135.20688)
		(width 0.5)
		(layer "F.Cu")
		(net 2)
	)
	(segment
		(start 192.682305 129.153483)
		(end 193.389411 129.860588)
		(width 0.125)
		(layer "F.Cu")
		(net 2)
	)
	(segment
		(start 212.833 127.324)
		(end 213.203 127.324)
		(width 0.2)
		(layer "F.Cu")
		(net 2)
	)
	(segment
		(start 121.5 74.09)
		(end 121.338 74.252)
		(width 0.3)
		(layer "F.Cu")
		(net 2)
	)
	(segment
		(start 120.4 148.901)
		(end 120.4 149.9)
		(width 0.5)
		(layer "F.Cu")
		(net 2)
	)
	(segment
		(start 193.916419 132.025607)
		(end 194.61999 132.729178)
		(width 0.5)
		(layer "F.Cu")
		(net 2)
	)
	(segment
		(start 191.795805 134.14622)
		(end 192.46685 134.817264)
		(width 0.5)
		(layer "F.Cu")
		(net 2)
	)
	(segment
		(start 196.801414 134.912017)
		(end 197.507814 135.618416)
		(width 0.5)
		(layer "F.Cu")
		(net 2)
	)
	(segment
		(start 218.76 127.324)
		(end 218.154 127.324)
		(width 0.2)
		(layer "F.Cu")
		(net 2)
	)
	(segment
		(start 189.674485 136.270369)
		(end 190.380885 136.976769)
		(width 0.5)
		(layer "F.Cu")
		(net 2)
	)
	(segment
		(start 304 103.56)
		(end 303.477 104.083)
		(width 0.125)
		(layer "F.Cu")
		(net 2)
	)
	(segment
		(start 215.88 131.570001)
		(end 215.88 131.2)
		(width 0.2)
		(layer "F.Cu")
		(net 2)
	)
	(segment
		(start 237.121707 78.423)
		(end 232.822707 78.423)
		(width 0.2)
		(layer "F.Cu")
		(net 2)
	)
	(segment
		(start 114.4 148.901)
		(end 114.4 149.901)
		(width 0.5)
		(layer "F.Cu")
		(net 2)
	)
	(segment
		(start 147.0805 89.3085)
		(end 146.0755 89.3085)
		(width 0.3)
		(layer "F.Cu")
		(net 2)
	)
	(segment
		(start 117.4 148.901)
		(end 117.4 149.901)
		(width 0.5)
		(layer "F.Cu")
		(net 2)
	)
	(segment
		(start 215.88 125.680623)
		(end 215.986207 125.574416)
		(width 0.2)
		(layer "F.Cu")
		(net 2)
	)
	(segment
		(start 215.677 131.773)
		(end 215.482 131.578)
		(width 0.2)
		(layer "F.Cu")
		(net 2)
	)
	(segment
		(start 115.9 144.822)
		(end 115.902 144.82)
		(width 0.5)
		(layer "F.Cu")
		(net 2)
	)
	(segment
		(start 237.977 78.423)
		(end 238.38 78.02)
		(width 0.2)
		(layer "F.Cu")
		(net 2)
	)
	(segment
		(start 143.19 149.925)
		(end 143.377 149.738)
		(width 0.3)
		(layer "F.Cu")
		(net 2)
	)
	(segment
		(start 246.552709 78.423)
		(end 245.192709 78.423)
		(width 0.3)
		(layer "F.Cu")
		(net 2)
	)
	(segment
		(start 115.882 144.84)
		(end 115.902 144.82)
		(width 0.5)
		(layer "F.Cu")
		(net 2)
	)
	(segment
		(start 310.174999 83.76)
		(end 309.975 83.959999)
		(width 0.3)
		(layer "F.Cu")
		(net 2)
	)
	(segment
		(start 193.619434 138.093997)
		(end 194.32654 138.801104)
		(width 0.5)
		(layer "F.Cu")
		(net 2)
	)
	(segment
		(start 260.282708 78.423)
		(end 258.872708 78.423)
		(width 0.3)
		(layer "F.Cu")
		(net 2)
	)
	(segment
		(start 218.727 130.326)
		(end 218.532 130.521)
		(width 0.2)
		(layer "F.Cu")
		(net 2)
	)
	(segment
		(start 194.680094 137.033337)
		(end 195.387201 137.740444)
		(width 0.5)
		(layer "F.Cu")
		(net 2)
	)
	(segment
		(start 125.87 136.04)
		(end 125.87 138.03)
		(width 0.125)
		(layer "F.Cu")
		(net 2)
	)
	(segment
		(start 120.4 149.9)
		(end 120.399 149.901)
		(width 0.125)
		(layer "F.Cu")
		(net 2)
	)
	(segment
		(start 215.482 131.578)
		(end 215.482001 131.2)
		(width 0.2)
		(layer "F.Cu")
		(net 2)
	)
	(segment
		(start 147.0805 71.308499)
		(end 146.0755 71.3085)
		(width 0.3)
		(layer "F.Cu")
		(net 2)
	)
	(segment
		(start 298.2 84.49)
		(end 299.2 84.49)
		(width 0.125)
		(layer "F.Cu")
		(net 2)
	)
	(segment
		(start 303.15 100.64)
		(end 303.83 100.64)
		(width 0.125)
		(layer "F.Cu")
		(net 2)
	)
	(segment
		(start 113.38 147.86)
		(end 113.38 148.86)
		(width 0.125)
		(layer "F.Cu")
		(net 2)
	)
	(segment
		(start 220.21 124.9)
		(end 220.21 123.9)
		(width 0.125)
		(layer "F.Cu")
		(net 2)
	)
	(segment
		(start 309.504002 77.483)
		(end 308.998 77.483)
		(width 0.2)
		(layer "F.Cu")
		(net 2)
	)
	(segment
		(start 262.83 93.337)
		(end 261.999999 93.337)
		(width 0.3)
		(layer "F.Cu")
		(net 2)
	)
	(segment
		(start 308.755 76.362002)
		(end 308.755 76.742002)
		(width 0.2)
		(layer "F.Cu")
		(net 2)
	)
	(segment
		(start 111.67 134.56)
		(end 111.67 134.99)
		(width 0.2)
		(layer "F.Cu")
		(net 2)
	)
	(segment
		(start 237.121707 78.423)
		(end 237.977 78.423)
		(width 0.2)
		(layer "F.Cu")
		(net 2)
	)
	(segment
		(start 138.53 169.64)
		(end 137.92 169.03)
		(width 0.125)
		(layer "F.Cu")
		(net 2)
	)
	(segment
		(start 309.017 83.752)
		(end 309.017 83.287)
		(width 0.3)
		(layer "F.Cu")
		(net 2)
	)
	(segment
		(start 232.822707 78.423)
		(end 231.442707 78.423)
		(width 0.3)
		(layer "F.Cu")
		(net 2)
	)
	(segment
		(start 138.25 157.11)
		(end 139.15 157.11)
		(width 0.125)
		(layer "F.Cu")
		(net 2)
	)
	(segment
		(start 111.449 135.211)
		(end 111.449 135.71)
		(width 0.2)
		(layer "F.Cu")
		(net 2)
	)
	(segment
		(start 263.25 92.917)
		(end 262.83 93.337)
		(width 0.3)
		(layer "F.Cu")
		(net 2)
	)
	(segment
		(start 121.338 71.459)
		(end 121.338 72.298)
		(width 0.125)
		(layer "F.Cu")
		(net 2)
	)
	(segment
		(start 125.32 135.88)
		(end 125.71 135.88)
		(width 0.125)
		(layer "F.Cu")
		(net 2)
	)
	(segment
		(start 147.0805 88.8085)
		(end 146.0755 88.8085)
		(width 0.3)
		(layer "F.Cu")
		(net 2)
	)
	(segment
		(start 121.338 72.298)
		(end 121.95 72.91)
		(width 0.125)
		(layer "F.Cu")
		(net 2)
	)
	(segment
		(start 220.21 125.9)
		(end 220.21 124.9)
		(width 0.125)
		(layer "F.Cu")
		(net 2)
	)
	(segment
		(start 193.52751 133.758018)
		(end 193.52751 133.759433)
		(width 0.5)
		(layer "F.Cu")
		(net 2)
	)
	(segment
		(start 115.9 145.821)
		(end 115.9 144.822)
		(width 0.5)
		(layer "F.Cu")
		(net 2)
	)
	(segment
		(start 176.7 159.55)
		(end 173.7 156.55)
		(width 0.125)
		(layer "F.Cu")
		(net 2)
	)
	(segment
		(start 261.83 94.337)
		(end 261.83 93.907)
		(width 0.125)
		(layer "F.Cu")
		(net 2)
	)
	(segment
		(start 308.755 76.742002)
		(end 308.998 76.985002)
		(width 0.2)
		(layer "F.Cu")
		(net 2)
	)
	(segment
		(start 310.075 77.382002)
		(end 309.605 77.382004)
		(width 0.2)
		(layer "F.Cu")
		(net 2)
	)
	(segment
		(start 125.87 138.03)
		(end 125.03 138.87)
		(width 0.125)
		(layer "F.Cu")
		(net 2)
	)
	(segment
		(start 115.4 144.84)
		(end 115.882 144.84)
		(width 0.5)
		(layer "F.Cu")
		(net 2)
	)
	(segment
		(start 109.505 135.71)
		(end 111.449 135.71)
		(width 0.5)
		(layer "F.Cu")
		(net 2)
	)
	(segment
		(start 115.9 148.901)
		(end 115.9 149.901)
		(width 0.5)
		(layer "F.Cu")
		(net 2)
	)
	(segment
		(start 137.92 169.03)
		(end 137.92 168.44)
		(width 0.125)
		(layer "F.Cu")
		(net 2)
	)
	(segment
		(start 212.63 127.121)
		(end 212.825 126.926)
		(width 0.2)
		(layer "F.Cu")
		(net 2)
	)
	(segment
		(start 121.95 72.91)
		(end 121.95 73.64)
		(width 0.125)
		(layer "F.Cu")
		(net 2)
	)
	(segment
		(start 212.63 127.121)
		(end 212.833 127.324)
		(width 0.2)
		(layer "F.Cu")
		(net 2)
	)
	(segment
		(start 130.9 82.24)
		(end 130.900001 83.620001)
		(width 0.2)
		(layer "F.Cu")
		(net 2)
	)
	(segment
		(start 137.93 156.79)
		(end 138.25 157.11)
		(width 0.125)
		(layer "F.Cu")
		(net 2)
	)
	(segment
		(start 303.83 100.64)
		(end 304 100.81)
		(width 0.125)
		(layer "F.Cu")
		(net 2)
	)
	(segment
		(start 303.477 104.083)
		(end 303.477 104.809)
		(width 0.125)
		(layer "F.Cu")
		(net 2)
	)
	(segment
		(start 113.38 148.86)
		(end 114.359 148.86)
		(width 0.125)
		(layer "F.Cu")
		(net 2)
	)
	(segment
		(start 238.38 78.02)
		(end 239.000001 78.02)
		(width 0.2)
		(layer "F.Cu")
		(net 2)
	)
	(segment
		(start 143.87 135.88)
		(end 144.03 136.04)
		(width 0.125)
		(layer "F.Cu")
		(net 2)
	)
	(segment
		(start 139.05 169.64)
		(end 138.53 169.64)
		(width 0.125)
		(layer "F.Cu")
		(net 2)
	)
	(segment
		(start 118.9 144.6)
		(end 118.9 145.771)
		(width 0.5)
		(layer "F.Cu")
		(net 2)
	)
	(segment
		(start 191.808533 139.846915)
		(end 192.500791 139.154657)
		(width 0.125)
		(layer "F.Cu")
		(net 2)
	)
	(segment
		(start 304 100.81)
		(end 304 103.56)
		(width 0.125)
		(layer "F.Cu")
		(net 2)
	)
	(segment
		(start 218.727 130.326)
		(end 218.524001 130.123)
		(width 0.2)
		(layer "F.Cu")
		(net 2)
	)
	(segment
		(start 250.851709 78.423)
		(end 246.552709 78.423)
		(width 0.125)
		(layer "F.Cu")
		(net 2)
	)
	(segment
		(start 125.033 151.411)
		(end 125.033 149.927)
		(width 0.3)
		(layer "F.Cu")
		(net 2)
	)
	(segment
		(start 111.67 134.99)
		(end 111.449 135.211)
		(width 0.2)
		(layer "F.Cu")
		(net 2)
	)
	(segment
		(start 115.879 149.88)
		(end 115.9 149.901)
		(width 0.5)
		(layer "F.Cu")
		(net 2)
	)
	(segment
		(start 192.855758 133.086267)
		(end 193.52751 133.758018)
		(width 0.5)
		(layer "F.Cu")
		(net 2)
	)
	(segment
		(start 189.674485 136.26754)
		(end 189.674485 136.270369)
		(width 0.5)
		(layer "F.Cu")
		(net 2)
	)
	(segment
		(start 212.63 129.12)
		(end 212.833 129.323)
		(width 0.2)
		(layer "F.Cu")
		(net 2)
	)
	(segment
		(start 117.402 145.769)
		(end 117.4 145.771)
		(width 0.5)
		(layer "F.Cu")
		(net 2)
	)
	(segment
		(start 212.825 128.925)
		(end 213.203 128.925)
		(width 0.2)
		(layer "F.Cu")
		(net 2)
	)
	(segment
		(start 310.175 83.28)
		(end 310.174999 83.76)
		(width 0.3)
		(layer "F.Cu")
		(net 2)
	)
	(segment
		(start 191.101426 139.139808)
		(end 191.808533 139.846915)
		(width 0.125)
		(layer "F.Cu")
		(net 2)
	)
	(segment
		(start 177.63 103.39)
		(end 178.35 103.39)
		(width 0.125)
		(layer "F.Cu")
		(net 2)
	)
	(segment
		(start 118.899 149.901)
		(end 118.899 148.851)
		(width 0.5)
		(layer "F.Cu")
		(net 2)
	)
	(segment
		(start 191.441545 135.916108)
		(end 190.735145 135.209709)
		(width 0.5)
		(layer "F.Cu")
		(net 2)
	)
	(segment
		(start 144.03 138.03)
		(end 143.19 138.87)
		(width 0.125)
		(layer "F.Cu")
		(net 2)
	)
	(segment
		(start 212.825 126.926)
		(end 213.203 126.926)
		(width 0.2)
		(layer "F.Cu")
		(net 2)
	)
	(segment
		(start 121.338 74.252)
		(end 121.338 75.758)
		(width 0.3)
		(layer "F.Cu")
		(net 2)
	)
	(segment
		(start 231.442707 78.423)
		(end 231.270707 78.595)
		(width 0.3)
		(layer "F.Cu")
		(net 2)
	)
	(segment
		(start 197.70861 74.102163)
		(end 197.70861 72.802163)
		(width 0.2)
		(layer "F.Cu")
		(net 2)
	)
	(segment
		(start 120.401 144.82)
		(end 120.401 145.815)
		(width 0.5)
		(layer "F.Cu")
		(net 2)
	)
	(segment
		(start 262 93.737)
		(end 261.999999 93.337)
		(width 0.125)
		(layer "F.Cu")
		(net 2)
	)
	(segment
		(start 114.4 144.822)
		(end 114.4 145.821)
		(width 0.5)
		(layer "F.Cu")
		(net 2)
	)
	(segment
		(start 159.55 157.29)
		(end 159.55 158.67)
		(width 0.2)
		(layer "F.Cu")
		(net 2)
	)
	(segment
		(start 218.532 130.521)
		(end 218.154 130.520999)
		(width 0.2)
		(layer "F.Cu")
		(net 2)
	)
	(segment
		(start 192.558774 139.154657)
		(end 193.26588 139.861764)
		(width 0.5)
		(layer "F.Cu")
		(net 2)
	)
	(segment
		(start 192.46685 134.817264)
		(end 192.46685 134.820093)
		(width 0.5)
		(layer "F.Cu")
		(net 2)
	)
	(segment
		(start 308.998 76.985002)
		(end 308.998 77.483)
		(width 0.2)
		(layer "F.Cu")
		(net 2)
	)
	(segment
		(start 215.677 131.773)
		(end 215.88 131.570001)
		(width 0.2)
		(layer "F.Cu")
		(net 2)
	)
	(segment
		(start 125.033 149.927)
		(end 125.22 149.74)
		(width 0.3)
		(layer "F.Cu")
		(net 2)
	)
	(segment
		(start 197.507814 135.618416)
		(end 197.507814 135.619831)
		(width 0.125)
		(layer "F.Cu")
		(net 2)
	)
	(segment
		(start 261.83 93.907)
		(end 262 93.737)
		(width 0.125)
		(layer "F.Cu")
		(net 2)
	)
	(segment
		(start 117.402 144.82)
		(end 117.402 145.769)
		(width 0.5)
		(layer "F.Cu")
		(net 2)
	)
	(segment
		(start 309.605 77.382004)
		(end 309.504002 77.483)
		(width 0.2)
		(layer "F.Cu")
		(net 2)
	)
	(segment
		(start 179.35 103.39)
		(end 178.35 103.39)
		(width 0.125)
		(layer "F.Cu")
		(net 2)
	)
	(segment
		(start 177.475 103.235)
		(end 177.63 103.39)
		(width 0.125)
		(layer "F.Cu")
		(net 2)
	)
	(segment
		(start 143.19 151.409)
		(end 143.19 149.925)
		(width 0.3)
		(layer "F.Cu")
		(net 2)
	)
	(segment
		(start 137.93 156.17)
		(end 137.93 156.79)
		(width 0.125)
		(layer "F.Cu")
		(net 2)
	)
	(segment
		(start 115.4 149.88)
		(end 115.879 149.88)
		(width 0.5)
		(layer "F.Cu")
		(net 2)
	)
	(segment
		(start 215.88 126.249)
		(end 215.88 125.680623)
		(width 0.2)
		(layer "F.Cu")
		(net 2)
	)
	(via
		(at 302.05 99.26)
		(size 0.45)
		(drill 0.1)
		(layers "F.Cu" "B.Cu")
		(remove_unused_layers yes)
		(keep_end_layers yes)
		(free yes)
		(zone_layer_connections "In3.Cu")
		(teardrops
			(best_length_ratio 0.4)
			(max_length 1)
			(best_width_ratio 0.9)
			(max_width 2)
			(curved_edges yes)
			(filter_ratio 0.9)
			(enabled yes)
			(allow_two_segments yes)
			(prefer_zone_connections yes)
		)
		(net 2)
	)
	(via
		(at 104.92 155.66)
		(size 0.45)
		(drill 0.1)
		(layers "F.Cu" "B.Cu")
		(remove_unused_layers yes)
		(keep_end_layers yes)
		(zone_layer_connections "In3.Cu")
		(teardrops
			(best_length_ratio 0.4)
			(max_length 1)
			(best_width_ratio 0.9)
			(max_width 2)
			(curved_edges yes)
			(filter_ratio 0.9)
			(enabled yes)
			(allow_two_segments yes)
			(prefer_zone_connections yes)
		)
		(net 2)
	)
	(via
		(at 243.820708 78.135)
		(size 0.45)
		(drill 0.1)
		(layers "F.Cu" "B.Cu")
		(remove_unused_layers yes)
		(keep_end_layers yes)
		(zone_layer_connections "In3.Cu")
		(teardrops
			(best_length_ratio 0.4)
			(max_length 1)
			(best_width_ratio 0.9)
			(max_width 2)
			(curved_edges yes)
			(filter_ratio 0.9)
			(enabled yes)
			(allow_two_segments yes)
			(prefer_zone_connections yes)
		)
		(net 2)
	)
	(via
		(at 303.05 99.26)
		(size 0.45)
		(drill 0.1)
		(layers "F.Cu" "B.Cu")
		(remove_unused_layers yes)
		(keep_end_layers yes)
		(free yes)
		(zone_layer_connections "In3.Cu")
		(teardrops
			(best_length_ratio 0.4)
			(max_length 1)
			(best_width_ratio 0.9)
			(max_width 2)
			(curved_edges yes)
			(filter_ratio 0.9)
			(enabled yes)
			(allow_two_segments yes)
			(prefer_zone_connections yes)
		)
		(net 2)
	)
	(via
		(at 303.05 100.26)
		(size 0.45)
		(drill 0.1)
		(layers "F.Cu" "B.Cu")
		(remove_unused_layers yes)
		(keep_end_layers yes)
		(free yes)
		(zone_layer_connections "In3.Cu")
		(teardrops
			(best_length_ratio 0.4)
			(max_length 1)
			(best_width_ratio 0.9)
			(max_width 2)
			(curved_edges yes)
			(filter_ratio 0.9)
			(enabled yes)
			(allow_two_segments yes)
			(prefer_zone_connections yes)
		)
		(net 2)
	)
	(via
		(at 178.85 159.55)
		(size 0.45)
		(drill 0.1)
		(layers "F.Cu" "B.Cu")
		(teardrops
			(best_length_ratio 0.4)
			(max_length 1)
			(best_width_ratio 0.9)
			(max_width 2)
			(curved_edges yes)
			(filter_ratio 0.9)
			(enabled yes)
			(allow_two_segments yes)
			(prefer_zone_connections yes)
		)
		(net 2)
	)
	(via
		(at 142.96 138.64)
		(size 0.45)
		(drill 0.1)
		(layers "F.Cu" "B.Cu")
		(remove_unused_layers yes)
		(keep_end_layers yes)
		(zone_layer_connections "In5.Cu")
		(teardrops
			(best_length_ratio 0.4)
			(max_length 1)
			(best_width_ratio 0.9)
			(max_width 2)
			(curved_edges yes)
			(filter_ratio 0.9)
			(enabled yes)
			(allow_two_segments yes)
			(prefer_zone_connections yes)
		)
		(net 2)
	)
	(via
		(at 306 81.46)
		(size 0.45)
		(drill 0.1)
		(layers "F.Cu" "B.Cu")
		(remove_unused_layers yes)
		(keep_end_layers yes)
		(zone_layer_connections "In3.Cu")
		(teardrops
			(best_length_ratio 0.4)
			(max_length 1)
			(best_width_ratio 0.9)
			(max_width 2)
			(curved_edges yes)
			(filter_ratio 0.9)
			(enabled yes)
			(allow_two_segments yes)
			(prefer_zone_connections yes)
		)
		(net 2)
	)
	(via
		(at 310.175 83.28)
		(size 0.45)
		(drill 0.1)
		(layers "F.Cu" "B.Cu")
		(remove_unused_layers yes)
		(keep_end_layers yes)
		(zone_layer_connections "In3.Cu")
		(teardrops
			(best_length_ratio 0.4)
			(max_length 1)
			(best_width_ratio 0.9)
			(max_width 2)
			(curved_edges yes)
			(filter_ratio 0.9)
			(enabled yes)
			(allow_two_segments yes)
			(prefer_zone_connections yes)
		)
		(net 2)
	)
	(via
		(at 163.025 153.4)
		(size 0.45)
		(drill 0.1)
		(layers "F.Cu" "B.Cu")
		(teardrops
			(best_length_ratio 0.4)
			(max_length 1)
			(best_width_ratio 0.9)
			(max_width 2)
			(curved_edges yes)
			(filter_ratio 0.9)
			(enabled yes)
			(allow_two_segments yes)
			(prefer_zone_connections yes)
		)
		(net 2)
	)
	(via
		(at 257.550707 78.135)
		(size 0.45)
		(drill 0.1)
		(layers "F.Cu" "B.Cu")
		(remove_unused_layers yes)
		(keep_end_layers yes)
		(zone_layer_connections "In3.Cu")
		(teardrops
			(best_length_ratio 0.4)
			(max_length 1)
			(best_width_ratio 0.9)
			(max_width 2)
			(curved_edges yes)
			(filter_ratio 0.9)
			(enabled yes)
			(allow_two_segments yes)
			(prefer_zone_connections yes)
		)
		(net 2)
	)
	(via
		(at 193.26588 139.861764)
		(size 0.45)
		(drill 0.1)
		(layers "F.Cu" "B.Cu")
		(remove_unused_layers yes)
		(keep_end_layers yes)
		(zone_layer_connections "In3.Cu")
		(teardrops
			(best_length_ratio 0.4)
			(max_length 1)
			(best_width_ratio 0.9)
			(max_width 2)
			(curved_edges yes)
			(filter_ratio 0.9)
			(enabled yes)
			(allow_two_segments yes)
			(prefer_zone_connections yes)
		)
		(net 2)
	)
	(via
		(at 283.36 78.54)
		(size 0.45)
		(drill 0.1)
		(layers "F.Cu" "B.Cu")
		(remove_unused_layers yes)
		(keep_end_layers yes)
		(zone_layer_connections "In3.Cu")
		(teardrops
			(best_length_ratio 0.4)
			(max_length 1)
			(best_width_ratio 0.9)
			(max_width 2)
			(curved_edges yes)
			(filter_ratio 0.9)
			(enabled yes)
			(allow_two_segments yes)
			(prefer_zone_connections yes)
		)
		(net 2)
	)
	(via
		(at 114.4 149.901)
		(size 0.45)
		(drill 0.1)
		(layers "F.Cu" "B.Cu")
		(remove_unused_layers yes)
		(keep_end_layers yes)
		(zone_layer_connections "In3.Cu")
		(teardrops
			(best_length_ratio 0.4)
			(max_length 1)
			(best_width_ratio 0.9)
			(max_width 2)
			(curved_edges yes)
			(filter_ratio 0.9)
			(enabled yes)
			(allow_two_segments yes)
			(prefer_zone_connections yes)
		)
		(net 2)
	)
	(via
		(at 215.986207 125.574416)
		(size 0.45)
		(drill 0.1)
		(layers "F.Cu" "B.Cu")
		(remove_unused_layers yes)
		(keep_end_layers yes)
		(zone_layer_connections "In3.Cu")
		(teardrops
			(best_length_ratio 0.4)
			(max_length 1)
			(best_width_ratio 0.9)
			(max_width 2)
			(curved_edges yes)
			(filter_ratio 0.9)
			(enabled yes)
			(allow_two_segments yes)
			(prefer_zone_connections yes)
		)
		(net 2)
	)
	(via
		(at 310.075 77.382002)
		(size 0.45)
		(drill 0.1)
		(layers "F.Cu" "B.Cu")
		(remove_unused_layers yes)
		(keep_end_layers yes)
		(zone_layer_connections "In3.Cu")
		(teardrops
			(best_length_ratio 0.4)
			(max_length 1)
			(best_width_ratio 0.9)
			(max_width 2)
			(curved_edges yes)
			(filter_ratio 0.9)
			(enabled yes)
			(allow_two_segments yes)
			(prefer_zone_connections yes)
		)
		(net 2)
	)
	(via
		(at 121.5 74.09)
		(size 0.45)
		(drill 0.1)
		(layers "F.Cu" "B.Cu")
		(remove_unused_layers yes)
		(keep_end_layers yes)
		(zone_layer_connections "In3.Cu")
		(teardrops
			(best_length_ratio 0.4)
			(max_length 1)
			(best_width_ratio 0.9)
			(max_width 2)
			(curved_edges yes)
			(filter_ratio 0.9)
			(enabled yes)
			(allow_two_segments yes)
			(prefer_zone_connections yes)
		)
		(net 2)
	)
	(via
		(at 118.899 149.901)
		(size 0.45)
		(drill 0.1)
		(layers "F.Cu" "B.Cu")
		(remove_unused_layers yes)
		(keep_end_layers yes)
		(zone_layer_connections "In3.Cu")
		(teardrops
			(best_length_ratio 0.4)
			(max_length 1)
			(best_width_ratio 0.9)
			(max_width 2)
			(curved_edges yes)
			(filter_ratio 0.9)
			(enabled yes)
			(allow_two_segments yes)
			(prefer_zone_connections yes)
		)
		(net 2)
	)
	(via
		(at 302.05 100.26)
		(size 0.45)
		(drill 0.1)
		(layers "F.Cu" "B.Cu")
		(remove_unused_layers yes)
		(keep_end_layers yes)
		(free yes)
		(zone_layer_connections "In3.Cu")
		(teardrops
			(best_length_ratio 0.4)
			(max_length 1)
			(best_width_ratio 0.9)
			(max_width 2)
			(curved_edges yes)
			(filter_ratio 0.9)
			(enabled yes)
			(allow_two_segments yes)
			(prefer_zone_connections yes)
		)
		(net 2)
	)
	(via
		(at 193.916419 132.025607)
		(size 0.45)
		(drill 0.1)
		(layers "F.Cu" "B.Cu")
		(remove_unused_layers yes)
		(keep_end_layers yes)
		(zone_layer_connections "In3.Cu")
		(teardrops
			(best_length_ratio 0.4)
			(max_length 1)
			(best_width_ratio 0.9)
			(max_width 2)
			(curved_edges yes)
			(filter_ratio 0.9)
			(enabled yes)
			(allow_two_segments yes)
			(prefer_zone_connections yes)
		)
		(net 2)
	)
	(via
		(at 252.135 83.174999)
		(size 0.45)
		(drill 0.1)
		(layers "F.Cu" "B.Cu")
		(remove_unused_layers yes)
		(keep_end_layers yes)
		(zone_layer_connections "In3.Cu")
		(teardrops
			(best_length_ratio 0.4)
			(max_length 1)
			(best_width_ratio 0.9)
			(max_width 2)
			(curved_edges yes)
			(filter_ratio 0.9)
			(enabled yes)
			(allow_two_segments yes)
			(prefer_zone_connections yes)
		)
		(net 2)
	)
	(via
		(at 212.63 127.121)
		(size 0.45)
		(drill 0.1)
		(layers "F.Cu" "B.Cu")
		(remove_unused_layers yes)
		(keep_end_layers yes)
		(zone_layer_connections "In3.Cu")
		(teardrops
			(best_length_ratio 0.4)
			(max_length 1)
			(best_width_ratio 0.9)
			(max_width 2)
			(curved_edges yes)
			(filter_ratio 0.9)
			(enabled yes)
			(allow_two_segments yes)
			(prefer_zone_connections yes)
		)
		(net 2)
	)
	(via
		(at 117.402 144.82)
		(size 0.45)
		(drill 0.1)
		(layers "F.Cu" "B.Cu")
		(remove_unused_layers yes)
		(keep_end_layers yes)
		(zone_layer_connections "In3.Cu")
		(teardrops
			(best_length_ratio 0.4)
			(max_length 1)
			(best_width_ratio 0.9)
			(max_width 2)
			(curved_edges yes)
			(filter_ratio 0.9)
			(enabled yes)
			(allow_two_segments yes)
			(prefer_zone_connections yes)
		)
		(net 2)
	)
	(via
		(at 189.674485 136.26754)
		(size 0.45)
		(drill 0.1)
		(layers "F.Cu" "B.Cu")
		(remove_unused_layers yes)
		(keep_end_layers yes)
		(zone_layer_connections "In3.Cu")
		(teardrops
			(best_length_ratio 0.4)
			(max_length 1)
			(best_width_ratio 0.9)
			(max_width 2)
			(curved_edges yes)
			(filter_ratio 0.9)
			(enabled yes)
			(allow_two_segments yes)
			(prefer_zone_connections yes)
		)
		(net 2)
	)
	(via
		(at 122.18 161.56)
		(size 0.45)
		(drill 0.1)
		(layers "F.Cu" "B.Cu")
		(remove_unused_layers yes)
		(keep_end_layers yes)
		(zone_layer_connections "In3.Cu")
		(teardrops
			(best_length_ratio 0.4)
			(max_length 1)
			(best_width_ratio 0.9)
			(max_width 2)
			(curved_edges yes)
			(filter_ratio 0.9)
			(enabled yes)
			(allow_two_segments yes)
			(prefer_zone_connections yes)
		)
		(net 2)
	)
	(via
		(at 301.05 101.26)
		(size 0.45)
		(drill 0.1)
		(layers "F.Cu" "B.Cu")
		(remove_unused_layers yes)
		(keep_end_layers yes)
		(free yes)
		(zone_layer_connections "In3.Cu")
		(teardrops
			(best_length_ratio 0.4)
			(max_length 1)
			(best_width_ratio 0.9)
			(max_width 2)
			(curved_edges yes)
			(filter_ratio 0.9)
			(enabled yes)
			(allow_two_segments yes)
			(prefer_zone_connections yes)
		)
		(net 2)
	)
	(via
		(at 159.55 157.29)
		(size 0.45)
		(drill 0.1)
		(layers "F.Cu" "B.Cu")
		(remove_unused_layers yes)
		(keep_end_layers yes)
		(zone_layer_connections "In3.Cu")
		(teardrops
			(best_length_ratio 0.4)
			(max_length 1)
			(best_width_ratio 0.9)
			(max_width 2)
			(curved_edges yes)
			(filter_ratio 0.9)
			(enabled yes)
			(allow_two_segments yes)
			(prefer_zone_connections yes)
		)
		(net 2)
	)
	(via
		(at 147.3 76.16)
		(size 0.45)
		(drill 0.1)
		(layers "F.Cu" "B.Cu")
		(remove_unused_layers yes)
		(keep_end_layers yes)
		(zone_layer_connections "In3.Cu")
		(teardrops
			(best_length_ratio 0.4)
			(max_length 1)
			(best_width_ratio 0.9)
			(max_width 2)
			(curved_edges yes)
			(filter_ratio 0.9)
			(enabled yes)
			(allow_two_segments yes)
			(prefer_zone_connections yes)
		)
		(net 2)
	)
	(via
		(at 196.447154 136.680491)
		(size 0.45)
		(drill 0.1)
		(layers "F.Cu" "B.Cu")
		(remove_unused_layers yes)
		(keep_end_layers yes)
		(zone_layer_connections "In3.Cu")
		(teardrops
			(best_length_ratio 0.4)
			(max_length 1)
			(best_width_ratio 0.9)
			(max_width 2)
			(curved_edges yes)
			(filter_ratio 0.9)
			(enabled yes)
			(allow_two_segments yes)
			(prefer_zone_connections yes)
		)
		(net 2)
	)
	(via
		(at 125.22 149.74)
		(size 0.45)
		(drill 0.1)
		(layers "F.Cu" "B.Cu")
		(remove_unused_layers yes)
		(keep_end_layers yes)
		(zone_layer_connections "In3.Cu")
		(teardrops
			(best_length_ratio 0.4)
			(max_length 1)
			(best_width_ratio 0.9)
			(max_width 2)
			(curved_edges yes)
			(filter_ratio 0.9)
			(enabled yes)
			(allow_two_segments yes)
			(prefer_zone_connections yes)
		)
		(net 2)
	)
	(via
		(at 195.387201 137.740444)
		(size 0.45)
		(drill 0.1)
		(layers "F.Cu" "B.Cu")
		(remove_unused_layers yes)
		(keep_end_layers yes)
		(zone_layer_connections "In3.Cu")
		(teardrops
			(best_length_ratio 0.4)
			(max_length 1)
			(best_width_ratio 0.9)
			(max_width 2)
			(curved_edges yes)
			(filter_ratio 0.9)
			(enabled yes)
			(allow_two_segments yes)
			(prefer_zone_connections yes)
		)
		(net 2)
	)
	(via
		(at 301.05 102.26)
		(size 0.45)
		(drill 0.1)
		(layers "F.Cu" "B.Cu")
		(remove_unused_layers yes)
		(keep_end_layers yes)
		(free yes)
		(zone_layer_connections "In3.Cu")
		(teardrops
			(best_length_ratio 0.4)
			(max_length 1)
			(best_width_ratio 0.9)
			(max_width 2)
			(curved_edges yes)
			(filter_ratio 0.9)
			(enabled yes)
			(allow_two_segments yes)
			(prefer_zone_connections yes)
		)
		(net 2)
	)
	(via
		(at 120.399 149.901)
		(size 0.45)
		(drill 0.1)
		(layers "F.Cu" "B.Cu")
		(remove_unused_layers yes)
		(keep_end_layers yes)
		(zone_layer_connections "In3.Cu")
		(teardrops
			(best_length_ratio 0.4)
			(max_length 1)
			(best_width_ratio 0.9)
			(max_width 2)
			(curved_edges yes)
			(filter_ratio 0.9)
			(enabled yes)
			(allow_two_segments yes)
			(prefer_zone_connections yes)
		)
		(net 2)
	)
	(via
		(at 147.0805 71.808499)
		(size 0.45)
		(drill 0.1)
		(layers "F.Cu" "B.Cu")
		(remove_unused_layers yes)
		(keep_end_layers yes)
		(zone_layer_connections "In3.Cu")
		(teardrops
			(best_length_ratio 0.4)
			(max_length 1)
			(best_width_ratio 0.9)
			(max_width 2)
			(curved_edges yes)
			(filter_ratio 0.9)
			(enabled yes)
			(allow_two_segments yes)
			(prefer_zone_connections yes)
		)
		(net 2)
	)
	(via
		(at 118.9 144.6)
		(size 0.45)
		(drill 0.1)
		(layers "F.Cu" "B.Cu")
		(remove_unused_layers yes)
		(keep_end_layers yes)
		(zone_layer_connections "In3.Cu")
		(teardrops
			(best_length_ratio 0.4)
			(max_length 1)
			(best_width_ratio 0.9)
			(max_width 2)
			(curved_edges yes)
			(filter_ratio 0.9)
			(enabled yes)
			(allow_two_segments yes)
			(prefer_zone_connections yes)
		)
		(net 2)
	)
	(via
		(at 148.3 76.16)
		(size 0.45)
		(drill 0.1)
		(layers "F.Cu" "B.Cu")
		(remove_unused_layers yes)
		(keep_end_layers yes)
		(zone_layer_connections "In3.Cu")
		(teardrops
			(best_length_ratio 0.4)
			(max_length 1)
			(best_width_ratio 0.9)
			(max_width 2)
			(curved_edges yes)
			(filter_ratio 0.9)
			(enabled yes)
			(allow_two_segments yes)
			(prefer_zone_connections yes)
		)
		(net 2)
	)
	(via
		(at 197.70861 74.102163)
		(size 0.45)
		(drill 0.1)
		(layers "F.Cu" "B.Cu")
		(remove_unused_layers yes)
		(keep_end_layers yes)
		(zone_layer_connections "In3.Cu" "In5.Cu")
		(teardrops
			(best_length_ratio 0.4)
			(max_length 1)
			(best_width_ratio 0.9)
			(max_width 2)
			(curved_edges yes)
			(filter_ratio 0.9)
			(enabled yes)
			(allow_two_segments yes)
			(prefer_zone_connections yes)
		)
		(net 2)
	)
	(via
		(at 114.402 144.82)
		(size 0.45)
		(drill 0.1)
		(layers "F.Cu" "B.Cu")
		(remove_unused_layers yes)
		(keep_end_layers yes)
		(zone_layer_connections "In3.Cu")
		(teardrops
			(best_length_ratio 0.4)
			(max_length 1)
			(best_width_ratio 0.9)
			(max_width 2)
			(curved_edges yes)
			(filter_ratio 0.9)
			(enabled yes)
			(allow_two_segments yes)
			(prefer_zone_connections yes)
		)
		(net 2)
	)
	(via
		(at 300.05 101.26)
		(size 0.45)
		(drill 0.1)
		(layers "F.Cu" "B.Cu")
		(remove_unused_layers yes)
		(keep_end_layers yes)
		(free yes)
		(zone_layer_connections "In3.Cu")
		(teardrops
			(best_length_ratio 0.4)
			(max_length 1)
			(best_width_ratio 0.9)
			(max_width 2)
			(curved_edges yes)
			(filter_ratio 0.9)
			(enabled yes)
			(allow_two_segments yes)
			(prefer_zone_connections yes)
		)
		(net 2)
	)
	(via
		(at 218.76 127.324)
		(size 0.45)
		(drill 0.1)
		(layers "F.Cu" "B.Cu")
		(remove_unused_layers yes)
		(keep_end_layers yes)
		(zone_layer_connections "In3.Cu")
		(teardrops
			(best_length_ratio 0.4)
			(max_length 1)
			(best_width_ratio 0.9)
			(max_width 2)
			(curved_edges yes)
			(filter_ratio 0.9)
			(enabled yes)
			(allow_two_segments yes)
			(prefer_zone_connections yes)
		)
		(net 2)
	)
	(via
		(at 306 80.81)
		(size 0.45)
		(drill 0.1)
		(layers "F.Cu" "B.Cu")
		(remove_unused_layers yes)
		(keep_end_layers yes)
		(zone_layer_connections "In3.Cu")
		(teardrops
			(best_length_ratio 0.4)
			(max_length 1)
			(best_width_ratio 0.9)
			(max_width 2)
			(curved_edges yes)
			(filter_ratio 0.9)
			(enabled yes)
			(allow_two_segments yes)
			(prefer_zone_connections yes)
		)
		(net 2)
	)
	(via
		(at 300.05 102.26)
		(size 0.45)
		(drill 0.1)
		(layers "F.Cu" "B.Cu")
		(remove_unused_layers yes)
		(keep_end_layers yes)
		(free yes)
		(zone_layer_connections "In3.Cu")
		(teardrops
			(best_length_ratio 0.4)
			(max_length 1)
			(best_width_ratio 0.9)
			(max_width 2)
			(curved_edges yes)
			(filter_ratio 0.9)
			(enabled yes)
			(allow_two_segments yes)
			(prefer_zone_connections yes)
		)
		(net 2)
	)
	(via
		(at 252.185 84.449999)
		(size 0.45)
		(drill 0.1)
		(layers "F.Cu" "B.Cu")
		(remove_unused_layers yes)
		(keep_end_layers yes)
		(zone_layer_connections "In3.Cu")
		(teardrops
			(best_length_ratio 0.4)
			(max_length 1)
			(best_width_ratio 0.9)
			(max_width 2)
			(curved_edges yes)
			(filter_ratio 0.9)
			(enabled yes)
			(allow_two_segments yes)
			(prefer_zone_connections yes)
		)
		(net 2)
	)
	(via
		(at 120.401 144.82)
		(size 0.45)
		(drill 0.1)
		(layers "F.Cu" "B.Cu")
		(remove_unused_layers yes)
		(keep_end_layers yes)
		(zone_layer_connections "In3.Cu")
		(teardrops
			(best_length_ratio 0.4)
			(max_length 1)
			(best_width_ratio 0.9)
			(max_width 2)
			(curved_edges yes)
			(filter_ratio 0.9)
			(enabled yes)
			(allow_two_segments yes)
			(prefer_zone_connections yes)
		)
		(net 2)
	)
	(via
		(at 180.78 90.43)
		(size 0.45)
		(drill 0.1)
		(layers "F.Cu" "B.Cu")
		(remove_unused_layers yes)
		(keep_end_layers yes)
		(zone_layer_connections "In3.Cu")
		(teardrops
			(best_length_ratio 0.4)
			(max_length 1)
			(best_width_ratio 0.9)
			(max_width 2)
			(curved_edges yes)
			(filter_ratio 0.9)
			(enabled yes)
			(allow_two_segments yes)
			(prefer_zone_connections yes)
		)
		(net 2)
	)
	(via
		(at 147.0805 71.308499)
		(size 0.45)
		(drill 0.1)
		(layers "F.Cu" "B.Cu")
		(remove_unused_layers yes)
		(keep_end_layers yes)
		(zone_layer_connections "In3.Cu")
		(teardrops
			(best_length_ratio 0.4)
			(max_length 1)
			(best_width_ratio 0.9)
			(max_width 2)
			(curved_edges yes)
			(filter_ratio 0.9)
			(enabled yes)
			(allow_two_segments yes)
			(prefer_zone_connections yes)
		)
		(net 2)
	)
	(via
		(at 220.21 125.4)
		(size 0.45)
		(drill 0.1)
		(layers "F.Cu" "B.Cu")
		(remove_unused_layers yes)
		(keep_end_layers yes)
		(zone_layer_connections "In3.Cu")
		(teardrops
			(best_length_ratio 0.4)
			(max_length 1)
			(best_width_ratio 0.9)
			(max_width 2)
			(curved_edges yes)
			(filter_ratio 0.9)
			(enabled yes)
			(allow_two_segments yes)
			(prefer_zone_connections yes)
		)
		(net 2)
	)
	(via
		(at 122.18 162.56)
		(size 0.45)
		(drill 0.1)
		(layers "F.Cu" "B.Cu")
		(remove_unused_layers yes)
		(keep_end_layers yes)
		(zone_layer_connections "In3.Cu")
		(teardrops
			(best_length_ratio 0.4)
			(max_length 1)
			(best_width_ratio 0.9)
			(max_width 2)
			(curved_edges yes)
			(filter_ratio 0.9)
			(enabled yes)
			(allow_two_segments yes)
			(prefer_zone_connections yes)
		)
		(net 2)
	)
	(via
		(at 181.43 88.53)
		(size 0.45)
		(drill 0.1)
		(layers "F.Cu" "B.Cu")
		(remove_unused_layers yes)
		(keep_end_layers yes)
		(zone_layer_connections "In3.Cu")
		(teardrops
			(best_length_ratio 0.4)
			(max_length 1)
			(best_width_ratio 0.9)
			(max_width 2)
			(curved_edges yes)
			(filter_ratio 0.9)
			(enabled yes)
			(allow_two_segments yes)
			(prefer_zone_connections yes)
		)
		(net 2)
	)
	(via
		(at 139.15 157.11)
		(size 0.45)
		(drill 0.1)
		(layers "F.Cu" "B.Cu")
		(remove_unused_layers yes)
		(keep_end_layers yes)
		(zone_layer_connections "In3.Cu")
		(teardrops
			(best_length_ratio 0.4)
			(max_length 1)
			(best_width_ratio 0.9)
			(max_width 2)
			(curved_edges yes)
			(filter_ratio 0.9)
			(enabled yes)
			(allow_two_segments yes)
			(prefer_zone_connections yes)
		)
		(net 2)
	)
	(via
		(at 173.7 156.55)
		(size 0.45)
		(drill 0.1)
		(layers "F.Cu" "B.Cu")
		(teardrops
			(best_length_ratio 0.4)
			(max_length 1)
			(best_width_ratio 0.9)
			(max_width 2)
			(curved_edges yes)
			(filter_ratio 0.9)
			(enabled yes)
			(allow_two_segments yes)
			(prefer_zone_connections yes)
		)
		(net 2)
	)
	(via
		(at 301.05 100.26)
		(size 0.45)
		(drill 0.1)
		(layers "F.Cu" "B.Cu")
		(remove_unused_layers yes)
		(keep_end_layers yes)
		(free yes)
		(zone_layer_connections "In3.Cu")
		(teardrops
			(best_length_ratio 0.4)
			(max_length 1)
			(best_width_ratio 0.9)
			(max_width 2)
			(curved_edges yes)
			(filter_ratio 0.9)
			(enabled yes)
			(allow_two_segments yes)
			(prefer_zone_connections yes)
		)
		(net 2)
	)
	(via
		(at 111.67 134.56)
		(size 0.45)
		(drill 0.1)
		(layers "F.Cu" "B.Cu")
		(remove_unused_layers yes)
		(keep_end_layers yes)
		(zone_layer_connections "In3.Cu")
		(teardrops
			(best_length_ratio 0.4)
			(max_length 1)
			(best_width_ratio 0.9)
			(max_width 2)
			(curved_edges yes)
			(filter_ratio 0.9)
			(enabled yes)
			(allow_two_segments yes)
			(prefer_zone_connections yes)
		)
		(net 2)
	)
	(via
		(at 123.7125 106.57)
		(size 0.45)
		(drill 0.1)
		(layers "F.Cu" "B.Cu")
		(remove_unused_layers yes)
		(keep_end_layers yes)
		(zone_layer_connections "In3.Cu")
		(teardrops
			(best_length_ratio 0.4)
			(max_length 1)
			(best_width_ratio 0.9)
			(max_width 2)
			(curved_edges yes)
			(filter_ratio 0.9)
			(enabled yes)
			(allow_two_segments yes)
			(prefer_zone_connections yes)
		)
		(net 2)
	)
	(via
		(at 191.795805 134.14622)
		(size 0.45)
		(drill 0.1)
		(layers "F.Cu" "B.Cu")
		(remove_unused_layers yes)
		(keep_end_layers yes)
		(zone_layer_connections "In3.Cu")
		(teardrops
			(best_length_ratio 0.4)
			(max_length 1)
			(best_width_ratio 0.9)
			(max_width 2)
			(curved_edges yes)
			(filter_ratio 0.9)
			(enabled yes)
			(allow_two_segments yes)
			(prefer_zone_connections yes)
		)
		(net 2)
	)
	(via
		(at 156.63 84.06)
		(size 0.45)
		(drill 0.1)
		(layers "F.Cu" "B.Cu")
		(remove_unused_layers yes)
		(keep_end_layers yes)
		(zone_layer_connections "In3.Cu")
		(teardrops
			(best_length_ratio 0.4)
			(max_length 1)
			(best_width_ratio 0.9)
			(max_width 2)
			(curved_edges yes)
			(filter_ratio 0.9)
			(enabled yes)
			(allow_two_segments yes)
			(prefer_zone_connections yes)
		)
		(net 2)
	)
	(via
		(at 261.999999 93.337)
		(size 0.45)
		(drill 0.1)
		(layers "F.Cu" "B.Cu")
		(remove_unused_layers yes)
		(keep_end_layers yes)
		(zone_layer_connections "In3.Cu")
		(teardrops
			(best_length_ratio 0.4)
			(max_length 1)
			(best_width_ratio 0.9)
			(max_width 2)
			(curved_edges yes)
			(filter_ratio 0.9)
			(enabled yes)
			(allow_two_segments yes)
			(prefer_zone_connections yes)
		)
		(net 2)
	)
	(via
		(at 212.63 129.12)
		(size 0.45)
		(drill 0.1)
		(layers "F.Cu" "B.Cu")
		(remove_unused_layers yes)
		(keep_end_layers yes)
		(zone_layer_connections "In3.Cu")
		(teardrops
			(best_length_ratio 0.4)
			(max_length 1)
			(best_width_ratio 0.9)
			(max_width 2)
			(curved_edges yes)
			(filter_ratio 0.9)
			(enabled yes)
			(allow_two_segments yes)
			(prefer_zone_connections yes)
		)
		(net 2)
	)
	(via
		(at 305.4 80.81)
		(size 0.45)
		(drill 0.1)
		(layers "F.Cu" "B.Cu")
		(remove_unused_layers yes)
		(keep_end_layers yes)
		(zone_layer_connections "In3.Cu")
		(teardrops
			(best_length_ratio 0.4)
			(max_length 1)
			(best_width_ratio 0.9)
			(max_width 2)
			(curved_edges yes)
			(filter_ratio 0.9)
			(enabled yes)
			(allow_two_segments yes)
			(prefer_zone_connections yes)
		)
		(net 2)
	)
	(via
		(at 147.3 75.16)
		(size 0.45)
		(drill 0.1)
		(layers "F.Cu" "B.Cu")
		(remove_unused_layers yes)
		(keep_end_layers yes)
		(zone_layer_connections "In3.Cu")
		(teardrops
			(best_length_ratio 0.4)
			(max_length 1)
			(best_width_ratio 0.9)
			(max_width 2)
			(curved_edges yes)
			(filter_ratio 0.9)
			(enabled yes)
			(allow_two_segments yes)
			(prefer_zone_connections yes)
		)
		(net 2)
	)
	(via
		(at 130.9 82.24)
		(size 0.45)
		(drill 0.1)
		(layers "F.Cu" "B.Cu")
		(remove_unused_layers yes)
		(keep_end_layers yes)
		(zone_layer_connections "In3.Cu")
		(teardrops
			(best_length_ratio 0.4)
			(max_length 1)
			(best_width_ratio 0.9)
			(max_width 2)
			(curved_edges yes)
			(filter_ratio 0.9)
			(enabled yes)
			(allow_two_segments yes)
			(prefer_zone_connections yes)
		)
		(net 2)
	)
	(via
		(at 298.2 84.49)
		(size 0.45)
		(drill 0.1)
		(layers "F.Cu" "B.Cu")
		(remove_unused_layers yes)
		(keep_end_layers yes)
		(zone_layer_connections "In3.Cu")
		(teardrops
			(best_length_ratio 0.4)
			(max_length 1)
			(best_width_ratio 0.9)
			(max_width 2)
			(curved_edges yes)
			(filter_ratio 0.9)
			(enabled yes)
			(allow_two_segments yes)
			(prefer_zone_connections yes)
		)
		(net 2)
	)
	(via
		(at 181.43 89.18)
		(size 0.45)
		(drill 0.1)
		(layers "F.Cu" "B.Cu")
		(remove_unused_layers yes)
		(keep_end_layers yes)
		(zone_layer_connections "In3.Cu")
		(teardrops
			(best_length_ratio 0.4)
			(max_length 1)
			(best_width_ratio 0.9)
			(max_width 2)
			(curved_edges yes)
			(filter_ratio 0.9)
			(enabled yes)
			(allow_two_segments yes)
			(prefer_zone_connections yes)
		)
		(net 2)
	)
	(via
		(at 124.8 138.64)
		(size 0.45)
		(drill 0.1)
		(layers "F.Cu" "B.Cu")
		(remove_unused_layers yes)
		(keep_end_layers yes)
		(zone_layer_connections "In3.Cu")
		(teardrops
			(best_length_ratio 0.4)
			(max_length 1)
			(best_width_ratio 0.9)
			(max_width 2)
			(curved_edges yes)
			(filter_ratio 0.9)
			(enabled yes)
			(allow_two_segments yes)
			(prefer_zone_connections yes)
		)
		(net 2)
	)
	(via
		(at 148.3 75.16)
		(size 0.45)
		(drill 0.1)
		(layers "F.Cu" "B.Cu")
		(remove_unused_layers yes)
		(keep_end_layers yes)
		(zone_layer_connections "In3.Cu")
		(teardrops
			(best_length_ratio 0.4)
			(max_length 1)
			(best_width_ratio 0.9)
			(max_width 2)
			(curved_edges yes)
			(filter_ratio 0.9)
			(enabled yes)
			(allow_two_segments yes)
			(prefer_zone_connections yes)
		)
		(net 2)
	)
	(via
		(at 194.32654 138.801104)
		(size 0.45)
		(drill 0.1)
		(layers "F.Cu" "B.Cu")
		(remove_unused_layers yes)
		(keep_end_layers yes)
		(zone_layer_connections "In3.Cu")
		(teardrops
			(best_length_ratio 0.4)
			(max_length 1)
			(best_width_ratio 0.9)
			(max_width 2)
			(curved_edges yes)
			(filter_ratio 0.9)
			(enabled yes)
			(allow_two_segments yes)
			(prefer_zone_connections yes)
		)
		(net 2)
	)
	(via
		(at 134.905 84.31)
		(size 0.45)
		(drill 0.1)
		(layers "F.Cu" "B.Cu")
		(remove_unused_layers yes)
		(keep_end_layers yes)
		(zone_layer_connections "In3.Cu")
		(teardrops
			(best_length_ratio 0.4)
			(max_length 1)
			(best_width_ratio 0.9)
			(max_width 2)
			(curved_edges yes)
			(filter_ratio 0.9)
			(enabled yes)
			(allow_two_segments yes)
			(prefer_zone_connections yes)
		)
		(net 2)
	)
	(via
		(at 123.88 96.86)
		(size 0.45)
		(drill 0.1)
		(layers "F.Cu" "B.Cu")
		(remove_unused_layers yes)
		(keep_end_layers yes)
		(zone_layer_connections "In3.Cu")
		(teardrops
			(best_length_ratio 0.4)
			(max_length 1)
			(best_width_ratio 0.9)
			(max_width 2)
			(curved_edges yes)
			(filter_ratio 0.9)
			(enabled yes)
			(allow_two_segments yes)
			(prefer_zone_connections yes)
		)
		(net 2)
	)
	(via
		(at 245.000709 78.615)
		(size 0.45)
		(drill 0.1)
		(layers "F.Cu" "B.Cu")
		(remove_unused_layers yes)
		(keep_end_layers yes)
		(zone_layer_connections "In3.Cu")
		(teardrops
			(best_length_ratio 0.4)
			(max_length 1)
			(best_width_ratio 0.9)
			(max_width 2)
			(curved_edges yes)
			(filter_ratio 0.9)
			(enabled yes)
			(allow_two_segments yes)
			(prefer_zone_connections yes)
		)
		(net 2)
	)
	(via
		(at 300.05 99.26)
		(size 0.45)
		(drill 0.1)
		(layers "F.Cu" "B.Cu")
		(remove_unused_layers yes)
		(keep_end_layers yes)
		(free yes)
		(zone_layer_connections "In3.Cu")
		(teardrops
			(best_length_ratio 0.4)
			(max_length 1)
			(best_width_ratio 0.9)
			(max_width 2)
			(curved_edges yes)
			(filter_ratio 0.9)
			(enabled yes)
			(allow_two_segments yes)
			(prefer_zone_connections yes)
		)
		(net 2)
	)
	(via
		(at 143.377 149.738)
		(size 0.45)
		(drill 0.1)
		(layers "F.Cu" "B.Cu")
		(remove_unused_layers yes)
		(keep_end_layers yes)
		(zone_layer_connections "In3.Cu" "In5.Cu")
		(teardrops
			(best_length_ratio 0.4)
			(max_length 1)
			(best_width_ratio 0.9)
			(max_width 2)
			(curved_edges yes)
			(filter_ratio 0.9)
			(enabled yes)
			(allow_two_segments yes)
			(prefer_zone_connections yes)
		)
		(net 2)
	)
	(via
		(at 117.4 149.901)
		(size 0.45)
		(drill 0.1)
		(layers "F.Cu" "B.Cu")
		(remove_unused_layers yes)
		(keep_end_layers yes)
		(zone_layer_connections "In3.Cu")
		(teardrops
			(best_length_ratio 0.4)
			(max_length 1)
			(best_width_ratio 0.9)
			(max_width 2)
			(curved_edges yes)
			(filter_ratio 0.9)
			(enabled yes)
			(allow_two_segments yes)
			(prefer_zone_connections yes)
		)
		(net 2)
	)
	(via
		(at 115.902 144.82)
		(size 0.45)
		(drill 0.1)
		(layers "F.Cu" "B.Cu")
		(remove_unused_layers yes)
		(keep_end_layers yes)
		(zone_layer_connections "In3.Cu")
		(teardrops
			(best_length_ratio 0.4)
			(max_length 1)
			(best_width_ratio 0.9)
			(max_width 2)
			(curved_edges yes)
			(filter_ratio 0.9)
			(enabled yes)
			(allow_two_segments yes)
			(prefer_zone_connections yes)
		)
		(net 2)
	)
	(via
		(at 163.58 160.36)
		(size 0.45)
		(drill 0.1)
		(layers "F.Cu" "B.Cu")
		(remove_unused_layers yes)
		(keep_end_layers yes)
		(zone_layer_connections "In3.Cu")
		(teardrops
			(best_length_ratio 0.4)
			(max_length 1)
			(best_width_ratio 0.9)
			(max_width 2)
			(curved_edges yes)
			(filter_ratio 0.9)
			(enabled yes)
			(allow_two_segments yes)
			(prefer_zone_connections yes)
		)
		(net 2)
	)
	(via
		(at 252.188337 90.548218)
		(size 0.45)
		(drill 0.1)
		(layers "F.Cu" "B.Cu")
		(remove_unused_layers yes)
		(keep_end_layers yes)
		(zone_layer_connections "In3.Cu")
		(teardrops
			(best_length_ratio 0.4)
			(max_length 1)
			(best_width_ratio 0.9)
			(max_width 2)
			(curved_edges yes)
			(filter_ratio 0.9)
			(enabled yes)
			(allow_two_segments yes)
			(prefer_zone_connections yes)
		)
		(net 2)
	)
	(via
		(at 190.735145 135.20688)
		(size 0.45)
		(drill 0.1)
		(layers "F.Cu" "B.Cu")
		(remove_unused_layers yes)
		(keep_end_layers yes)
		(zone_layer_connections "In3.Cu")
		(teardrops
			(best_length_ratio 0.4)
			(max_length 1)
			(best_width_ratio 0.9)
			(max_width 2)
			(curved_edges yes)
			(filter_ratio 0.9)
			(enabled yes)
			(allow_two_segments yes)
			(prefer_zone_connections yes)
		)
		(net 2)
	)
	(via
		(at 306.6 80.81)
		(size 0.45)
		(drill 0.1)
		(layers "F.Cu" "B.Cu")
		(remove_unused_layers yes)
		(keep_end_layers yes)
		(zone_layer_connections "In3.Cu")
		(teardrops
			(best_length_ratio 0.4)
			(max_length 1)
			(best_width_ratio 0.9)
			(max_width 2)
			(curved_edges yes)
			(filter_ratio 0.9)
			(enabled yes)
			(allow_two_segments yes)
			(prefer_zone_connections yes)
		)
		(net 2)
	)
	(via
		(at 231.270707 78.595)
		(size 0.45)
		(drill 0.1)
		(layers "F.Cu" "B.Cu")
		(remove_unused_layers yes)
		(keep_end_layers yes)
		(zone_layer_connections "In3.Cu")
		(teardrops
			(best_length_ratio 0.4)
			(max_length 1)
			(best_width_ratio 0.9)
			(max_width 2)
			(curved_edges yes)
			(filter_ratio 0.9)
			(enabled yes)
			(allow_two_segments yes)
			(prefer_zone_connections yes)
		)
		(net 2)
	)
	(via
		(at 177.475 103.235)
		(size 0.45)
		(drill 0.1)
		(layers "F.Cu" "B.Cu")
		(remove_unused_layers yes)
		(keep_end_layers yes)
		(zone_layer_connections "In3.Cu")
		(teardrops
			(best_length_ratio 0.4)
			(max_length 1)
			(best_width_ratio 0.9)
			(max_width 2)
			(curved_edges yes)
			(filter_ratio 0.9)
			(enabled yes)
			(allow_two_segments yes)
			(prefer_zone_connections yes)
		)
		(net 2)
	)
	(via
		(at 105.67 169.97)
		(size 0.45)
		(drill 0.1)
		(layers "F.Cu" "B.Cu")
		(remove_unused_layers yes)
		(keep_end_layers yes)
		(zone_layer_connections "In3.Cu")
		(teardrops
			(best_length_ratio 0.4)
			(max_length 1)
			(best_width_ratio 0.9)
			(max_width 2)
			(curved_edges yes)
			(filter_ratio 0.9)
			(enabled yes)
			(allow_two_segments yes)
			(prefer_zone_connections yes)
		)
		(net 2)
	)
	(via
		(at 197.507814 135.619831)
		(size 0.45)
		(drill 0.1)
		(layers "F.Cu" "B.Cu")
		(remove_unused_layers yes)
		(keep_end_layers yes)
		(zone_layer_connections "In3.Cu")
		(teardrops
			(best_length_ratio 0.4)
			(max_length 1)
			(best_width_ratio 0.9)
			(max_width 2)
			(curved_edges yes)
			(filter_ratio 0.9)
			(enabled yes)
			(allow_two_segments yes)
			(prefer_zone_connections yes)
		)
		(net 2)
	)
	(via
		(at 215.677 131.773)
		(size 0.45)
		(drill 0.1)
		(layers "F.Cu" "B.Cu")
		(remove_unused_layers yes)
		(keep_end_layers yes)
		(zone_layer_connections "In3.Cu")
		(teardrops
			(best_length_ratio 0.4)
			(max_length 1)
			(best_width_ratio 0.9)
			(max_width 2)
			(curved_edges yes)
			(filter_ratio 0.9)
			(enabled yes)
			(allow_two_segments yes)
			(prefer_zone_connections yes)
		)
		(net 2)
	)
	(via
		(at 142.97 85.06)
		(size 0.45)
		(drill 0.1)
		(layers "F.Cu" "B.Cu")
		(remove_unused_layers yes)
		(keep_end_layers yes)
		(zone_layer_connections "In3.Cu")
		(teardrops
			(best_length_ratio 0.4)
			(max_length 1)
			(best_width_ratio 0.9)
			(max_width 2)
			(curved_edges yes)
			(filter_ratio 0.9)
			(enabled yes)
			(allow_two_segments yes)
			(prefer_zone_connections yes)
		)
		(net 2)
	)
	(via
		(at 122.53 86.06)
		(size 0.45)
		(drill 0.1)
		(layers "F.Cu" "B.Cu")
		(remove_unused_layers yes)
		(keep_end_layers yes)
		(zone_layer_connections "In3.Cu")
		(teardrops
			(best_length_ratio 0.4)
			(max_length 1)
			(best_width_ratio 0.9)
			(max_width 2)
			(curved_edges yes)
			(filter_ratio 0.9)
			(enabled yes)
			(allow_two_segments yes)
			(prefer_zone_connections yes)
		)
		(net 2)
	)
	(via
		(at 115.9 149.901)
		(size 0.45)
		(drill 0.1)
		(layers "F.Cu" "B.Cu")
		(remove_unused_layers yes)
		(keep_end_layers yes)
		(zone_layer_connections "In3.Cu")
		(teardrops
			(best_length_ratio 0.4)
			(max_length 1)
			(best_width_ratio 0.9)
			(max_width 2)
			(curved_edges yes)
			(filter_ratio 0.9)
			(enabled yes)
			(allow_two_segments yes)
			(prefer_zone_connections yes)
		)
		(net 2)
	)
	(via
		(at 145.79 156.17)
		(size 0.45)
		(drill 0.1)
		(layers "F.Cu" "B.Cu")
		(remove_unused_layers yes)
		(keep_end_layers yes)
		(zone_layer_connections "In3.Cu")
		(teardrops
			(best_length_ratio 0.4)
			(max_length 1)
			(best_width_ratio 0.9)
			(max_width 2)
			(curved_edges yes)
			(filter_ratio 0.9)
			(enabled yes)
			(allow_two_segments yes)
			(prefer_zone_connections yes)
		)
		(net 2)
	)
	(via
		(at 139.05 169.64)
		(size 0.45)
		(drill 0.1)
		(layers "F.Cu" "B.Cu")
		(remove_unused_layers yes)
		(keep_end_layers yes)
		(zone_layer_connections "In3.Cu")
		(teardrops
			(best_length_ratio 0.4)
			(max_length 1)
			(best_width_ratio 0.9)
			(max_width 2)
			(curved_edges yes)
			(filter_ratio 0.9)
			(enabled yes)
			(allow_two_segments yes)
			(prefer_zone_connections yes)
		)
		(net 2)
	)
	(via
		(at 303.05 101.26)
		(size 0.45)
		(drill 0.1)
		(layers "F.Cu" "B.Cu")
		(remove_unused_layers yes)
		(keep_end_layers yes)
		(free yes)
		(zone_layer_connections "In3.Cu")
		(teardrops
			(best_length_ratio 0.4)
			(max_length 1)
			(best_width_ratio 0.9)
			(max_width 2)
			(curved_edges yes)
			(filter_ratio 0.9)
			(enabled yes)
			(allow_two_segments yes)
			(prefer_zone_connections yes)
		)
		(net 2)
	)
	(via
		(at 302.05 101.26)
		(size 0.45)
		(drill 0.1)
		(layers "F.Cu" "B.Cu")
		(remove_unused_layers yes)
		(keep_end_layers yes)
		(free yes)
		(zone_layer_connections "In3.Cu")
		(teardrops
			(best_length_ratio 0.4)
			(max_length 1)
			(best_width_ratio 0.9)
			(max_width 2)
			(curved_edges yes)
			(filter_ratio 0.9)
			(enabled yes)
			(allow_two_segments yes)
			(prefer_zone_connections yes)
		)
		(net 2)
	)
	(via
		(at 305.4 81.46)
		(size 0.45)
		(drill 0.1)
		(layers "F.Cu" "B.Cu")
		(remove_unused_layers yes)
		(keep_end_layers yes)
		(zone_layer_connections "In3.Cu")
		(teardrops
			(best_length_ratio 0.4)
			(max_length 1)
			(best_width_ratio 0.9)
			(max_width 2)
			(curved_edges yes)
			(filter_ratio 0.9)
			(enabled yes)
			(allow_two_segments yes)
			(prefer_zone_connections yes)
		)
		(net 2)
	)
	(via
		(at 300.05 100.26)
		(size 0.45)
		(drill 0.1)
		(layers "F.Cu" "B.Cu")
		(remove_unused_layers yes)
		(keep_end_layers yes)
		(free yes)
		(zone_layer_connections "In3.Cu")
		(teardrops
			(best_length_ratio 0.4)
			(max_length 1)
			(best_width_ratio 0.9)
			(max_width 2)
			(curved_edges yes)
			(filter_ratio 0.9)
			(enabled yes)
			(allow_two_segments yes)
			(prefer_zone_connections yes)
		)
		(net 2)
	)
	(via
		(at 122.53 91.96)
		(size 0.45)
		(drill 0.1)
		(layers "F.Cu" "B.Cu")
		(remove_unused_layers yes)
		(keep_end_layers yes)
		(zone_layer_connections "In3.Cu")
		(teardrops
			(best_length_ratio 0.4)
			(max_length 1)
			(best_width_ratio 0.9)
			(max_width 2)
			(curved_edges yes)
			(filter_ratio 0.9)
			(enabled yes)
			(allow_two_segments yes)
			(prefer_zone_connections yes)
		)
		(net 2)
	)
	(via
		(at 180.78 89.18)
		(size 0.45)
		(drill 0.1)
		(layers "F.Cu" "B.Cu")
		(remove_unused_layers yes)
		(keep_end_layers yes)
		(zone_layer_connections "In3.Cu")
		(teardrops
			(best_length_ratio 0.4)
			(max_length 1)
			(best_width_ratio 0.9)
			(max_width 2)
			(curved_edges yes)
			(filter_ratio 0.9)
			(enabled yes)
			(allow_two_segments yes)
			(prefer_zone_connections yes)
		)
		(net 2)
	)
	(via
		(at 218.727 130.326)
		(size 0.45)
		(drill 0.1)
		(layers "F.Cu" "B.Cu")
		(remove_unused_layers yes)
		(keep_end_layers yes)
		(zone_layer_connections "In3.Cu")
		(teardrops
			(best_length_ratio 0.4)
			(max_length 1)
			(best_width_ratio 0.9)
			(max_width 2)
			(curved_edges yes)
			(filter_ratio 0.9)
			(enabled yes)
			(allow_two_segments yes)
			(prefer_zone_connections yes)
		)
		(net 2)
	)
	(via
		(at 192.855758 133.086267)
		(size 0.45)
		(drill 0.1)
		(layers "F.Cu" "B.Cu")
		(remove_unused_layers yes)
		(keep_end_layers yes)
		(zone_layer_connections "In3.Cu")
		(teardrops
			(best_length_ratio 0.4)
			(max_length 1)
			(best_width_ratio 0.9)
			(max_width 2)
			(curved_edges yes)
			(filter_ratio 0.9)
			(enabled yes)
			(allow_two_segments yes)
			(prefer_zone_connections yes)
		)
		(net 2)
	)
	(via
		(at 111.7 139.96)
		(size 0.45)
		(drill 0.1)
		(layers "F.Cu" "B.Cu")
		(remove_unused_layers yes)
		(keep_end_layers yes)
		(zone_layer_connections "In3.Cu")
		(teardrops
			(best_length_ratio 0.4)
			(max_length 1)
			(best_width_ratio 0.9)
			(max_width 2)
			(curved_edges yes)
			(filter_ratio 0.9)
			(enabled yes)
			(allow_two_segments yes)
			(prefer_zone_connections yes)
		)
		(net 2)
	)
	(via
		(at 180.78 89.78)
		(size 0.45)
		(drill 0.1)
		(layers "F.Cu" "B.Cu")
		(remove_unused_layers yes)
		(keep_end_layers yes)
		(zone_layer_connections "In3.Cu")
		(teardrops
			(best_length_ratio 0.4)
			(max_length 1)
			(best_width_ratio 0.9)
			(max_width 2)
			(curved_edges yes)
			(filter_ratio 0.9)
			(enabled yes)
			(allow_two_segments yes)
			(prefer_zone_connections yes)
		)
		(net 2)
	)
	(via
		(at 146.05 169.64)
		(size 0.45)
		(drill 0.1)
		(layers "F.Cu" "B.Cu")
		(remove_unused_layers yes)
		(keep_end_layers yes)
		(zone_layer_connections "In3.Cu")
		(teardrops
			(best_length_ratio 0.4)
			(max_length 1)
			(best_width_ratio 0.9)
			(max_width 2)
			(curved_edges yes)
			(filter_ratio 0.9)
			(enabled yes)
			(allow_two_segments yes)
			(prefer_zone_connections yes)
		)
		(net 2)
	)
	(via
		(at 193.035858 129.507035)
		(size 0.45)
		(drill 0.1)
		(layers "F.Cu" "B.Cu")
		(remove_unused_layers yes)
		(keep_end_layers yes)
		(zone_layer_connections "In3.Cu")
		(teardrops
			(best_length_ratio 0.4)
			(max_length 1)
			(best_width_ratio 0.9)
			(max_width 2)
			(curved_edges yes)
			(filter_ratio 0.9)
			(enabled yes)
			(allow_two_segments yes)
			(prefer_zone_connections yes)
		)
		(net 2)
	)
	(via
		(at 122.53 87.06)
		(size 0.45)
		(drill 0.1)
		(layers "F.Cu" "B.Cu")
		(remove_unused_layers yes)
		(keep_end_layers yes)
		(zone_layer_connections "In3.Cu")
		(teardrops
			(best_length_ratio 0.4)
			(max_length 1)
			(best_width_ratio 0.9)
			(max_width 2)
			(curved_edges yes)
			(filter_ratio 0.9)
			(enabled yes)
			(allow_two_segments yes)
			(prefer_zone_connections yes)
		)
		(net 2)
	)
	(via
		(at 180.78 88.58)
		(size 0.45)
		(drill 0.1)
		(layers "F.Cu" "B.Cu")
		(remove_unused_layers yes)
		(keep_end_layers yes)
		(zone_layer_connections "In3.Cu")
		(teardrops
			(best_length_ratio 0.4)
			(max_length 1)
			(best_width_ratio 0.9)
			(max_width 2)
			(curved_edges yes)
			(filter_ratio 0.9)
			(enabled yes)
			(allow_two_segments yes)
			(prefer_zone_connections yes)
		)
		(net 2)
	)
	(via
		(at 147.0805 88.8085)
		(size 0.45)
		(drill 0.1)
		(layers "F.Cu" "B.Cu")
		(remove_unused_layers yes)
		(keep_end_layers yes)
		(zone_layer_connections "In3.Cu")
		(teardrops
			(best_length_ratio 0.4)
			(max_length 1)
			(best_width_ratio 0.9)
			(max_width 2)
			(curved_edges yes)
			(filter_ratio 0.9)
			(enabled yes)
			(allow_two_segments yes)
			(prefer_zone_connections yes)
		)
		(net 2)
	)
	(via
		(at 301.05 99.26)
		(size 0.45)
		(drill 0.1)
		(layers "F.Cu" "B.Cu")
		(remove_unused_layers yes)
		(keep_end_layers yes)
		(free yes)
		(zone_layer_connections "In3.Cu")
		(teardrops
			(best_length_ratio 0.4)
			(max_length 1)
			(best_width_ratio 0.9)
			(max_width 2)
			(curved_edges yes)
			(filter_ratio 0.9)
			(enabled yes)
			(allow_two_segments yes)
			(prefer_zone_connections yes)
		)
		(net 2)
	)
	(via
		(at 302.05 102.26)
		(size 0.45)
		(drill 0.1)
		(layers "F.Cu" "B.Cu")
		(remove_unused_layers yes)
		(keep_end_layers yes)
		(free yes)
		(zone_layer_connections "In3.Cu")
		(teardrops
			(best_length_ratio 0.4)
			(max_length 1)
			(best_width_ratio 0.9)
			(max_width 2)
			(curved_edges yes)
			(filter_ratio 0.9)
			(enabled yes)
			(allow_two_segments yes)
			(prefer_zone_connections yes)
		)
		(net 2)
	)
	(via
		(at 147.0805 89.3085)
		(size 0.45)
		(drill 0.1)
		(layers "F.Cu" "B.Cu")
		(remove_unused_layers yes)
		(keep_end_layers yes)
		(zone_layer_connections "In3.Cu")
		(teardrops
			(best_length_ratio 0.4)
			(max_length 1)
			(best_width_ratio 0.9)
			(max_width 2)
			(curved_edges yes)
			(filter_ratio 0.9)
			(enabled yes)
			(allow_two_segments yes)
			(prefer_zone_connections yes)
		)
		(net 2)
	)
	(via
		(at 196.65861 78.102163)
		(size 0.45)
		(drill 0.1)
		(layers "F.Cu" "B.Cu")
		(remove_unused_layers yes)
		(keep_end_layers yes)
		(zone_layer_connections "In3.Cu" "In5.Cu")
		(teardrops
			(best_length_ratio 0.4)
			(max_length 1)
			(best_width_ratio 0.9)
			(max_width 2)
			(curved_edges yes)
			(filter_ratio 0.9)
			(enabled yes)
			(allow_two_segments yes)
			(prefer_zone_connections yes)
		)
		(net 2)
	)
	(via
		(at 122.53 90.96)
		(size 0.45)
		(drill 0.1)
		(layers "F.Cu" "B.Cu")
		(remove_unused_layers yes)
		(keep_end_layers yes)
		(zone_layer_connections "In3.Cu")
		(teardrops
			(best_length_ratio 0.4)
			(max_length 1)
			(best_width_ratio 0.9)
			(max_width 2)
			(curved_edges yes)
			(filter_ratio 0.9)
			(enabled yes)
			(allow_two_segments yes)
			(prefer_zone_connections yes)
		)
		(net 2)
	)
	(via
		(at 147.3 74.16)
		(size 0.45)
		(drill 0.1)
		(layers "F.Cu" "B.Cu")
		(remove_unused_layers yes)
		(keep_end_layers yes)
		(zone_layer_connections "In3.Cu")
		(teardrops
			(best_length_ratio 0.4)
			(max_length 1)
			(best_width_ratio 0.9)
			(max_width 2)
			(curved_edges yes)
			(filter_ratio 0.9)
			(enabled yes)
			(allow_two_segments yes)
			(prefer_zone_connections yes)
		)
		(net 2)
	)
	(via
		(at 306.6 81.46)
		(size 0.45)
		(drill 0.1)
		(layers "F.Cu" "B.Cu")
		(remove_unused_layers yes)
		(keep_end_layers yes)
		(zone_layer_connections "In3.Cu")
		(teardrops
			(best_length_ratio 0.4)
			(max_length 1)
			(best_width_ratio 0.9)
			(max_width 2)
			(curved_edges yes)
			(filter_ratio 0.9)
			(enabled yes)
			(allow_two_segments yes)
			(prefer_zone_connections yes)
		)
		(net 2)
	)
	(via
		(at 299.2 84.49)
		(size 0.45)
		(drill 0.1)
		(layers "F.Cu" "B.Cu")
		(remove_unused_layers yes)
		(keep_end_layers yes)
		(zone_layer_connections "In3.Cu")
		(teardrops
			(best_length_ratio 0.4)
			(max_length 1)
			(best_width_ratio 0.9)
			(max_width 2)
			(curved_edges yes)
			(filter_ratio 0.9)
			(enabled yes)
			(allow_two_segments yes)
			(prefer_zone_connections yes)
		)
		(net 2)
	)
	(via
		(at 258.730708 78.565)
		(size 0.45)
		(drill 0.1)
		(layers "F.Cu" "B.Cu")
		(remove_unused_layers yes)
		(keep_end_layers yes)
		(zone_layer_connections "In3.Cu")
		(teardrops
			(best_length_ratio 0.4)
			(max_length 1)
			(best_width_ratio 0.9)
			(max_width 2)
			(curved_edges yes)
			(filter_ratio 0.9)
			(enabled yes)
			(allow_two_segments yes)
			(prefer_zone_connections yes)
		)
		(net 2)
	)
	(via
		(at 261.54 82.869998)
		(size 0.45)
		(drill 0.1)
		(layers "F.Cu" "B.Cu")
		(remove_unused_layers yes)
		(keep_end_layers yes)
		(zone_layer_connections "In3.Cu")
		(teardrops
			(best_length_ratio 0.4)
			(max_length 1)
			(best_width_ratio 0.9)
			(max_width 2)
			(curved_edges yes)
			(filter_ratio 0.9)
			(enabled yes)
			(allow_two_segments yes)
			(prefer_zone_connections yes)
		)
		(net 2)
	)
	(via
		(at 303.05 102.26)
		(size 0.45)
		(drill 0.1)
		(layers "F.Cu" "B.Cu")
		(remove_unused_layers yes)
		(keep_end_layers yes)
		(free yes)
		(zone_layer_connections "In3.Cu")
		(teardrops
			(best_length_ratio 0.4)
			(max_length 1)
			(best_width_ratio 0.9)
			(max_width 2)
			(curved_edges yes)
			(filter_ratio 0.9)
			(enabled yes)
			(allow_two_segments yes)
			(prefer_zone_connections yes)
		)
		(net 2)
	)
	(segment
		(start 120.88 151.29)
		(end 120.7 151.11)
		(width 0.125)
		(layer "B.Cu")
		(net 2)
	)
	(segment
		(start 124.4 99.34)
		(end 124.4 97.38)
		(width 0.2)
		(layer "B.Cu")
		(net 2)
	)
	(segment
		(start 121.25 151.29)
		(end 120.88 151.29)
		(width 0.125)
		(layer "B.Cu")
		(net 2)
	)
	(segment
		(start 121.97 74.09)
		(end 121.5 74.09)
		(width 0.3)
		(layer "B.Cu")
		(net 2)
	)
	(segment
		(start 123.7125 106.57)
		(end 123.88 106.7375)
		(width 0.125)
		(layer "B.Cu")
		(net 2)
	)
	(segment
		(start 192.879093 142.019147)
		(end 193.5862 141.31204)
		(width 0.125)
		(layer "B.Cu")
		(net 2)
	)
	(segment
		(start 194.784746 137.136575)
		(end 195.387201 137.73903)
		(width 0.125)
		(layer "B.Cu")
		(net 2)
	)
	(segment
		(start 114.401 145.673)
		(end 114.401 144.821)
		(width 0.125)
		(layer "B.Cu")
		(net 2)
	)
	(segment
		(start 310.5 116.76)
		(end 304.05 110.31)
		(width 0.125)
		(layer "B.Cu")
		(net 2)
	)
	(segment
		(start 114.401 149.048)
		(end 114.401 149.9)
		(width 0.125)
		(layer "B.Cu")
		(net 2)
	)
	(segment
		(start 199.091733 136.000254)
		(end 198.31533 136.000254)
		(width 0.125)
		(layer "B.Cu")
		(net 2)
	)
	(segment
		(start 120.4 144.821)
		(end 120.401 144.82)
		(width 0.125)
		(layer "B.Cu")
		(net 2)
	)
	(segment
		(start 178.85 160.45)
		(end 178.85 159.55)
		(width 0.125)
		(layer "B.Cu")
		(net 2)
	)
	(segment
		(start 123.88 99.86)
		(end 124.4 99.34)
		(width 0.2)
		(layer "B.Cu")
		(net 2)
	)
	(segment
		(start 114.401 149.9)
		(end 114.4 149.901)
		(width 0.125)
		(layer "B.Cu")
		(net 2)
	)
	(segment
		(start 118.9 145.673)
		(end 118.9 144.821)
		(width 0.125)
		(layer "B.Cu")
		(net 2)
	)
	(segment
		(start 124.22 138.04)
		(end 124.8 138.62)
		(width 0.3)
		(layer "B.Cu")
		(net 2)
	)
	(segment
		(start 116.45 70.34)
		(end 120.53 70.34)
		(width 0.3)
		(layer "B.Cu")
		(net 2)
	)
	(segment
		(start 218.85 128.85)
		(end 218.85 130.203)
		(width 0.3)
		(layer "B.Cu")
		(net 2)
	)
	(segment
		(start 115.901 149.048)
		(end 115.901 149.9)
		(width 0.125)
		(layer "B.Cu")
		(net 2)
	)
	(segment
		(start 193.883185 140.831208)
		(end 193.26588 140.213903)
		(width 0.125)
		(layer "B.Cu")
		(net 2)
	)
	(segment
		(start 122.35 72.16)
		(end 122.35 73.71)
		(width 0.3)
		(layer "B.Cu")
		(net 2)
	)
	(segment
		(start 310.5 117.68)
		(end 310.5 116.76)
		(width 0.125)
		(layer "B.Cu")
		(net 2)
	)
	(segment
		(start 192.39826 134.750089)
		(end 191.795805 134.147634)
		(width 0.125)
		(layer "B.Cu")
		(net 2)
	)
	(segment
		(start 193.724086 138.197235)
		(end 194.32654 138.79969)
		(width 0.125)
		(layer "B.Cu")
		(net 2)
	)
	(segment
		(start 115.901 145.673)
		(end 115.901 144.821)
		(width 0.125)
		(layer "B.Cu")
		(net 2)
	)
	(segment
		(start 196.905359 135.015961)
		(end 197.507814 135.618416)
		(width 0.125)
		(layer "B.Cu")
		(net 2)
	)
	(segment
		(start 190.27694 136.87141)
		(end 189.674485 136.268955)
		(width 0.125)
		(layer "B.Cu")
		(net 2)
	)
	(segment
		(start 122.35 73.71)
		(end 121.97 74.09)
		(width 0.3)
		(layer "B.Cu")
		(net 2)
	)
	(segment
		(start 256.830707 78.135)
		(end 257.550707 78.135)
		(width 0.5)
		(layer "B.Cu")
		(net 2)
	)
	(segment
		(start 304.05 110.31)
		(end 304.05 103.26)
		(width 0.125)
		(layer "B.Cu")
		(net 2)
	)
	(segment
		(start 118.9 149.048)
		(end 118.9 149.9)
		(width 0.125)
		(layer "B.Cu")
		(net 2)
	)
	(segment
		(start 197.934906 135.619831)
		(end 197.507814 135.619831)
		(width 0.125)
		(layer "B.Cu")
		(net 2)
	)
	(segment
		(start 243.820708 78.135)
		(end 243.100708 78.135)
		(width 0.5)
		(layer "B.Cu")
		(net 2)
	)
	(segment
		(start 123.88 106.7375)
		(end 123.88 107.81)
		(width 0.125)
		(layer "B.Cu")
		(net 2)
	)
	(segment
		(start 188.8 168)
		(end 189.8 169)
		(width 0.125)
		(layer "B.Cu")
		(net 2)
	)
	(segment
		(start 120.7 151.11)
		(end 120.7 150.202)
		(width 0.125)
		(layer "B.Cu")
		(net 2)
	)
	(segment
		(start 304.05 103.26)
		(end 303.05 102.26)
		(width 0.125)
		(layer "B.Cu")
		(net 2)
	)
	(segment
		(start 183.6 166.4)
		(end 183.6 165.2)
		(width 0.125)
		(layer "B.Cu")
		(net 2)
	)
	(segment
		(start 193.458213 133.690136)
		(end 192.855758 133.087681)
		(width 0.125)
		(layer "B.Cu")
		(net 2)
	)
	(segment
		(start 115.901 149.9)
		(end 115.9 149.901)
		(width 0.125)
		(layer "B.Cu")
		(net 2)
	)
	(segment
		(start 139.05 169.64)
		(end 146.05 169.64)
		(width 0.125)
		(layer "B.Cu")
		(net 2)
	)
	(segment
		(start 124.8 138.62)
		(end 124.8 138.64)
		(width 0.3)
		(layer "B.Cu")
		(net 2)
	)
	(segment
		(start 180.78 89.169999)
		(end 180.370001 88.76)
		(width 0.2)
		(layer "B.Cu")
		(net 2)
	)
	(segment
		(start 192.05 169)
		(end 193 168.05)
		(width 0.125)
		(layer "B.Cu")
		(net 2)
	)
	(segment
		(start 142.38 138.04)
		(end 142.96 138.62)
		(width 0.3)
		(layer "B.Cu")
		(net 2)
	)
	(segment
		(start 120.7 150.202)
		(end 120.399 149.901)
		(width 0.125)
		(layer "B.Cu")
		(net 2)
	)
	(segment
		(start 189.8 169)
		(end 192.05 169)
		(width 0.125)
		(layer "B.Cu")
		(net 2)
	)
	(segment
		(start 104.92 169.96)
		(end 105.66 169.96)
		(width 0.3)
		(layer "B.Cu")
		(net 2)
	)
	(segment
		(start 183.6 166.4)
		(end 185.2 168)
		(width 0.125)
		(layer "B.Cu")
		(net 2)
	)
	(segment
		(start 193 166.38)
		(end 193 168.05)
		(width 0.125)
		(layer "B.Cu")
		(net 2)
	)
	(segment
		(start 114.95 70.34)
		(end 116.45 70.34)
		(width 0.3)
		(layer "B.Cu")
		(net 2)
	)
	(segment
		(start 118.9 149.9)
		(end 118.899 149.901)
		(width 0.125)
		(layer "B.Cu")
		(net 2)
	)
	(segment
		(start 123.88 107.81)
		(end 123.88 108.81)
		(width 0.125)
		(layer "B.Cu")
		(net 2)
	)
	(segment
		(start 193.5862 141.31204)
		(end 193.883185 141.015055)
		(width 0.125)
		(layer "B.Cu")
		(net 2)
	)
	(segment
		(start 105.66 169.96)
		(end 105.67 169.97)
		(width 0.3)
		(layer "B.Cu")
		(net 2)
	)
	(segment
		(start 117.401 145.673)
		(end 117.401 144.821)
		(width 0.125)
		(layer "B.Cu")
		(net 2)
	)
	(segment
		(start 180.550001 88.58)
		(end 180.78 88.58)
		(width 0.125)
		(layer "B.Cu")
		(net 2)
	)
	(segment
		(start 218.85 128.85)
		(end 218.85 127.414)
		(width 0.3)
		(layer "B.Cu")
		(net 2)
	)
	(segment
		(start 120.53 70.34)
		(end 122.35 72.16)
		(width 0.3)
		(layer "B.Cu")
		(net 2)
	)
	(segment
		(start 195.844699 136.076622)
		(end 196.447154 136.679077)
		(width 0.125)
		(layer "B.Cu")
		(net 2)
	)
	(segment
		(start 124.4 97.38)
		(end 123.88 96.86)
		(width 0.2)
		(layer "B.Cu")
		(net 2)
	)
	(segment
		(start 198.31533 136.000254)
		(end 197.934906 135.619831)
		(width 0.125)
		(layer "B.Cu")
		(net 2)
	)
	(segment
		(start 178.85 160.45)
		(end 183.6 165.2)
		(width 0.125)
		(layer "B.Cu")
		(net 2)
	)
	(segment
		(start 142.96 138.62)
		(end 142.96 138.64)
		(width 0.3)
		(layer "B.Cu")
		(net 2)
	)
	(segment
		(start 194.518874 132.629476)
		(end 193.916419 132.027021)
		(width 0.125)
		(layer "B.Cu")
		(net 2)
	)
	(segment
		(start 185.2 168)
		(end 188.8 168)
		(width 0.125)
		(layer "B.Cu")
		(net 2)
	)
	(segment
		(start 192.663425 139.257895)
		(end 193.26588 139.86035)
		(width 0.125)
		(layer "B.Cu")
		(net 2)
	)
	(segment
		(start 193.26588 140.213903)
		(end 193.26588 139.861764)
		(width 0.125)
		(layer "B.Cu")
		(net 2)
	)
	(segment
		(start 191.3376 135.810749)
		(end 190.735145 135.208294)
		(width 0.125)
		(layer "B.Cu")
		(net 2)
	)
	(segment
		(start 120.4 145.673)
		(end 120.4 144.821)
		(width 0.125)
		(layer "B.Cu")
		(net 2)
	)
	(segment
		(start 120.4 149.048)
		(end 120.4 149.9)
		(width 0.125)
		(layer "B.Cu")
		(net 2)
	)
	(segment
		(start 193.883185 141.015055)
		(end 193.883185 140.831208)
		(width 0.125)
		(layer "B.Cu")
		(net 2)
	)
	(segment
		(start 180.78 89.18)
		(end 180.78 89.169999)
		(width 0.2)
		(layer "B.Cu")
		(net 2)
	)
	(segment
		(start 180.370001 88.76)
		(end 180.550001 88.58)
		(width 0.125)
		(layer "B.Cu")
		(net 2)
	)
	(segment
		(start 117.401 149.048)
		(end 117.401 149.9)
		(width 0.125)
		(layer "B.Cu")
		(net 2)
	)
	(segment
		(start 117.401 149.9)
		(end 117.4 149.901)
		(width 0.125)
		(layer "B.Cu")
		(net 2)
	)
	(segment
		(start 122.18 161.56)
		(end 122.18 162.56)
		(width 0.125)
		(layer "B.Cu")
		(net 2)
	)
	(segment
		(start 163.375 153.05)
		(end 166.7 153.05)
		(width 0.125)
		(layer "In2.Cu")
		(net 2)
	)
	(segment
		(start 166.7 153.05)
		(end 170.2 156.55)
		(width 0.125)
		(layer "In2.Cu")
		(net 2)
	)
	(segment
		(start 170.2 156.55)
		(end 173.7 156.55)
		(width 0.125)
		(layer "In2.Cu")
		(net 2)
	)
	(segment
		(start 163.025 153.4)
		(end 163.375 153.05)
		(width 0.125)
		(layer "In2.Cu")
		(net 2)
	)
	(segment
		(start 194.32654 138.801104)
		(end 194.326541 138.801104)
		(width 0.2)
		(layer "In3.Cu")
		(net 2)
	)
	(segment
		(start 124.8 138.64)
		(end 122.08 138.64)
		(width 0.3)
		(layer "In3.Cu")
		(net 2)
	)
	(segment
		(start 197.70861 74.102163)
		(end 197.70861 75.652163)
		(width 0.2)
		(layer "In5.Cu")
		(net 2)
	)
	(segment
		(start 144 146.76)
		(end 142.05 144.81)
		(width 0.3)
		(layer "In5.Cu")
		(net 2)
	)
	(segment
		(start 142.05 139.55)
		(end 142.96 138.64)
		(width 0.3)
		(layer "In5.Cu")
		(net 2)
	)
	(segment
		(start 143.377 149.738)
		(end 143.722 149.738)
		(width 0.3)
		(layer "In5.Cu")
		(net 2)
	)
	(segment
		(start 196.65861 76.702163)
		(end 196.65861 78.102163)
		(width 0.2)
		(layer "In5.Cu")
		(net 2)
	)
	(segment
		(start 197.70861 75.652163)
		(end 196.65861 76.702163)
		(width 0.2)
		(layer "In5.Cu")
		(net 2)
	)
	(segment
		(start 143.722 149.738)
		(end 144 149.46)
		(width 0.3)
		(layer "In5.Cu")
		(net 2)
	)
	(segment
		(start 144 149.46)
		(end 144 146.76)
		(width 0.3)
		(layer "In5.Cu")
		(net 2)
	)
	(segment
		(start 142.05 144.81)
		(end 142.05 139.55)
		(width 0.3)
		(layer "In5.Cu")
		(net 2)
	)
	(segment
		(start 155.97 71.31)
		(end 155.6615 71.6185)
		(width 0.185)
		(layer "F.Cu")
		(net 3)
	)
	(segment
		(start 154.2585 71.6185)
		(end 154.1985 71.5585)
		(width 0.185)
		(layer "F.Cu")
		(net 3)
	)
	(segment
		(start 155.6615 71.6185)
		(end 154.2585 71.6185)
		(width 0.185)
		(layer "F.Cu")
		(net 3)
	)
	(segment
		(start 154.2585 71.9985)
		(end 154.1985 72.0585)
		(width 0.185)
		(layer "F.Cu")
		(net 4)
	)
	(segment
		(start 155.97 72.31)
		(end 155.6585 71.9985)
		(width 0.185)
		(layer "F.Cu")
		(net 4)
	)
	(segment
		(start 155.6585 71.9985)
		(end 154.2585 71.9985)
		(width 0.185)
		(layer "F.Cu")
		(net 4)
	)
	(segment
		(start 143.5495 72.3095)
		(end 146.0755 72.3095)
		(width 0.125)
		(layer "F.Cu")
		(net 5)
	)
	(segment
		(start 116.55 71.21)
		(end 117.5 71.21)
		(width 0.125)
		(layer "F.Cu")
		(net 5)
	)
	(segment
		(start 140.55 69.31)
		(end 143.5495 72.3095)
		(width 0.125)
		(layer "F.Cu")
		(net 5)
	)
	(segment
		(start 117.5 71.21)
		(end 119.4 69.31)
		(width 0.125)
		(layer "F.Cu")
		(net 5)
	)
	(segment
		(start 116.45 71.11)
		(end 116.55 71.21)
		(width 0.125)
		(layer "F.Cu")
		(net 5)
	)
	(segment
		(start 119.4 69.31)
		(end 140.55 69.31)
		(width 0.125)
		(layer "F.Cu")
		(net 5)
	)
	(segment
		(start 116.45 70.56)
		(end 116.45 71.11)
		(width 0.125)
		(layer "F.Cu")
		(net 5)
	)
	(segment
		(start 145.1755 74.8095)
		(end 140.326 69.96)
		(width 0.125)
		(layer "F.Cu")
		(net 6)
	)
	(segment
		(start 114.95 71.135)
		(end 114.95 70.56)
		(width 0.125)
		(layer "F.Cu")
		(net 6)
	)
	(segment
		(start 117.9 71.66)
		(end 115.475 71.66)
		(width 0.125)
		(layer "F.Cu")
		(net 6)
	)
	(segment
		(start 146.0755 74.8095)
		(end 145.1755 74.8095)
		(width 0.125)
		(layer "F.Cu")
		(net 6)
	)
	(segment
		(start 119.6 69.96)
		(end 117.9 71.66)
		(width 0.125)
		(layer "F.Cu")
		(net 6)
	)
	(segment
		(start 140.326 69.96)
		(end 119.6 69.96)
		(width 0.125)
		(layer "F.Cu")
		(net 6)
	)
	(segment
		(start 115.475 71.66)
		(end 114.95 71.135)
		(width 0.125)
		(layer "F.Cu")
		(net 6)
	)
	(segment
		(start 159.680566 74.3445)
		(end 169.259461 74.3445)
		(width 0.202)
		(layer "F.Cu")
		(net 9)
	)
	(segment
		(start 203.0805 167.124)
		(end 202.9565 167)
		(width 0.202)
		(layer "F.Cu")
		(net 9)
	)
	(segment
		(start 155.471066 80.004)
		(end 156.4945 78.980566)
		(width 0.202)
		(layer "F.Cu")
		(net 9)
	)
	(segment
		(start 193.1055 90.730566)
		(end 193.1055 113.680565)
		(width 0.202)
		(layer "F.Cu")
		(net 9)
	)
	(segment
		(start 176.719434 74.3445)
		(end 193.1055 90.730566)
		(width 0.202)
		(layer "F.Cu")
		(net 9)
	)
	(segment
		(start 169.739461 74.88637)
		(end 169.859461 74.88637)
		(width 0.202)
		(layer "F.Cu")
		(net 9)
	)
	(segment
		(start 153.5735 80.0595)
		(end 154.1985 80.0595)
		(width 0.202)
		(layer "F.Cu")
		(net 9)
	)
	(segment
		(start 193.1055 113.680565)
		(end 203.671604 124.246669)
		(width 0.202)
		(layer "F.Cu")
		(net 9)
	)
	(segment
		(start 154.1985 80.0595)
		(end 154.254 80.004)
		(width 0.202)
		(layer "F.Cu")
		(net 9)
	)
	(segment
		(start 169.499461 74.5845)
		(end 169.499461 74.64637)
		(width 0.202)
		(layer "F.Cu")
		(net 9)
	)
	(segment
		(start 154.254 80.004)
		(end 155.471066 80.004)
		(width 0.202)
		(layer "F.Cu")
		(net 9)
	)
	(segment
		(start 156.4945 78.980566)
		(end 156.4945 77.530566)
		(width 0.202)
		(layer "F.Cu")
		(net 9)
	)
	(segment
		(start 170.339461 74.3445)
		(end 170.459461 74.3445)
		(width 0.202)
		(layer "F.Cu")
		(net 9)
	)
	(segment
		(start 203.671604 124.246669)
		(end 203.671604 124.428396)
		(width 0.202)
		(layer "F.Cu")
		(net 9)
	)
	(segment
		(start 170.459461 74.3445)
		(end 170.683824 74.3445)
		(width 0.202)
		(layer "F.Cu")
		(net 9)
	)
	(segment
		(start 203.025 168.685)
		(end 203.025 167.96)
		(width 0.202)
		(layer "F.Cu")
		(net 9)
	)
	(segment
		(start 203.025 167.96)
		(end 203.0805 167.9045)
		(width 0.202)
		(layer "F.Cu")
		(net 9)
	)
	(segment
		(start 170.683824 74.3445)
		(end 176.719434 74.3445)
		(width 0.202)
		(layer "F.Cu")
		(net 9)
	)
	(segment
		(start 170.099461 74.64637)
		(end 170.099461 74.5845)
		(width 0.202)
		(layer "F.Cu")
		(net 9)
	)
	(segment
		(start 203.0805 167.9045)
		(end 203.0805 167.124)
		(width 0.202)
		(layer "F.Cu")
		(net 9)
	)
	(segment
		(start 156.4945 77.530566)
		(end 159.680566 74.3445)
		(width 0.202)
		(layer "F.Cu")
		(net 9)
	)
	(via
		(at 203.671604 124.428396)
		(size 0.45)
		(drill 0.1)
		(layers "F.Cu" "B.Cu")
		(teardrops
			(best_length_ratio 0.4)
			(max_length 1)
			(best_width_ratio 0.9)
			(max_width 2)
			(curved_edges yes)
			(filter_ratio 0.9)
			(enabled yes)
			(allow_two_segments yes)
			(prefer_zone_connections yes)
		)
		(net 9)
	)
	(via
		(at 202.9565 167)
		(size 0.45)
		(drill 0.1)
		(layers "F.Cu" "B.Cu")
		(teardrops
			(best_length_ratio 0.4)
			(max_length 1)
			(best_width_ratio 0.9)
			(max_width 2)
			(curved_edges yes)
			(filter_ratio 0.9)
			(enabled yes)
			(allow_two_segments yes)
			(prefer_zone_connections yes)
		)
		(net 9)
	)
	(arc
		(start 169.259461 74.3445)
		(mid 169.429167 74.414794)
		(end 169.499461 74.5845)
		(width 0.202)
		(layer "F.Cu")
		(net 9)
	)
	(arc
		(start 170.099461 74.5845)
		(mid 170.169755 74.414794)
		(end 170.339461 74.3445)
		(width 0.202)
		(layer "F.Cu")
		(net 9)
	)
	(arc
		(start 169.859461 74.88637)
		(mid 170.029167 74.816076)
		(end 170.099461 74.64637)
		(width 0.202)
		(layer "F.Cu")
		(net 9)
	)
	(arc
		(start 169.499461 74.64637)
		(mid 169.569755 74.816076)
		(end 169.739461 74.88637)
		(width 0.202)
		(layer "F.Cu")
		(net 9)
	)
	(segment
		(start 204.651 129.834542)
		(end 204.651 125.232429)
		(width 0.178)
		(layer "In5.Cu")
		(net 9)
	)
	(segment
		(start 206.013 140.827458)
		(end 204.063 138.877458)
		(width 0.178)
		(layer "In5.Cu")
		(net 9)
	)
	(segment
		(start 203.076 166.8805)
		(end 203.076 166.55743)
		(width 0.178)
		(layer "In5.Cu")
		(net 9)
	)
	(segment
		(start 203.846967 124.428396)
		(end 204.651 125.232429)
		(width 0.178)
		(layer "In5.Cu")
		(net 9)
	)
	(segment
		(start 201.513 164.99443)
		(end 201.513 160.822542)
		(width 0.178)
		(layer "In5.Cu")
		(net 9)
	)
	(segment
		(start 204.613 157.722542)
		(end 204.613 146.822542)
		(width 0.178)
		(layer "In5.Cu")
		(net 9)
	)
	(segment
		(start 201.513 164.99443)
		(end 203.076 166.55743)
		(width 0.178)
		(layer "In5.Cu")
		(net 9)
	)
	(segment
		(start 204.063 138.877458)
		(end 204.063 130.422542)
		(width 0.178)
		(layer "In5.Cu")
		(net 9)
	)
	(segment
		(start 203.671604 124.428396)
		(end 203.846967 124.428396)
		(width 0.178)
		(layer "In5.Cu")
		(net 9)
	)
	(segment
		(start 201.513 160.822542)
		(end 204.613 157.722542)
		(width 0.178)
		(layer "In5.Cu")
		(net 9)
	)
	(segment
		(start 204.063 130.422542)
		(end 204.651 129.834542)
		(width 0.178)
		(layer "In5.Cu")
		(net 9)
	)
	(segment
		(start 202.9565 167)
		(end 203.076 166.8805)
		(width 0.178)
		(layer "In5.Cu")
		(net 9)
	)
	(segment
		(start 206.013 145.422542)
		(end 206.013 140.827458)
		(width 0.178)
		(layer "In5.Cu")
		(net 9)
	)
	(segment
		(start 204.613 146.822542)
		(end 206.013 145.422542)
		(width 0.178)
		(layer "In5.Cu")
		(net 9)
	)
	(segment
		(start 203.525 167.96)
		(end 203.4695 167.9045)
		(width 0.202)
		(layer "F.Cu")
		(net 11)
	)
	(segment
		(start 156.1055 78.819434)
		(end 155.309934 79.615)
		(width 0.202)
		(layer "F.Cu")
		(net 11)
	)
	(segment
		(start 203.4695 167.124)
		(end 203.5935 167)
		(width 0.202)
		(layer "F.Cu")
		(net 11)
	)
	(segment
		(start 203.946669 123.971604)
		(end 193.4945 113.519435)
		(width 0.202)
		(layer "F.Cu")
		(net 11)
	)
	(segment
		(start 156.1055 77.369434)
		(end 156.1055 78.819434)
		(width 0.202)
		(layer "F.Cu")
		(net 11)
	)
	(segment
		(start 204.128396 123.971604)
		(end 203.946669 123.971604)
		(width 0.202)
		(layer "F.Cu")
		(net 11)
	)
	(segment
		(start 203.525 168.685)
		(end 203.525 167.96)
		(width 0.202)
		(layer "F.Cu")
		(net 11)
	)
	(segment
		(start 193.4945 113.519435)
		(end 193.4945 90.569434)
		(width 0.202)
		(layer "F.Cu")
		(net 11)
	)
	(segment
		(start 155.309934 79.615)
		(end 154.254 79.615)
		(width 0.202)
		(layer "F.Cu")
		(net 11)
	)
	(segment
		(start 159.519434 73.9555)
		(end 156.1055 77.369434)
		(width 0.202)
		(layer "F.Cu")
		(net 11)
	)
	(segment
		(start 154.1985 79.5595)
		(end 153.5735 79.5595)
		(width 0.202)
		(layer "F.Cu")
		(net 11)
	)
	(segment
		(start 203.4695 167.9045)
		(end 203.4695 167.124)
		(width 0.202)
		(layer "F.Cu")
		(net 11)
	)
	(segment
		(start 176.880566 73.9555)
		(end 159.519434 73.9555)
		(width 0.202)
		(layer "F.Cu")
		(net 11)
	)
	(segment
		(start 193.4945 90.569434)
		(end 176.880566 73.9555)
		(width 0.202)
		(layer "F.Cu")
		(net 11)
	)
	(segment
		(start 154.254 79.615)
		(end 154.1985 79.5595)
		(width 0.202)
		(layer "F.Cu")
		(net 11)
	)
	(via
		(at 203.5935 167)
		(size 0.45)
		(drill 0.1)
		(layers "F.Cu" "B.Cu")
		(teardrops
			(best_length_ratio 0.4)
			(max_length 1)
			(best_width_ratio 0.9)
			(max_width 2)
			(curved_edges yes)
			(filter_ratio 0.9)
			(enabled yes)
			(allow_two_segments yes)
			(prefer_zone_connections yes)
		)
		(net 11)
	)
	(via
		(at 204.128396 123.971604)
		(size 0.45)
		(drill 0.1)
		(layers "F.Cu" "B.Cu")
		(teardrops
			(best_length_ratio 0.4)
			(max_length 1)
			(best_width_ratio 0.9)
			(max_width 2)
			(curved_edges yes)
			(filter_ratio 0.9)
			(enabled yes)
			(allow_two_segments yes)
			(prefer_zone_connections yes)
		)
		(net 11)
	)
	(segment
		(start 201.887 164.80557)
		(end 203.474 166.39257)
		(width 0.178)
		(layer "In5.Cu")
		(net 11)
	)
	(segment
		(start 204.437 130.577458)
		(end 205.049 129.965458)
		(width 0.178)
		(layer "In5.Cu")
		(net 11)
	)
	(segment
		(start 201.887 164.80557)
		(end 201.887 160.977458)
		(width 0.178)
		(layer "In5.Cu")
		(net 11)
	)
	(segment
		(start 204.987 157.877458)
		(end 204.987 146.977458)
		(width 0.178)
		(layer "In5.Cu")
		(net 11)
	)
	(segment
		(start 203.5935 167)
		(end 203.474 166.8805)
		(width 0.178)
		(layer "In5.Cu")
		(net 11)
	)
	(segment
		(start 206.387 140.672542)
		(end 204.437 138.722542)
		(width 0.178)
		(layer "In5.Cu")
		(net 11)
	)
	(segment
		(start 205.049 129.965458)
		(end 205.049 125.067571)
		(width 0.178)
		(layer "In5.Cu")
		(net 11)
	)
	(segment
		(start 201.887 160.977458)
		(end 204.987 157.877458)
		(width 0.178)
		(layer "In5.Cu")
		(net 11)
	)
	(segment
		(start 203.474 166.8805)
		(end 203.474 166.39257)
		(width 0.178)
		(layer "In5.Cu")
		(net 11)
	)
	(segment
		(start 204.128396 124.146967)
		(end 205.049 125.067571)
		(width 0.178)
		(layer "In5.Cu")
		(net 11)
	)
	(segment
		(start 206.387 145.577458)
		(end 206.387 140.672542)
		(width 0.178)
		(layer "In5.Cu")
		(net 11)
	)
	(segment
		(start 204.437 138.722542)
		(end 204.437 130.577458)
		(width 0.178)
		(layer "In5.Cu")
		(net 11)
	)
	(segment
		(start 204.128396 123.971604)
		(end 204.128396 124.146967)
		(width 0.178)
		(layer "In5.Cu")
		(net 11)
	)
	(segment
		(start 204.987 146.977458)
		(end 206.387 145.577458)
		(width 0.178)
		(layer "In5.Cu")
		(net 11)
	)
	(segment
		(start 169.053794 76.4945)
		(end 170.576997 76.4945)
		(width 0.202)
		(layer "F.Cu")
		(net 14)
	)
	(segment
		(start 153.5735 81.5595)
		(end 154.1985 81.5595)
		(width 0.202)
		(layer "F.Cu")
		(net 14)
	)
	(segment
		(start 157.8945 80.430566)
		(end 157.8945 78.030566)
		(width 0.202)
		(layer "F.Cu")
		(net 14)
	)
	(segment
		(start 168.943794 76.4945)
		(end 169.053794 76.4945)
		(width 0.202)
		(layer "F.Cu")
		(net 14)
	)
	(segment
		(start 157.8945 78.030566)
		(end 159.430566 76.4945)
		(width 0.202)
		(layer "F.Cu")
		(net 14)
	)
	(segment
		(start 175.069434 76.4945)
		(end 190.8555 92.280566)
		(width 0.202)
		(layer "F.Cu")
		(net 14)
	)
	(segment
		(start 203.025 163.135)
		(end 203.025 163.86)
		(width 0.202)
		(layer "F.Cu")
		(net 14)
	)
	(segment
		(start 168.723794 76.785611)
		(end 168.723794 76.7145)
		(width 0.202)
		(layer "F.Cu")
		(net 14)
	)
	(segment
		(start 205.8055 131.2715)
		(end 205.677 131.4)
		(width 0.202)
		(layer "F.Cu")
		(net 14)
	)
	(segment
		(start 203.0805 163.9155)
		(end 203.0805 164.226)
		(width 0.202)
		(layer "F.Cu")
		(net 14)
	)
	(segment
		(start 190.8555 114.980566)
		(end 205.8055 129.930566)
		(width 0.202)
		(layer "F.Cu")
		(net 14)
	)
	(segment
		(start 156.821066 81.504)
		(end 157.8945 80.430566)
		(width 0.202)
		(layer "F.Cu")
		(net 14)
	)
	(segment
		(start 168.393794 77.005611)
		(end 168.503794 77.005611)
		(width 0.202)
		(layer "F.Cu")
		(net 14)
	)
	(segment
		(start 170.576997 76.4945)
		(end 175.069434 76.4945)
		(width 0.202)
		(layer "F.Cu")
		(net 14)
	)
	(segment
		(start 205.8055 129.930566)
		(end 205.8055 131.2715)
		(width 0.202)
		(layer "F.Cu")
		(net 14)
	)
	(segment
		(start 154.1985 81.5595)
		(end 154.254 81.504)
		(width 0.202)
		(layer "F.Cu")
		(net 14)
	)
	(segment
		(start 190.8555 92.280566)
		(end 190.8555 114.980566)
		(width 0.202)
		(layer "F.Cu")
		(net 14)
	)
	(segment
		(start 203.025 163.86)
		(end 203.0805 163.9155)
		(width 0.202)
		(layer "F.Cu")
		(net 14)
	)
	(segment
		(start 154.254 81.504)
		(end 156.821066 81.504)
		(width 0.202)
		(layer "F.Cu")
		(net 14)
	)
	(segment
		(start 159.430566 76.4945)
		(end 167.953794 76.4945)
		(width 0.202)
		(layer "F.Cu")
		(net 14)
	)
	(segment
		(start 168.173794 76.7145)
		(end 168.173794 76.785611)
		(width 0.202)
		(layer "F.Cu")
		(net 14)
	)
	(segment
		(start 203.0805 164.226)
		(end 202.9565 164.35)
		(width 0.202)
		(layer "F.Cu")
		(net 14)
	)
	(via
		(at 205.677 131.4)
		(size 0.45)
		(drill 0.1)
		(layers "F.Cu" "B.Cu")
		(teardrops
			(best_length_ratio 0.4)
			(max_length 1)
			(best_width_ratio 0.9)
			(max_width 2)
			(curved_edges yes)
			(filter_ratio 0.9)
			(enabled yes)
			(allow_two_segments yes)
			(prefer_zone_connections yes)
		)
		(net 14)
	)
	(via
		(at 202.9565 164.35)
		(size 0.45)
		(drill 0.1)
		(layers "F.Cu" "B.Cu")
		(teardrops
			(best_length_ratio 0.4)
			(max_length 1)
			(best_width_ratio 0.9)
			(max_width 2)
			(curved_edges yes)
			(filter_ratio 0.9)
			(enabled yes)
			(allow_two_segments yes)
			(prefer_zone_connections yes)
		)
		(net 14)
	)
	(arc
		(start 167.953794 76.4945)
		(mid 168.109357 76.558937)
		(end 168.173794 76.7145)
		(width 0.202)
		(layer "F.Cu")
		(net 14)
	)
	(arc
		(start 168.503794 77.005611)
		(mid 168.659357 76.941174)
		(end 168.723794 76.785611)
		(width 0.202)
		(layer "F.Cu")
		(net 14)
	)
	(arc
		(start 168.173794 76.785611)
		(mid 168.238231 76.941174)
		(end 168.393794 77.005611)
		(width 0.202)
		(layer "F.Cu")
		(net 14)
	)
	(arc
		(start 168.723794 76.7145)
		(mid 168.788231 76.558937)
		(end 168.943794 76.4945)
		(width 0.202)
		(layer "F.Cu")
		(net 14)
	)
	(segment
		(start 203.088 164.2185)
		(end 203.088 160.897542)
		(width 0.178)
		(layer "In5.Cu")
		(net 14)
	)
	(segment
		(start 206.313 157.672542)
		(end 206.313 147.572542)
		(width 0.178)
		(layer "In5.Cu")
		(net 14)
	)
	(segment
		(start 207.613 146.272542)
		(end 207.613 139.227458)
		(width 0.178)
		(layer "In5.Cu")
		(net 14)
	)
	(segment
		(start 207.613 139.227458)
		(end 205.813 137.427458)
		(width 0.178)
		(layer "In5.Cu")
		(net 14)
	)
	(segment
		(start 206.313 147.572542)
		(end 207.613 146.272542)
		(width 0.178)
		(layer "In5.Cu")
		(net 14)
	)
	(segment
		(start 203.088 160.897542)
		(end 206.313 157.672542)
		(width 0.178)
		(layer "In5.Cu")
		(net 14)
	)
	(segment
		(start 205.813 137.427458)
		(end 205.813 131.536)
		(width 0.178)
		(layer "In5.Cu")
		(net 14)
	)
	(segment
		(start 202.9565 164.35)
		(end 203.088 164.2185)
		(width 0.178)
		(layer "In5.Cu")
		(net 14)
	)
	(segment
		(start 205.813 131.536)
		(end 205.677 131.4)
		(width 0.178)
		(layer "In5.Cu")
		(net 14)
	)
	(segment
		(start 154.1985 81.0595)
		(end 153.5735 81.0595)
		(width 0.202)
		(layer "F.Cu")
		(net 16)
	)
	(segment
		(start 203.525 163.135)
		(end 203.525 163.86)
		(width 0.202)
		(layer "F.Cu")
		(net 16)
	)
	(segment
		(start 203.4695 164.226)
		(end 203.5935 164.35)
		(width 0.202)
		(layer "F.Cu")
		(net 16)
	)
	(segment
		(start 203.525 163.86)
		(end 203.4695 163.9155)
		(width 0.202)
		(layer "F.Cu")
		(net 16)
	)
	(segment
		(start 191.2445 114.819434)
		(end 191.2445 92.119434)
		(width 0.202)
		(layer "F.Cu")
		(net 16)
	)
	(segment
		(start 206.1945 129.769434)
		(end 191.2445 114.819434)
		(width 0.202)
		(layer "F.Cu")
		(net 16)
	)
	(segment
		(start 203.4695 163.9155)
		(end 203.4695 164.226)
		(width 0.202)
		(layer "F.Cu")
		(net 16)
	)
	(segment
		(start 154.254 81.115)
		(end 154.1985 81.0595)
		(width 0.202)
		(layer "F.Cu")
		(net 16)
	)
	(segment
		(start 157.5055 77.869434)
		(end 157.5055 80.269434)
		(width 0.202)
		(layer "F.Cu")
		(net 16)
	)
	(segment
		(start 206.323 131.4)
		(end 206.1945 131.2715)
		(width 0.202)
		(layer "F.Cu")
		(net 16)
	)
	(segment
		(start 206.1945 131.2715)
		(end 206.1945 129.769434)
		(width 0.202)
		(layer "F.Cu")
		(net 16)
	)
	(segment
		(start 156.659934 81.115)
		(end 154.254 81.115)
		(width 0.202)
		(layer "F.Cu")
		(net 16)
	)
	(segment
		(start 191.2445 92.119434)
		(end 175.230566 76.1055)
		(width 0.202)
		(layer "F.Cu")
		(net 16)
	)
	(segment
		(start 175.230566 76.1055)
		(end 159.269434 76.1055)
		(width 0.202)
		(layer "F.Cu")
		(net 16)
	)
	(segment
		(start 159.269434 76.1055)
		(end 157.5055 77.869434)
		(width 0.202)
		(layer "F.Cu")
		(net 16)
	)
	(segment
		(start 157.5055 80.269434)
		(end 156.659934 81.115)
		(width 0.202)
		(layer "F.Cu")
		(net 16)
	)
	(via
		(at 203.5935 164.35)
		(size 0.45)
		(drill 0.1)
		(layers "F.Cu" "B.Cu")
		(teardrops
			(best_length_ratio 0.4)
			(max_length 1)
			(best_width_ratio 0.9)
			(max_width 2)
			(curved_edges yes)
			(filter_ratio 0.9)
			(enabled yes)
			(allow_two_segments yes)
			(prefer_zone_connections yes)
		)
		(net 16)
	)
	(via
		(at 206.323 131.4)
		(size 0.45)
		(drill 0.1)
		(layers "F.Cu" "B.Cu")
		(teardrops
			(best_length_ratio 0.4)
			(max_length 1)
			(best_width_ratio 0.9)
			(max_width 2)
			(curved_edges yes)
			(filter_ratio 0.9)
			(enabled yes)
			(allow_two_segments yes)
			(prefer_zone_connections yes)
		)
		(net 16)
	)
	(segment
		(start 206.687 157.827458)
		(end 206.687 147.727458)
		(width 0.178)
		(layer "In5.Cu")
		(net 16)
	)
	(segment
		(start 203.462 164.2185)
		(end 203.462 161.052458)
		(width 0.178)
		(layer "In5.Cu")
		(net 16)
	)
	(segment
		(start 203.462 161.052458)
		(end 206.687 157.827458)
		(width 0.178)
		(layer "In5.Cu")
		(net 16)
	)
	(segment
		(start 206.187 137.272542)
		(end 206.187 131.536)
		(width 0.178)
		(layer "In5.Cu")
		(net 16)
	)
	(segment
		(start 207.987 146.427458)
		(end 207.987 139.072542)
		(width 0.178)
		(layer "In5.Cu")
		(net 16)
	)
	(segment
		(start 206.187 131.536)
		(end 206.323 131.4)
		(width 0.178)
		(layer "In5.Cu")
		(net 16)
	)
	(segment
		(start 206.687 147.727458)
		(end 207.987 146.427458)
		(width 0.178)
		(layer "In5.Cu")
		(net 16)
	)
	(segment
		(start 207.987 139.072542)
		(end 206.187 137.272542)
		(width 0.178)
		(layer "In5.Cu")
		(net 16)
	)
	(segment
		(start 203.5935 164.35)
		(end 203.462 164.2185)
		(width 0.178)
		(layer "In5.Cu")
		(net 16)
	)
	(segment
		(start 157.528934 83.004)
		(end 157.9055 83.380566)
		(width 0.202)
		(layer "F.Cu")
		(net 19)
	)
	(segment
		(start 195.1555 122.580566)
		(end 195.1555 128.080566)
		(width 0.202)
		(layer "F.Cu")
		(net 19)
	)
	(segment
		(start 157.9055 85.930566)
		(end 163.519434 91.5445)
		(width 0.202)
		(layer "F.Cu")
		(net 19)
	)
	(segment
		(start 214.6745 136.350566)
		(end 214.6745 135.8105)
		(width 0.202)
		(layer "F.Cu")
		(net 19)
	)
	(segment
		(start 213.780566 137.2445)
		(end 214.6745 136.350566)
		(width 0.202)
		(layer "F.Cu")
		(net 19)
	)
	(segment
		(start 154.254 83.004)
		(end 157.528934 83.004)
		(width 0.202)
		(layer "F.Cu")
		(net 19)
	)
	(segment
		(start 153.5735 83.0595)
		(end 154.1985 83.0595)
		(width 0.202)
		(layer "F.Cu")
		(net 19)
	)
	(segment
		(start 182.219434 86.4945)
		(end 188.5055 92.780566)
		(width 0.202)
		(layer "F.Cu")
		(net 19)
	)
	(segment
		(start 154.1985 83.0595)
		(end 154.254 83.004)
		(width 0.202)
		(layer "F.Cu")
		(net 19)
	)
	(segment
		(start 214.98 135.505)
		(end 214.98 135.48)
		(width 0.202)
		(layer "F.Cu")
		(net 19)
	)
	(segment
		(start 188.5055 115.930566)
		(end 195.1555 122.580566)
		(width 0.202)
		(layer "F.Cu")
		(net 19)
	)
	(segment
		(start 170.280566 91.5445)
		(end 175.330566 86.4945)
		(width 0.202)
		(layer "F.Cu")
		(net 19)
	)
	(segment
		(start 214.6745 135.8105)
		(end 214.98 135.505)
		(width 0.202)
		(layer "F.Cu")
		(net 19)
	)
	(segment
		(start 188.5055 92.780566)
		(end 188.5055 115.930566)
		(width 0.202)
		(layer "F.Cu")
		(net 19)
	)
	(segment
		(start 204.319434 137.2445)
		(end 213.780566 137.2445)
		(width 0.202)
		(layer "F.Cu")
		(net 19)
	)
	(segment
		(start 163.519434 91.5445)
		(end 170.280566 91.5445)
		(width 0.202)
		(layer "F.Cu")
		(net 19)
	)
	(segment
		(start 175.330566 86.4945)
		(end 182.219434 86.4945)
		(width 0.202)
		(layer "F.Cu")
		(net 19)
	)
	(segment
		(start 157.9055 83.380566)
		(end 157.9055 85.930566)
		(width 0.202)
		(layer "F.Cu")
		(net 19)
	)
	(segment
		(start 195.1555 128.080566)
		(end 204.319434 137.2445)
		(width 0.202)
		(layer "F.Cu")
		(net 19)
	)
	(segment
		(start 188.8945 92.619434)
		(end 182.380566 86.1055)
		(width 0.202)
		(layer "F.Cu")
		(net 21)
	)
	(segment
		(start 154.1985 82.5595)
		(end 153.5735 82.5595)
		(width 0.202)
		(layer "F.Cu")
		(net 21)
	)
	(segment
		(start 212.620793 136.6555)
		(end 212.620793 136.561549)
		(width 0.202)
		(layer "F.Cu")
		(net 21)
	)
	(segment
		(start 154.254 82.615)
		(end 154.1985 82.5595)
		(width 0.202)
		(layer "F.Cu")
		(net 21)
	)
	(segment
		(start 213.619434 136.8555)
		(end 212.820793 136.8555)
		(width 0.202)
		(layer "F.Cu")
		(net 21)
	)
	(segment
		(start 175.169434 86.1055)
		(end 170.119434 91.1555)
		(width 0.202)
		(layer "F.Cu")
		(net 21)
	)
	(segment
		(start 211.920793 136.8555)
		(end 211.820793 136.8555)
		(width 0.202)
		(layer "F.Cu")
		(net 21)
	)
	(segment
		(start 182.380566 86.1055)
		(end 175.169434 86.1055)
		(width 0.202)
		(layer "F.Cu")
		(net 21)
	)
	(segment
		(start 157.690066 82.615)
		(end 154.254 82.615)
		(width 0.202)
		(layer "F.Cu")
		(net 21)
	)
	(segment
		(start 214.2855 135.8105)
		(end 214.2855 136.189434)
		(width 0.202)
		(layer "F.Cu")
		(net 21)
	)
	(segment
		(start 214.2855 136.189434)
		(end 213.619434 136.8555)
		(width 0.202)
		(layer "F.Cu")
		(net 21)
	)
	(segment
		(start 158.2945 83.219434)
		(end 157.690066 82.615)
		(width 0.202)
		(layer "F.Cu")
		(net 21)
	)
	(segment
		(start 213.98 135.505)
		(end 214.2855 135.8105)
		(width 0.202)
		(layer "F.Cu")
		(net 21)
	)
	(segment
		(start 195.5445 127.919434)
		(end 195.5445 122.419434)
		(width 0.202)
		(layer "F.Cu")
		(net 21)
	)
	(segment
		(start 158.2945 85.769434)
		(end 158.2945 83.219434)
		(width 0.202)
		(layer "F.Cu")
		(net 21)
	)
	(segment
		(start 195.5445 122.419434)
		(end 188.8945 115.769434)
		(width 0.202)
		(layer "F.Cu")
		(net 21)
	)
	(segment
		(start 211.820793 136.8555)
		(end 211.298157 136.8555)
		(width 0.202)
		(layer "F.Cu")
		(net 21)
	)
	(segment
		(start 212.120793 136.561549)
		(end 212.120793 136.6555)
		(width 0.202)
		(layer "F.Cu")
		(net 21)
	)
	(segment
		(start 170.119434 91.1555)
		(end 163.680566 91.1555)
		(width 0.202)
		(layer "F.Cu")
		(net 21)
	)
	(segment
		(start 188.8945 115.769434)
		(end 188.8945 92.619434)
		(width 0.202)
		(layer "F.Cu")
		(net 21)
	)
	(segment
		(start 163.680566 91.1555)
		(end 158.2945 85.769434)
		(width 0.202)
		(layer "F.Cu")
		(net 21)
	)
	(segment
		(start 212.420793 136.361549)
		(end 212.320793 136.361549)
		(width 0.202)
		(layer "F.Cu")
		(net 21)
	)
	(segment
		(start 204.480566 136.8555)
		(end 195.5445 127.919434)
		(width 0.202)
		(layer "F.Cu")
		(net 21)
	)
	(segment
		(start 211.298157 136.8555)
		(end 204.480566 136.8555)
		(width 0.202)
		(layer "F.Cu")
		(net 21)
	)
	(segment
		(start 213.98 135.48)
		(end 213.98 135.505)
		(width 0.202)
		(layer "F.Cu")
		(net 21)
	)
	(arc
		(start 212.120793 136.6555)
		(mid 212.062214 136.796921)
		(end 211.920793 136.8555)
		(width 0.202)
		(layer "F.Cu")
		(net 21)
	)
	(arc
		(start 212.620793 136.561549)
		(mid 212.562214 136.420128)
		(end 212.420793 136.361549)
		(width 0.202)
		(layer "F.Cu")
		(net 21)
	)
	(arc
		(start 212.320793 136.361549)
		(mid 212.179372 136.420128)
		(end 212.120793 136.561549)
		(width 0.202)
		(layer "F.Cu")
		(net 21)
	)
	(arc
		(start 212.820793 136.8555)
		(mid 212.679372 136.796921)
		(end 212.620793 136.6555)
		(width 0.202)
		(layer "F.Cu")
		(net 21)
	)
	(segment
		(start 143.93 84.06)
		(end 144.35 84.06)
		(width 0.125)
		(layer "F.Cu")
		(net 23)
	)
	(segment
		(start 143.93 85.06)
		(end 143.93 84.06)
		(width 0.125)
		(layer "F.Cu")
		(net 23)
	)
	(segment
		(start 144.35 84.06)
		(end 144.6005 83.8095)
		(width 0.125)
		(layer "F.Cu")
		(net 23)
	)
	(segment
		(start 144.6005 83.8095)
		(end 146.0755 83.8095)
		(width 0.125)
		(layer "F.Cu")
		(net 23)
	)
	(segment
		(start 154.7305 84.06)
		(end 154.73 84.0595)
		(width 0.125)
		(layer "F.Cu")
		(net 24)
	)
	(segment
		(start 154.73 84.0595)
		(end 153.5735 84.0595)
		(width 0.125)
		(layer "F.Cu")
		(net 24)
	)
	(segment
		(start 155.67 84.06)
		(end 154.7305 84.06)
		(width 0.125)
		(layer "F.Cu")
		(net 24)
	)
	(via
		(at 154.73 84.0595)
		(size 0.45)
		(drill 0.1)
		(layers "F.Cu" "B.Cu")
		(remove_unused_layers yes)
		(keep_end_layers yes)
		(zone_layer_connections "In2.Cu")
		(teardrops
			(best_length_ratio 0.4)
			(max_length 1)
			(best_width_ratio 0.9)
			(max_width 2)
			(curved_edges yes)
			(filter_ratio 0.9)
			(enabled yes)
			(allow_two_segments yes)
			(prefer_zone_connections yes)
		)
		(net 24)
	)
	(via
		(at 216.925 137.42)
		(size 0.45)
		(drill 0.1)
		(layers "F.Cu" "B.Cu")
		(remove_unused_layers yes)
		(keep_end_layers yes)
		(zone_layer_connections "In2.Cu")
		(teardrops
			(best_length_ratio 0.4)
			(max_length 1)
			(best_width_ratio 0.9)
			(max_width 2)
			(curved_edges yes)
			(filter_ratio 0.9)
			(enabled yes)
			(allow_two_segments yes)
			(prefer_zone_connections yes)
		)
		(net 24)
	)
	(segment
		(start 201.25 119.45)
		(end 205.15 123.35)
		(width 0.125)
		(layer "In2.Cu")
		(net 24)
	)
	(segment
		(start 207.94 132.4)
		(end 212.39 132.4)
		(width 0.125)
		(layer "In2.Cu")
		(net 24)
	)
	(segment
		(start 205.15 123.35)
		(end 205.15 129.61)
		(width 0.125)
		(layer "In2.Cu")
		(net 24)
	)
	(segment
		(start 205.15 129.61)
		(end 207.94 132.4)
		(width 0.125)
		(layer "In2.Cu")
		(net 24)
	)
	(segment
		(start 178.64 119.45)
		(end 201.25 119.45)
		(width 0.125)
		(layer "In2.Cu")
		(net 24)
	)
	(segment
		(start 216.925 136.935)
		(end 216.925 137.42)
		(width 0.125)
		(layer "In2.Cu")
		(net 24)
	)
	(segment
		(start 154.73 84.0595)
		(end 154.73 95.54)
		(width 0.125)
		(layer "In2.Cu")
		(net 24)
	)
	(segment
		(start 212.39 132.4)
		(end 216.925 136.935)
		(width 0.125)
		(layer "In2.Cu")
		(net 24)
	)
	(segment
		(start 154.73 95.54)
		(end 178.64 119.45)
		(width 0.125)
		(layer "In2.Cu")
		(net 24)
	)
	(segment
		(start 144.35 83.06)
		(end 144.5995 83.3095)
		(width 0.125)
		(layer "F.Cu")
		(net 38)
	)
	(segment
		(start 143.93 83.06)
		(end 144.35 83.06)
		(width 0.125)
		(layer "F.Cu")
		(net 38)
	)
	(segment
		(start 144.5995 83.3095)
		(end 146.0755 83.3095)
		(width 0.125)
		(layer "F.Cu")
		(net 38)
	)
	(segment
		(start 310.58 74.81)
		(end 310.15 74.38)
		(width 0.3)
		(layer "F.Cu")
		(net 41)
	)
	(segment
		(start 310.15 74.38)
		(end 310.15 73.56)
		(width 0.3)
		(layer "F.Cu")
		(net 41)
	)
	(via
		(at 111.35 86.46)
		(size 0.45)
		(drill 0.1)
		(layers "F.Cu" "B.Cu")
		(remove_unused_layers yes)
		(keep_end_layers yes)
		(free yes)
		(zone_layer_connections "In3.Cu")
		(teardrops
			(best_length_ratio 0.4)
			(max_length 1)
			(best_width_ratio 0.9)
			(max_width 2)
			(curved_edges yes)
			(filter_ratio 0.9)
			(enabled yes)
			(allow_two_segments yes)
			(prefer_zone_connections yes)
		)
		(net 42)
	)
	(via
		(at 109.6 86.46)
		(size 0.45)
		(drill 0.1)
		(layers "F.Cu" "B.Cu")
		(remove_unused_layers yes)
		(keep_end_layers yes)
		(free yes)
		(zone_layer_connections "In3.Cu")
		(teardrops
			(best_length_ratio 0.4)
			(max_length 1)
			(best_width_ratio 0.9)
			(max_width 2)
			(curved_edges yes)
			(filter_ratio 0.9)
			(enabled yes)
			(allow_two_segments yes)
			(prefer_zone_connections yes)
		)
		(net 42)
	)
	(via
		(at 110.45 86.46)
		(size 0.45)
		(drill 0.1)
		(layers "F.Cu" "B.Cu")
		(remove_unused_layers yes)
		(keep_end_layers yes)
		(free yes)
		(zone_layer_connections "In3.Cu")
		(teardrops
			(best_length_ratio 0.4)
			(max_length 1)
			(best_width_ratio 0.9)
			(max_width 2)
			(curved_edges yes)
			(filter_ratio 0.9)
			(enabled yes)
			(allow_two_segments yes)
			(prefer_zone_connections yes)
		)
		(net 42)
	)
	(via
		(at 112.25 86.46)
		(size 0.45)
		(drill 0.1)
		(layers "F.Cu" "B.Cu")
		(remove_unused_layers yes)
		(keep_end_layers yes)
		(free yes)
		(zone_layer_connections "In3.Cu")
		(teardrops
			(best_length_ratio 0.4)
			(max_length 1)
			(best_width_ratio 0.9)
			(max_width 2)
			(curved_edges yes)
			(filter_ratio 0.9)
			(enabled yes)
			(allow_two_segments yes)
			(prefer_zone_connections yes)
		)
		(net 42)
	)
	(via
		(at 110.45 91.31)
		(size 0.45)
		(drill 0.1)
		(layers "F.Cu" "B.Cu")
		(remove_unused_layers yes)
		(keep_end_layers yes)
		(free yes)
		(zone_layer_connections "In3.Cu")
		(teardrops
			(best_length_ratio 0.4)
			(max_length 1)
			(best_width_ratio 0.9)
			(max_width 2)
			(curved_edges yes)
			(filter_ratio 0.9)
			(enabled yes)
			(allow_two_segments yes)
			(prefer_zone_connections yes)
		)
		(net 43)
	)
	(via
		(at 109.6 91.31)
		(size 0.45)
		(drill 0.1)
		(layers "F.Cu" "B.Cu")
		(remove_unused_layers yes)
		(keep_end_layers yes)
		(free yes)
		(zone_layer_connections "In3.Cu")
		(teardrops
			(best_length_ratio 0.4)
			(max_length 1)
			(best_width_ratio 0.9)
			(max_width 2)
			(curved_edges yes)
			(filter_ratio 0.9)
			(enabled yes)
			(allow_two_segments yes)
			(prefer_zone_connections yes)
		)
		(net 43)
	)
	(via
		(at 112.25 91.31)
		(size 0.45)
		(drill 0.1)
		(layers "F.Cu" "B.Cu")
		(remove_unused_layers yes)
		(keep_end_layers yes)
		(free yes)
		(zone_layer_connections "In3.Cu")
		(teardrops
			(best_length_ratio 0.4)
			(max_length 1)
			(best_width_ratio 0.9)
			(max_width 2)
			(curved_edges yes)
			(filter_ratio 0.9)
			(enabled yes)
			(allow_two_segments yes)
			(prefer_zone_connections yes)
		)
		(net 43)
	)
	(via
		(at 111.35 91.31)
		(size 0.45)
		(drill 0.1)
		(layers "F.Cu" "B.Cu")
		(remove_unused_layers yes)
		(keep_end_layers yes)
		(free yes)
		(zone_layer_connections "In3.Cu")
		(teardrops
			(best_length_ratio 0.4)
			(max_length 1)
			(best_width_ratio 0.9)
			(max_width 2)
			(curved_edges yes)
			(filter_ratio 0.9)
			(enabled yes)
			(allow_two_segments yes)
			(prefer_zone_connections yes)
		)
		(net 43)
	)
	(segment
		(start 180.465 149.6825)
		(end 180.5975 149.55)
		(width 0.185)
		(layer "F.Cu")
		(net 44)
	)
	(segment
		(start 180.525 150.41)
		(end 180.465 150.35)
		(width 0.185)
		(layer "F.Cu")
		(net 44)
	)
	(segment
		(start 180.465 150.35)
		(end 180.465 149.6825)
		(width 0.185)
		(layer "F.Cu")
		(net 44)
	)
	(segment
		(start 180.525 151.135)
		(end 180.525 150.41)
		(width 0.185)
		(layer "F.Cu")
		(net 44)
	)
	(via
		(at 98.361224 103.998776)
		(size 0.45)
		(drill 0.1)
		(layers "F.Cu" "B.Cu")
		(net 44)
	)
	(via
		(at 180.5975 149.55)
		(size 0.45)
		(drill 0.1)
		(layers "F.Cu" "B.Cu")
		(teardrops
			(best_length_ratio 0.4)
			(max_length 1)
			(best_width_ratio 0.9)
			(max_width 2)
			(curved_edges yes)
			(filter_ratio 0.9)
			(enabled yes)
			(allow_two_segments yes)
			(prefer_zone_connections yes)
		)
		(net 44)
	)
	(segment
		(start 98.361224 104.192523)
		(end 98.595701 104.427)
		(width 0.185)
		(layer "B.Cu")
		(net 44)
	)
	(segment
		(start 101.325 104.367)
		(end 101.282 104.41)
		(width 0.185)
		(layer "B.Cu")
		(net 44)
	)
	(segment
		(start 107.240079 102.637107)
		(end 107.515721 102.361465)
		(width 0.185)
		(layer "B.Cu")
		(net 44)
	)
	(segment
		(start 104.224302 102.93)
		(end 106.532972 102.93)
		(width 0.185)
		(layer "B.Cu")
		(net 44)
	)
	(segment
		(start 101.282 104.41)
		(end 100.596 104.41)
		(width 0.185)
		(layer "B.Cu")
		(net 44)
	)
	(segment
		(start 100.403 104.367)
		(end 100.553 104.367)
		(width 0.185)
		(layer "B.Cu")
		(net 44)
	)
	(segment
		(start 98.361224 103.998776)
		(end 98.361224 104.192523)
		(width 0.185)
		(layer "B.Cu")
		(net 44)
	)
	(segment
		(start 101.535 104.427)
		(end 101.627917 104.427)
		(width 0.185)
		(layer "B.Cu")
		(net 44)
	)
	(segment
		(start 101.475 104.367)
		(end 101.535 104.427)
		(width 0.185)
		(layer "B.Cu")
		(net 44)
	)
	(segment
		(start 107.701036 101.913964)
		(end 108.25 101.365)
		(width 0.185)
		(layer "B.Cu")
		(net 44)
	)
	(segment
		(start 100.596 104.41)
		(end 100.553 104.367)
		(width 0.185)
		(layer "B.Cu")
		(net 44)
	)
	(segment
		(start 98.595701 104.427)
		(end 100.343 104.427)
		(width 0.185)
		(layer "B.Cu")
		(net 44)
	)
	(segment
		(start 101.840049 104.339132)
		(end 102.559667 103.619514)
		(width 0.185)
		(layer "B.Cu")
		(net 44)
	)
	(segment
		(start 100.343 104.427)
		(end 100.403 104.367)
		(width 0.185)
		(layer "B.Cu")
		(net 44)
	)
	(arc
		(start 107.515721 102.361465)
		(mid 107.609562 102.221012)
		(end 107.6425 102.055343)
		(width 0.185)
		(layer "B.Cu")
		(net 44)
	)
	(arc
		(start 104.224302 102.93)
		(mid 103.323408 103.109199)
		(end 102.559667 103.619514)
		(width 0.185)
		(layer "B.Cu")
		(net 44)
	)
	(arc
		(start 101.627917 104.427)
		(mid 101.742722 104.404164)
		(end 101.840049 104.339132)
		(width 0.185)
		(layer "B.Cu")
		(net 44)
	)
	(arc
		(start 107.240079 102.637107)
		(mid 106.915656 102.85388)
		(end 106.532972 102.93)
		(width 0.185)
		(layer "B.Cu")
		(net 44)
	)
	(arc
		(start 107.701036 101.913964)
		(mid 107.657705 101.978821)
		(end 107.6425 102.055343)
		(width 0.185)
		(layer "B.Cu")
		(net 44)
	)
	(segment
		(start 180.5975 149.55)
		(end 180.4565 149.409)
		(width 0.159)
		(layer "In5.Cu")
		(net 44)
	)
	(segment
		(start 98.361224 104.204544)
		(end 98.361224 103.998776)
		(width 0.159)
		(layer "In5.Cu")
		(net 44)
	)
	(segment
		(start 161.75018 120.1185)
		(end 105.47518 120.1185)
		(width 0.159)
		(layer "In5.Cu")
		(net 44)
	)
	(segment
		(start 180.4565 149.409)
		(end 180.4565 148.94982)
		(width 0.159)
		(layer "In5.Cu")
		(net 44)
	)
	(segment
		(start 180.4565 148.94982)
		(end 174.8065 143.29982)
		(width 0.159)
		(layer "In5.Cu")
		(net 44)
	)
	(segment
		(start 105.47518 120.1185)
		(end 99.6565 114.29982)
		(width 0.159)
		(layer "In5.Cu")
		(net 44)
	)
	(segment
		(start 99.6565 105.49982)
		(end 98.361224 104.204544)
		(width 0.159)
		(layer "In5.Cu")
		(net 44)
	)
	(segment
		(start 174.8065 133.17482)
		(end 161.75018 120.1185)
		(width 0.159)
		(layer "In5.Cu")
		(net 44)
	)
	(segment
		(start 174.8065 143.29982)
		(end 174.8065 133.17482)
		(width 0.159)
		(layer "In5.Cu")
		(net 44)
	)
	(segment
		(start 99.6565 114.29982)
		(end 99.6565 105.49982)
		(width 0.159)
		(layer "In5.Cu")
		(net 44)
	)
	(segment
		(start 182.025 150.41)
		(end 181.965 150.35)
		(width 0.185)
		(layer "F.Cu")
		(net 45)
	)
	(segment
		(start 181.965 149.7075)
		(end 182.0975 149.575)
		(width 0.185)
		(layer "F.Cu")
		(net 45)
	)
	(segment
		(start 182.025 151.135)
		(end 182.025 150.41)
		(width 0.185)
		(layer "F.Cu")
		(net 45)
	)
	(segment
		(start 181.965 150.35)
		(end 181.965 149.7075)
		(width 0.185)
		(layer "F.Cu")
		(net 45)
	)
	(via
		(at 182.0975 149.575)
		(size 0.45)
		(drill 0.1)
		(layers "F.Cu" "B.Cu")
		(teardrops
			(best_length_ratio 0.4)
			(max_length 1)
			(best_width_ratio 0.9)
			(max_width 2)
			(curved_edges yes)
			(filter_ratio 0.9)
			(enabled yes)
			(allow_two_segments yes)
			(prefer_zone_connections yes)
		)
		(net 45)
	)
	(via
		(at 126.769736 103.2295)
		(size 0.45)
		(drill 0.1)
		(layers "F.Cu" "B.Cu")
		(remove_unused_layers yes)
		(keep_end_layers yes)
		(zone_layer_connections)
		(teardrops
			(best_length_ratio 0.4)
			(max_length 1)
			(best_width_ratio 0.9)
			(max_width 2)
			(curved_edges yes)
			(filter_ratio 0.9)
			(enabled yes)
			(allow_two_segments yes)
			(prefer_zone_connections yes)
		)
		(net 45)
	)
	(segment
		(start 123.013 103.302)
		(end 123.785 103.302)
		(width 0.185)
		(layer "B.Cu")
		(net 45)
	)
	(segment
		(start 118.049964 99.771262)
		(end 121.054916 102.776214)
		(width 0.185)
		(layer "B.Cu")
		(net 45)
	)
	(segment
		(start 113.177818 101.83348)
		(end 113.18233 101.828967)
		(width 0.185)
		(layer "B.Cu")
		(net 45)
	)
	(segment
		(start 122.469129 103.362)
		(end 122.803 103.362)
		(width 0.185)
		(layer "B.Cu")
		(net 45)
	)
	(segment
		(start 122.803 103.362)
		(end 122.863 103.302)
		(width 0.185)
		(layer "B.Cu")
		(net 45)
	)
	(segment
		(start 123.935 103.302)
		(end 123.995 103.362)
		(width 0.185)
		(layer "B.Cu")
		(net 45)
	)
	(segment
		(start 126.637236 103.362)
		(end 126.769736 103.2295)
		(width 0.185)
		(layer "B.Cu")
		(net 45)
	)
	(segment
		(start 113.933267 99.648031)
		(end 114.075359 99.505939)
		(width 0.185)
		(layer "B.Cu")
		(net 45)
	)
	(segment
		(start 111.45 101.365)
		(end 112.26 102.175)
		(width 0.185)
		(layer "B.Cu")
		(net 45)
	)
	(segment
		(start 115.103668 99.08)
		(end 116.381109 99.08)
		(width 0.185)
		(layer "B.Cu")
		(net 45)
	)
	(segment
		(start 123.995 103.362)
		(end 126.637236 103.362)
		(width 0.185)
		(layer "B.Cu")
		(net 45)
	)
	(segment
		(start 113.158481 101.852817)
		(end 113.177818 101.83348)
		(width 0.185)
		(layer "B.Cu")
		(net 45)
	)
	(segment
		(start 112.26 102.175)
		(end 112.380663 102.175)
		(width 0.185)
		(layer "B.Cu")
		(net 45)
	)
	(segment
		(start 113.5 101.062019)
		(end 113.5 100.69403)
		(width 0.185)
		(layer "B.Cu")
		(net 45)
	)
	(arc
		(start 113.158481 101.852817)
		(mid 112.801615 102.091267)
		(end 112.380663 102.175)
		(width 0.185)
		(layer "B.Cu")
		(net 45)
	)
	(arc
		(start 118.049964 99.771262)
		(mid 117.284287 99.259653)
		(end 116.381109 99.08)
		(width 0.185)
		(layer "B.Cu")
		(net 45)
	)
	(arc
		(start 121.054916 102.776214)
		(mid 121.703762 103.209759)
		(end 122.469129 103.362)
		(width 0.185)
		(layer "B.Cu")
		(net 45)
	)
	(arc
		(start 113.933267 99.648031)
		(mid 113.612602 100.127939)
		(end 113.5 100.69403)
		(width 0.185)
		(layer "B.Cu")
		(net 45)
	)
	(arc
		(start 114.075359 99.505939)
		(mid 114.547151 99.190698)
		(end 115.103668 99.08)
		(width 0.185)
		(layer "B.Cu")
		(net 45)
	)
	(arc
		(start 113.18233 101.828967)
		(mid 113.41744 101.477086)
		(end 113.5 101.062019)
		(width 0.185)
		(layer "B.Cu")
		(net 45)
	)
	(segment
		(start 176.6315 142.39982)
		(end 181.9565 147.72482)
		(width 0.159)
		(layer "In5.Cu")
		(net 45)
	)
	(segment
		(start 138.22518 118.2435)
		(end 163.02518 118.2435)
		(width 0.159)
		(layer "In5.Cu")
		(net 45)
	)
	(segment
		(start 128.377195 103.970515)
		(end 128.377195 104.949485)
		(width 0.159)
		(layer "In5.Cu")
		(net 45)
	)
	(segment
		(start 126.6215 106.70518)
		(end 126.6215 108.57482)
		(width 0.159)
		(layer "In5.Cu")
		(net 45)
	)
	(segment
		(start 126.769736 103.2295)
		(end 126.910736 103.3705)
		(width 0.159)
		(layer "In5.Cu")
		(net 45)
	)
	(segment
		(start 129.20018 109.2185)
		(end 138.22518 118.2435)
		(width 0.159)
		(layer "In5.Cu")
		(net 45)
	)
	(segment
		(start 181.9565 149.434)
		(end 182.0975 149.575)
		(width 0.159)
		(layer "In5.Cu")
		(net 45)
	)
	(segment
		(start 181.9565 147.72482)
		(end 181.9565 149.434)
		(width 0.159)
		(layer "In5.Cu")
		(net 45)
	)
	(segment
		(start 176.6315 131.84982)
		(end 176.6315 142.39982)
		(width 0.159)
		(layer "In5.Cu")
		(net 45)
	)
	(segment
		(start 128.377195 104.949485)
		(end 126.6215 106.70518)
		(width 0.159)
		(layer "In5.Cu")
		(net 45)
	)
	(segment
		(start 126.910736 103.3705)
		(end 127.77718 103.3705)
		(width 0.159)
		(layer "In5.Cu")
		(net 45)
	)
	(segment
		(start 126.6215 108.57482)
		(end 127.26518 109.2185)
		(width 0.159)
		(layer "In5.Cu")
		(net 45)
	)
	(segment
		(start 163.02518 118.2435)
		(end 176.6315 131.84982)
		(width 0.159)
		(layer "In5.Cu")
		(net 45)
	)
	(segment
		(start 127.77718 103.3705)
		(end 128.377195 103.970515)
		(width 0.159)
		(layer "In5.Cu")
		(net 45)
	)
	(segment
		(start 127.26518 109.2185)
		(end 129.20018 109.2185)
		(width 0.159)
		(layer "In5.Cu")
		(net 45)
	)
	(segment
		(start 244.377 130.56)
		(end 244.377 131.451)
		(width 0.125)
		(layer "F.Cu")
		(net 46)
	)
	(segment
		(start 244.377 131.451)
		(end 244.8 131.874)
		(width 0.125)
		(layer "F.Cu")
		(net 46)
	)
	(segment
		(start 180.085 150.35)
		(end 180.085 149.6825)
		(width 0.185)
		(layer "F.Cu")
		(net 47)
	)
	(segment
		(start 180.025 151.135)
		(end 180.025 150.41)
		(width 0.185)
		(layer "F.Cu")
		(net 47)
	)
	(segment
		(start 180.085 149.6825)
		(end 179.9525 149.55)
		(width 0.185)
		(layer "F.Cu")
		(net 47)
	)
	(segment
		(start 180.025 150.41)
		(end 180.085 150.35)
		(width 0.185)
		(layer "F.Cu")
		(net 47)
	)
	(via
		(at 97.898776 104.461224)
		(size 0.45)
		(drill 0.1)
		(layers "F.Cu" "B.Cu")
		(net 47)
	)
	(via
		(at 179.9525 149.55)
		(size 0.45)
		(drill 0.1)
		(layers "F.Cu" "B.Cu")
		(teardrops
			(best_length_ratio 0.4)
			(max_length 1)
			(best_width_ratio 0.9)
			(max_width 2)
			(curved_edges yes)
			(filter_ratio 0.9)
			(enabled yes)
			(allow_two_segments yes)
			(prefer_zone_connections yes)
		)
		(net 47)
	)
	(segment
		(start 100.343 104.807)
		(end 100.403 104.867)
		(width 0.185)
		(layer "B.Cu")
		(net 47)
	)
	(segment
		(start 101.268 104.81)
		(end 100.61 104.81)
		(width 0.185)
		(layer "B.Cu")
		(net 47)
	)
	(segment
		(start 105.332 103.31)
		(end 105.282 103.31)
		(width 0.185)
		(layer "B.Cu")
		(net 47)
	)
	(segment
		(start 98.438299 104.807)
		(end 100.343 104.807)
		(width 0.185)
		(layer "B.Cu")
		(net 47)
	)
	(segment
		(start 100.403 104.867)
		(end 100.553 104.867)
		(width 0.185)
		(layer "B.Cu")
		(net 47)
	)
	(segment
		(start 107.508357 102.906201)
		(end 107.50647 102.908088)
		(width 0.185)
		(layer "B.Cu")
		(net 47)
	)
	(segment
		(start 98.092523 104.461224)
		(end 98.438299 104.807)
		(width 0.185)
		(layer "B.Cu")
		(net 47)
	)
	(segment
		(start 105.732 103.66)
		(end 105.682 103.66)
		(width 0.185)
		(layer "B.Cu")
		(net 47)
	)
	(segment
		(start 102.820798 103.895787)
		(end 102.107721 104.608864)
		(width 0.185)
		(layer "B.Cu")
		(net 47)
	)
	(segment
		(start 108.25 103.365)
		(end 107.7912 102.9062)
		(width 0.185)
		(layer "B.Cu")
		(net 47)
	)
	(segment
		(start 100.61 104.81)
		(end 100.553 104.867)
		(width 0.185)
		(layer "B.Cu")
		(net 47)
	)
	(segment
		(start 101.62934 104.807003)
		(end 101.571073 104.807)
		(width 0.185)
		(layer "B.Cu")
		(net 47)
	)
	(segment
		(start 97.898776 104.461224)
		(end 98.092523 104.461224)
		(width 0.185)
		(layer "B.Cu")
		(net 47)
	)
	(segment
		(start 105.282 103.31)
		(end 104.235012 103.31)
		(width 0.185)
		(layer "B.Cu")
		(net 47)
	)
	(segment
		(start 106.536167 103.31)
		(end 106.082 103.31)
		(width 0.185)
		(layer "B.Cu")
		(net 47)
	)
	(segment
		(start 101.571073 104.807)
		(end 101.535 104.807)
		(width 0.185)
		(layer "B.Cu")
		(net 47)
	)
	(segment
		(start 101.535 104.807)
		(end 101.475 104.867)
		(width 0.185)
		(layer "B.Cu")
		(net 47)
	)
	(segment
		(start 101.325 104.867)
		(end 101.268 104.81)
		(width 0.185)
		(layer "B.Cu")
		(net 47)
	)
	(arc
		(start 102.107721 104.608864)
		(mid 101.888238 104.755514)
		(end 101.62934 104.807003)
		(width 0.185)
		(layer "B.Cu")
		(net 47)
	)
	(arc
		(start 107.7912 102.9062)
		(mid 107.649778 102.847622)
		(end 107.508357 102.906201)
		(width 0.185)
		(layer "B.Cu")
		(net 47)
	)
	(arc
		(start 107.50647 102.908088)
		(mid 107.061291 103.205546)
		(end 106.536167 103.31)
		(width 0.185)
		(layer "B.Cu")
		(net 47)
	)
	(arc
		(start 105.907 103.485)
		(mid 105.855744 103.608744)
		(end 105.732 103.66)
		(width 0.185)
		(layer "B.Cu")
		(net 47)
	)
	(arc
		(start 106.082 103.31)
		(mid 105.958256 103.361256)
		(end 105.907 103.485)
		(width 0.185)
		(layer "B.Cu")
		(net 47)
	)
	(arc
		(start 105.682 103.66)
		(mid 105.558256 103.608744)
		(end 105.507 103.485)
		(width 0.185)
		(layer "B.Cu")
		(net 47)
	)
	(arc
		(start 104.235012 103.31)
		(mid 103.469645 103.462241)
		(end 102.820798 103.895787)
		(width 0.185)
		(layer "B.Cu")
		(net 47)
	)
	(arc
		(start 105.507 103.485)
		(mid 105.455744 103.361256)
		(end 105.332 103.31)
		(width 0.185)
		(layer "B.Cu")
		(net 47)
	)
	(segment
		(start 99.2935 114.45018)
		(end 99.2935 105.65018)
		(width 0.159)
		(layer "In5.Cu")
		(net 47)
	)
	(segment
		(start 174.4435 133.32518)
		(end 161.59982 120.4815)
		(width 0.159)
		(layer "In5.Cu")
		(net 47)
	)
	(segment
		(start 180.0935 149.409)
		(end 180.0935 149.10018)
		(width 0.159)
		(layer "In5.Cu")
		(net 47)
	)
	(segment
		(start 105.32482 120.4815)
		(end 99.2935 114.45018)
		(width 0.159)
		(layer "In5.Cu")
		(net 47)
	)
	(segment
		(start 99.2935 105.65018)
		(end 98.104544 104.461224)
		(width 0.159)
		(layer "In5.Cu")
		(net 47)
	)
	(segment
		(start 174.4435 143.45018)
		(end 174.4435 133.32518)
		(width 0.159)
		(layer "In5.Cu")
		(net 47)
	)
	(segment
		(start 179.9525 149.55)
		(end 180.0935 149.409)
		(width 0.159)
		(layer "In5.Cu")
		(net 47)
	)
	(segment
		(start 161.59982 120.4815)
		(end 105.32482 120.4815)
		(width 0.159)
		(layer "In5.Cu")
		(net 47)
	)
	(segment
		(start 180.0935 149.10018)
		(end 174.4435 143.45018)
		(width 0.159)
		(layer "In5.Cu")
		(net 47)
	)
	(segment
		(start 98.104544 104.461224)
		(end 97.898776 104.461224)
		(width 0.159)
		(layer "In5.Cu")
		(net 47)
	)
	(segment
		(start 243.569 128.79)
		(end 241.75 128.79)
		(width 0.125)
		(layer "F.Cu")
		(net 48)
	)
	(segment
		(start 243.725 128.634)
		(end 243.569 128.79)
		(width 0.125)
		(layer "F.Cu")
		(net 48)
	)
	(segment
		(start 243.725 127.959)
		(end 243.725 128.634)
		(width 0.125)
		(layer "F.Cu")
		(net 48)
	)
	(segment
		(start 181.525 150.41)
		(end 181.585 150.35)
		(width 0.185)
		(layer "F.Cu")
		(net 49)
	)
	(segment
		(start 181.525 151.135)
		(end 181.525 150.41)
		(width 0.185)
		(layer "F.Cu")
		(net 49)
	)
	(segment
		(start 181.585 150.35)
		(end 181.585 149.7075)
		(width 0.185)
		(layer "F.Cu")
		(net 49)
	)
	(segment
		(start 181.585 149.7075)
		(end 181.4525 149.575)
		(width 0.185)
		(layer "F.Cu")
		(net 49)
	)
	(via
		(at 181.4525 149.575)
		(size 0.45)
		(drill 0.1)
		(layers "F.Cu" "B.Cu")
		(teardrops
			(best_length_ratio 0.4)
			(max_length 1)
			(best_width_ratio 0.9)
			(max_width 2)
			(curved_edges yes)
			(filter_ratio 0.9)
			(enabled yes)
			(allow_two_segments yes)
			(prefer_zone_connections yes)
		)
		(net 49)
	)
	(via
		(at 126.769736 103.8745)
		(size 0.45)
		(drill 0.1)
		(layers "F.Cu" "B.Cu")
		(remove_unused_layers yes)
		(keep_end_layers yes)
		(zone_layer_connections)
		(teardrops
			(best_length_ratio 0.4)
			(max_length 1)
			(best_width_ratio 0.9)
			(max_width 2)
			(curved_edges yes)
			(filter_ratio 0.9)
			(enabled yes)
			(allow_two_segments yes)
			(prefer_zone_connections yes)
		)
		(net 49)
	)
	(segment
		(start 123.995 103.742)
		(end 126.637236 103.742)
		(width 0.185)
		(layer "B.Cu")
		(net 49)
	)
	(segment
		(start 115.114337 99.46)
		(end 116.372871 99.46)
		(width 0.185)
		(layer "B.Cu")
		(net 49)
	)
	(segment
		(start 112.26 102.555)
		(end 112.384923 102.555)
		(width 0.185)
		(layer "B.Cu")
		(net 49)
	)
	(segment
		(start 111.45 103.365)
		(end 112.26 102.555)
		(width 0.185)
		(layer "B.Cu")
		(net 49)
	)
	(segment
		(start 122.803 103.742)
		(end 122.863 103.802)
		(width 0.185)
		(layer "B.Cu")
		(net 49)
	)
	(segment
		(start 122.460021 103.742)
		(end 122.803 103.742)
		(width 0.185)
		(layer "B.Cu")
		(net 49)
	)
	(segment
		(start 117.787085 100.045787)
		(end 120.792651 103.051353)
		(width 0.185)
		(layer "B.Cu")
		(net 49)
	)
	(segment
		(start 114.202183 99.916519)
		(end 114.33652 99.782182)
		(width 0.185)
		(layer "B.Cu")
		(net 49)
	)
	(segment
		(start 123.935 103.802)
		(end 123.995 103.742)
		(width 0.185)
		(layer "B.Cu")
		(net 49)
	)
	(segment
		(start 113.88 101.069337)
		(end 113.88 100.694337)
		(width 0.185)
		(layer "B.Cu")
		(net 49)
	)
	(segment
		(start 113.456109 102.092593)
		(end 113.424233 102.124472)
		(width 0.185)
		(layer "B.Cu")
		(net 49)
	)
	(segment
		(start 126.637236 103.742)
		(end 126.769736 103.8745)
		(width 0.185)
		(layer "B.Cu")
		(net 49)
	)
	(segment
		(start 123.013 103.802)
		(end 123.785 103.802)
		(width 0.185)
		(layer "B.Cu")
		(net 49)
	)
	(arc
		(start 112.384923 102.555)
		(mid 112.9474 102.443109)
		(end 113.424233 102.124472)
		(width 0.185)
		(layer "B.Cu")
		(net 49)
	)
	(arc
		(start 115.114337 99.46)
		(mid 114.693386 99.543732)
		(end 114.33652 99.782182)
		(width 0.185)
		(layer "B.Cu")
		(net 49)
	)
	(arc
		(start 114.202183 99.916519)
		(mid 113.963733 100.273385)
		(end 113.88 100.694337)
		(width 0.185)
		(layer "B.Cu")
		(net 49)
	)
	(arc
		(start 113.456109 102.092593)
		(mid 113.769857 101.623072)
		(end 113.88 101.069337)
		(width 0.185)
		(layer "B.Cu")
		(net 49)
	)
	(arc
		(start 122.460021 103.742)
		(mid 121.557647 103.562507)
		(end 120.792651 103.051353)
		(width 0.185)
		(layer "B.Cu")
		(net 49)
	)
	(arc
		(start 116.372871 99.46)
		(mid 117.138238 99.612241)
		(end 117.787085 100.045787)
		(width 0.185)
		(layer "B.Cu")
		(net 49)
	)
	(segment
		(start 128.014195 104.120875)
		(end 128.014195 104.799125)
		(width 0.159)
		(layer "In5.Cu")
		(net 49)
	)
	(segment
		(start 126.2585 106.55482)
		(end 126.2585 108.72518)
		(width 0.159)
		(layer "In5.Cu")
		(net 49)
	)
	(segment
		(start 126.745715 106.067604)
		(end 126.71166 106.10166)
		(width 0.159)
		(layer "In5.Cu")
		(net 49)
	)
	(segment
		(start 128.014195 104.799125)
		(end 127.594244 105.219076)
		(width 0.159)
		(layer "In5.Cu")
		(net 49)
	)
	(segment
		(start 126.811644 105.624417)
		(end 126.830566 105.643339)
		(width 0.159)
		(layer "In5.Cu")
		(net 49)
	)
	(segment
		(start 162.87482 118.6065)
		(end 176.2685 132.00018)
		(width 0.159)
		(layer "In5.Cu")
		(net 49)
	)
	(segment
		(start 126.896497 105.200153)
		(end 126.811644 105.285005)
		(width 0.159)
		(layer "In5.Cu")
		(net 49)
	)
	(segment
		(start 126.769736 103.8745)
		(end 126.910736 103.7335)
		(width 0.159)
		(layer "In5.Cu")
		(net 49)
	)
	(segment
		(start 176.2685 132.00018)
		(end 176.2685 142.55018)
		(width 0.159)
		(layer "In5.Cu")
		(net 49)
	)
	(segment
		(start 129.04982 109.5815)
		(end 138.07482 118.6065)
		(width 0.159)
		(layer "In5.Cu")
		(net 49)
	)
	(segment
		(start 126.2585 108.72518)
		(end 127.11482 109.5815)
		(width 0.159)
		(layer "In5.Cu")
		(net 49)
	)
	(segment
		(start 138.07482 118.6065)
		(end 162.87482 118.6065)
		(width 0.159)
		(layer "In5.Cu")
		(net 49)
	)
	(segment
		(start 127.254832 105.219076)
		(end 127.235909 105.200153)
		(width 0.159)
		(layer "In5.Cu")
		(net 49)
	)
	(segment
		(start 127.62682 103.7335)
		(end 128.014195 104.120875)
		(width 0.159)
		(layer "In5.Cu")
		(net 49)
	)
	(segment
		(start 181.5935 149.434)
		(end 181.4525 149.575)
		(width 0.159)
		(layer "In5.Cu")
		(net 49)
	)
	(segment
		(start 126.71166 106.10166)
		(end 126.2585 106.55482)
		(width 0.159)
		(layer "In5.Cu")
		(net 49)
	)
	(segment
		(start 126.910736 103.7335)
		(end 127.62682 103.7335)
		(width 0.159)
		(layer "In5.Cu")
		(net 49)
	)
	(segment
		(start 181.5935 147.87518)
		(end 181.5935 149.434)
		(width 0.159)
		(layer "In5.Cu")
		(net 49)
	)
	(segment
		(start 126.830566 105.982751)
		(end 126.745715 106.067604)
		(width 0.159)
		(layer "In5.Cu")
		(net 49)
	)
	(segment
		(start 176.2685 142.55018)
		(end 181.5935 147.87518)
		(width 0.159)
		(layer "In5.Cu")
		(net 49)
	)
	(segment
		(start 127.11482 109.5815)
		(end 129.04982 109.5815)
		(width 0.159)
		(layer "In5.Cu")
		(net 49)
	)
	(arc
		(start 127.594244 105.219076)
		(mid 127.424538 105.289371)
		(end 127.254832 105.219076)
		(width 0.159)
		(layer "In5.Cu")
		(net 49)
	)
	(arc
		(start 126.811644 105.285005)
		(mid 126.741349 105.454711)
		(end 126.811644 105.624417)
		(width 0.159)
		(layer "In5.Cu")
		(net 49)
	)
	(arc
		(start 126.830566 105.643339)
		(mid 126.900861 105.813045)
		(end 126.830566 105.982751)
		(width 0.159)
		(layer "In5.Cu")
		(net 49)
	)
	(arc
		(start 127.235909 105.200153)
		(mid 127.066203 105.129858)
		(end 126.896497 105.200153)
		(width 0.159)
		(layer "In5.Cu")
		(net 49)
	)
	(segment
		(start 137.08 105.3)
		(end 137.7 105.3)
		(width 0.2)
		(layer "F.Cu")
		(net 50)
	)
	(segment
		(start 137.08 101.41)
		(end 137.79 101.41)
		(width 0.2)
		(layer "F.Cu")
		(net 50)
	)
	(segment
		(start 137.78 109.22)
		(end 137.8 109.2)
		(width 0.2)
		(layer "F.Cu")
		(net 50)
	)
	(segment
		(start 137.69 113.11)
		(end 137.8 113)
		(width 0.2)
		(layer "F.Cu")
		(net 50)
	)
	(segment
		(start 137.08 109.22)
		(end 137.78 109.22)
		(width 0.2)
		(layer "F.Cu")
		(net 50)
	)
	(segment
		(start 137.7 105.3)
		(end 137.8 105.2)
		(width 0.2)
		(layer "F.Cu")
		(net 50)
	)
	(segment
		(start 137.79 101.41)
		(end 137.8 101.4)
		(width 0.2)
		(layer "F.Cu")
		(net 50)
	)
	(segment
		(start 137.08 113.11)
		(end 137.69 113.11)
		(width 0.2)
		(layer "F.Cu")
		(net 50)
	)
	(via
		(at 137.8 109.2)
		(size 0.45)
		(drill 0.1)
		(layers "F.Cu" "B.Cu")
		(teardrops
			(best_length_ratio 0.4)
			(max_length 1)
			(best_width_ratio 0.9)
			(max_width 2)
			(curved_edges yes)
			(filter_ratio 0.9)
			(enabled yes)
			(allow_two_segments yes)
			(prefer_zone_connections yes)
		)
		(net 50)
	)
	(via
		(at 137.8 105.2)
		(size 0.45)
		(drill 0.1)
		(layers "F.Cu" "B.Cu")
		(teardrops
			(best_length_ratio 0.4)
			(max_length 1)
			(best_width_ratio 0.9)
			(max_width 2)
			(curved_edges yes)
			(filter_ratio 0.9)
			(enabled yes)
			(allow_two_segments yes)
			(prefer_zone_connections yes)
		)
		(net 50)
	)
	(via
		(at 137.8 113)
		(size 0.45)
		(drill 0.1)
		(layers "F.Cu" "B.Cu")
		(teardrops
			(best_length_ratio 0.4)
			(max_length 1)
			(best_width_ratio 0.9)
			(max_width 2)
			(curved_edges yes)
			(filter_ratio 0.9)
			(enabled yes)
			(allow_two_segments yes)
			(prefer_zone_connections yes)
		)
		(net 50)
	)
	(via
		(at 137.8 101.4)
		(size 0.45)
		(drill 0.1)
		(layers "F.Cu" "B.Cu")
		(teardrops
			(best_length_ratio 0.4)
			(max_length 1)
			(best_width_ratio 0.9)
			(max_width 2)
			(curved_edges yes)
			(filter_ratio 0.9)
			(enabled yes)
			(allow_two_segments yes)
			(prefer_zone_connections yes)
		)
		(net 50)
	)
	(segment
		(start 137.8 105.2)
		(end 137.8 101.4)
		(width 0.5)
		(layer "B.Cu")
		(net 50)
	)
	(segment
		(start 137.8 113)
		(end 137.8 109.2)
		(width 0.5)
		(layer "B.Cu")
		(net 50)
	)
	(segment
		(start 139.455 105.2)
		(end 137.8 105.2)
		(width 0.5)
		(layer "B.Cu")
		(net 50)
	)
	(segment
		(start 137.8 105.2)
		(end 137.8 109.2)
		(width 0.5)
		(layer "B.Cu")
		(net 50)
	)
	(segment
		(start 131.9 99.76)
		(end 131.9 103.16)
		(width 0.3)
		(layer "F.Cu")
		(net 51)
	)
	(segment
		(start 130.19 110.95)
		(end 130.77 110.95)
		(width 0.3)
		(layer "F.Cu")
		(net 51)
	)
	(segment
		(start 130.77 103.14)
		(end 131.89 103.14)
		(width 0.3)
		(layer "F.Cu")
		(net 51)
	)
	(segment
		(start 129.95 106.82)
		(end 130.19 107.06)
		(width 0.3)
		(layer "F.Cu")
		(net 51)
	)
	(segment
		(start 130.19 99.25)
		(end 130.77 99.25)
		(width 0.3)
		(layer "F.Cu")
		(net 51)
	)
	(segment
		(start 129.5 110.71)
		(end 129.95 110.71)
		(width 0.3)
		(layer "F.Cu")
		(net 51)
	)
	(segment
		(start 130.19 103.14)
		(end 130.77 103.14)
		(width 0.3)
		(layer "F.Cu")
		(net 51)
	)
	(segment
		(start 131.9 103.16)
		(end 131.9 107.06)
		(width 0.3)
		(layer "F.Cu")
		(net 51)
	)
	(segment
		(start 130.77 107.06)
		(end 131.9 107.06)
		(width 0.3)
		(layer "F.Cu")
		(net 51)
	)
	(segment
		(start 131.46 110.95)
		(end 130.77 110.95)
		(width 0.3)
		(layer "F.Cu")
		(net 51)
	)
	(segment
		(start 131.9 110.51)
		(end 131.46 110.95)
		(width 0.3)
		(layer "F.Cu")
		(net 51)
	)
	(segment
		(start 131.39 99.25)
		(end 131.9 99.76)
		(width 0.3)
		(layer "F.Cu")
		(net 51)
	)
	(segment
		(start 129.5 99.01)
		(end 129.95 99.01)
		(width 0.3)
		(layer "F.Cu")
		(net 51)
	)
	(segment
		(start 131.9 107.06)
		(end 131.9 110.51)
		(width 0.3)
		(layer "F.Cu")
		(net 51)
	)
	(segment
		(start 130.19 107.06)
		(end 130.77 107.06)
		(width 0.3)
		(layer "F.Cu")
		(net 51)
	)
	(segment
		(start 129.95 110.71)
		(end 130.19 110.95)
		(width 0.3)
		(layer "F.Cu")
		(net 51)
	)
	(segment
		(start 130.77 99.25)
		(end 131.39 99.25)
		(width 0.3)
		(layer "F.Cu")
		(net 51)
	)
	(segment
		(start 129.95 102.9)
		(end 130.19 103.14)
		(width 0.3)
		(layer "F.Cu")
		(net 51)
	)
	(segment
		(start 129.95 99.01)
		(end 130.19 99.25)
		(width 0.3)
		(layer "F.Cu")
		(net 51)
	)
	(segment
		(start 129.5 102.9)
		(end 129.95 102.9)
		(width 0.3)
		(layer "F.Cu")
		(net 51)
	)
	(segment
		(start 130.77 97.91)
		(end 130.77 99.25)
		(width 0.3)
		(layer "F.Cu")
		(net 51)
	)
	(segment
		(start 129.5 106.82)
		(end 129.95 106.82)
		(width 0.3)
		(layer "F.Cu")
		(net 51)
	)
	(segment
		(start 262.910708 76.835999)
		(end 262.910708 75.76)
		(width 0.3)
		(layer "F.Cu")
		(net 52)
	)
	(segment
		(start 195.70861 74.102163)
		(end 195.70861 72.802163)
		(width 0.2)
		(layer "F.Cu")
		(net 52)
	)
	(segment
		(start 250.851709 77.772)
		(end 250.11671 77.772)
		(width 0.3)
		(layer "F.Cu")
		(net 52)
	)
	(segment
		(start 235.450708 75.76)
		(end 235.450708 76.836)
		(width 0.3)
		(layer "F.Cu")
		(net 52)
	)
	(segment
		(start 236.386708 77.772)
		(end 237.121707 77.772)
		(width 0.3)
		(layer "F.Cu")
		(net 52)
	)
	(segment
		(start 264.581708 77.772)
		(end 263.846709 77.772)
		(width 0.3)
		(layer "F.Cu")
		(net 52)
	)
	(segment
		(start 249.175708 76.830998)
		(end 249.175708 75.76)
		(width 0.3)
		(layer "F.Cu")
		(net 52)
	)
	(segment
		(start 250.11671 77.772)
		(end 249.175708 76.830998)
		(width 0.3)
		(layer "F.Cu")
		(net 52)
	)
	(segment
		(start 263.846709 77.772)
		(end 262.910708 76.835999)
		(width 0.3)
		(layer "F.Cu")
		(net 52)
	)
	(segment
		(start 235.450708 76.836)
		(end 236.386708 77.772)
		(width 0.3)
		(layer "F.Cu")
		(net 52)
	)
	(via
		(at 262.910708 75.76)
		(size 0.45)
		(drill 0.1)
		(layers "F.Cu" "B.Cu")
		(remove_unused_layers yes)
		(keep_end_layers yes)
		(zone_layer_connections "In3.Cu" "In5.Cu")
		(teardrops
			(best_length_ratio 0.4)
			(max_length 1)
			(best_width_ratio 0.9)
			(max_width 2)
			(curved_edges yes)
			(filter_ratio 0.9)
			(enabled yes)
			(allow_two_segments yes)
			(prefer_zone_connections yes)
		)
		(net 52)
	)
	(via
		(at 249.175708 75.76)
		(size 0.45)
		(drill 0.1)
		(layers "F.Cu" "B.Cu")
		(remove_unused_layers yes)
		(keep_end_layers yes)
		(zone_layer_connections "In3.Cu")
		(teardrops
			(best_length_ratio 0.4)
			(max_length 1)
			(best_width_ratio 0.9)
			(max_width 2)
			(curved_edges yes)
			(filter_ratio 0.9)
			(enabled yes)
			(allow_two_segments yes)
			(prefer_zone_connections yes)
		)
		(net 52)
	)
	(via
		(at 292.100001 99.9395)
		(size 0.45)
		(drill 0.1)
		(layers "F.Cu" "B.Cu")
		(remove_unused_layers yes)
		(keep_end_layers yes)
		(free yes)
		(zone_layer_connections "In3.Cu")
		(teardrops
			(best_length_ratio 0.4)
			(max_length 1)
			(best_width_ratio 0.9)
			(max_width 2)
			(curved_edges yes)
			(filter_ratio 0.9)
			(enabled yes)
			(allow_two_segments yes)
			(prefer_zone_connections yes)
		)
		(net 52)
	)
	(via
		(at 105.15 151.35)
		(size 0.45)
		(drill 0.1)
		(layers "F.Cu" "B.Cu")
		(teardrops
			(best_length_ratio 0.4)
			(max_length 1)
			(best_width_ratio 0.9)
			(max_width 2)
			(curved_edges yes)
			(filter_ratio 0.9)
			(enabled yes)
			(allow_two_segments yes)
			(prefer_zone_connections yes)
		)
		(net 52)
	)
	(via
		(at 195.70861 74.102163)
		(size 0.45)
		(drill 0.1)
		(layers "F.Cu" "B.Cu")
		(remove_unused_layers yes)
		(keep_end_layers yes)
		(zone_layer_connections "In3.Cu")
		(teardrops
			(best_length_ratio 0.4)
			(max_length 1)
			(best_width_ratio 0.9)
			(max_width 2)
			(curved_edges yes)
			(filter_ratio 0.9)
			(enabled yes)
			(allow_two_segments yes)
			(prefer_zone_connections yes)
		)
		(net 52)
	)
	(via
		(at 103.2 78.81)
		(size 0.45)
		(drill 0.1)
		(layers "F.Cu" "B.Cu")
		(remove_unused_layers yes)
		(keep_end_layers yes)
		(zone_layer_connections "In3.Cu")
		(teardrops
			(best_length_ratio 0.4)
			(max_length 1)
			(best_width_ratio 0.9)
			(max_width 2)
			(curved_edges yes)
			(filter_ratio 0.9)
			(enabled yes)
			(allow_two_segments yes)
			(prefer_zone_connections yes)
		)
		(net 52)
	)
	(via
		(at 119.05 90.81)
		(size 0.45)
		(drill 0.1)
		(layers "F.Cu" "B.Cu")
		(remove_unused_layers yes)
		(keep_end_layers yes)
		(zone_layer_connections "In3.Cu")
		(teardrops
			(best_length_ratio 0.4)
			(max_length 1)
			(best_width_ratio 0.9)
			(max_width 2)
			(curved_edges yes)
			(filter_ratio 0.9)
			(enabled yes)
			(allow_two_segments yes)
			(prefer_zone_connections yes)
		)
		(net 52)
	)
	(via
		(at 235.450708 75.76)
		(size 0.45)
		(drill 0.1)
		(layers "F.Cu" "B.Cu")
		(remove_unused_layers yes)
		(keep_end_layers yes)
		(zone_layer_connections "In3.Cu")
		(teardrops
			(best_length_ratio 0.4)
			(max_length 1)
			(best_width_ratio 0.9)
			(max_width 2)
			(curved_edges yes)
			(filter_ratio 0.9)
			(enabled yes)
			(allow_two_segments yes)
			(prefer_zone_connections yes)
		)
		(net 52)
	)
	(via
		(at 118.2 85.06)
		(size 0.45)
		(drill 0.1)
		(layers "F.Cu" "B.Cu")
		(remove_unused_layers yes)
		(keep_end_layers yes)
		(zone_layer_connections "In3.Cu")
		(teardrops
			(best_length_ratio 0.4)
			(max_length 1)
			(best_width_ratio 0.9)
			(max_width 2)
			(curved_edges yes)
			(filter_ratio 0.9)
			(enabled yes)
			(allow_two_segments yes)
			(prefer_zone_connections yes)
		)
		(net 52)
	)
	(via
		(at 119.05 85.06)
		(size 0.45)
		(drill 0.1)
		(layers "F.Cu" "B.Cu")
		(remove_unused_layers yes)
		(keep_end_layers yes)
		(zone_layer_connections "In3.Cu")
		(teardrops
			(best_length_ratio 0.4)
			(max_length 1)
			(best_width_ratio 0.9)
			(max_width 2)
			(curved_edges yes)
			(filter_ratio 0.9)
			(enabled yes)
			(allow_two_segments yes)
			(prefer_zone_connections yes)
		)
		(net 52)
	)
	(via
		(at 294.1 99.9395)
		(size 0.45)
		(drill 0.1)
		(layers "F.Cu" "B.Cu")
		(remove_unused_layers yes)
		(keep_end_layers yes)
		(free yes)
		(zone_layer_connections "In3.Cu")
		(teardrops
			(best_length_ratio 0.4)
			(max_length 1)
			(best_width_ratio 0.9)
			(max_width 2)
			(curved_edges yes)
			(filter_ratio 0.9)
			(enabled yes)
			(allow_two_segments yes)
			(prefer_zone_connections yes)
		)
		(net 52)
	)
	(via
		(at 105.15 150.75)
		(size 0.45)
		(drill 0.1)
		(layers "F.Cu" "B.Cu")
		(teardrops
			(best_length_ratio 0.4)
			(max_length 1)
			(best_width_ratio 0.9)
			(max_width 2)
			(curved_edges yes)
			(filter_ratio 0.9)
			(enabled yes)
			(allow_two_segments yes)
			(prefer_zone_connections yes)
		)
		(net 52)
	)
	(via
		(at 293.1 100.9395)
		(size 0.45)
		(drill 0.1)
		(layers "F.Cu" "B.Cu")
		(remove_unused_layers yes)
		(keep_end_layers yes)
		(free yes)
		(zone_layer_connections "In3.Cu")
		(teardrops
			(best_length_ratio 0.4)
			(max_length 1)
			(best_width_ratio 0.9)
			(max_width 2)
			(curved_edges yes)
			(filter_ratio 0.9)
			(enabled yes)
			(allow_two_segments yes)
			(prefer_zone_connections yes)
		)
		(net 52)
	)
	(via
		(at 118.199 90.813)
		(size 0.45)
		(drill 0.1)
		(layers "F.Cu" "B.Cu")
		(remove_unused_layers yes)
		(keep_end_layers yes)
		(zone_layer_connections "In3.Cu")
		(teardrops
			(best_length_ratio 0.4)
			(max_length 1)
			(best_width_ratio 0.9)
			(max_width 2)
			(curved_edges yes)
			(filter_ratio 0.9)
			(enabled yes)
			(allow_two_segments yes)
			(prefer_zone_connections yes)
		)
		(net 52)
	)
	(via
		(at 294.1 98.9395)
		(size 0.45)
		(drill 0.1)
		(layers "F.Cu" "B.Cu")
		(remove_unused_layers yes)
		(keep_end_layers yes)
		(free yes)
		(zone_layer_connections "In3.Cu")
		(teardrops
			(best_length_ratio 0.4)
			(max_length 1)
			(best_width_ratio 0.9)
			(max_width 2)
			(curved_edges yes)
			(filter_ratio 0.9)
			(enabled yes)
			(allow_two_segments yes)
			(prefer_zone_connections yes)
		)
		(net 52)
	)
	(via
		(at 118.2 89.96)
		(size 0.45)
		(drill 0.1)
		(layers "F.Cu" "B.Cu")
		(remove_unused_layers yes)
		(keep_end_layers yes)
		(zone_layer_connections "In3.Cu")
		(teardrops
			(best_length_ratio 0.4)
			(max_length 1)
			(best_width_ratio 0.9)
			(max_width 2)
			(curved_edges yes)
			(filter_ratio 0.9)
			(enabled yes)
			(allow_two_segments yes)
			(prefer_zone_connections yes)
		)
		(net 52)
	)
	(via
		(at 119.05 89.96)
		(size 0.45)
		(drill 0.1)
		(layers "F.Cu" "B.Cu")
		(remove_unused_layers yes)
		(keep_end_layers yes)
		(zone_layer_connections "In3.Cu")
		(teardrops
			(best_length_ratio 0.4)
			(max_length 1)
			(best_width_ratio 0.9)
			(max_width 2)
			(curved_edges yes)
			(filter_ratio 0.9)
			(enabled yes)
			(allow_two_segments yes)
			(prefer_zone_connections yes)
		)
		(net 52)
	)
	(via
		(at 294.1 100.9395)
		(size 0.45)
		(drill 0.1)
		(layers "F.Cu" "B.Cu")
		(remove_unused_layers yes)
		(keep_end_layers yes)
		(free yes)
		(zone_layer_connections "In3.Cu")
		(teardrops
			(best_length_ratio 0.4)
			(max_length 1)
			(best_width_ratio 0.9)
			(max_width 2)
			(curved_edges yes)
			(filter_ratio 0.9)
			(enabled yes)
			(allow_two_segments yes)
			(prefer_zone_connections yes)
		)
		(net 52)
	)
	(via
		(at 252.185 86.449999)
		(size 0.45)
		(drill 0.1)
		(layers "F.Cu" "B.Cu")
		(remove_unused_layers yes)
		(keep_end_layers yes)
		(zone_layer_connections "In5.Cu")
		(teardrops
			(best_length_ratio 0.4)
			(max_length 1)
			(best_width_ratio 0.9)
			(max_width 2)
			(curved_edges yes)
			(filter_ratio 0.9)
			(enabled yes)
			(allow_two_segments yes)
			(prefer_zone_connections yes)
		)
		(net 52)
	)
	(via
		(at 118.199 85.913)
		(size 0.45)
		(drill 0.1)
		(layers "F.Cu" "B.Cu")
		(remove_unused_layers yes)
		(keep_end_layers yes)
		(zone_layer_connections "In3.Cu")
		(teardrops
			(best_length_ratio 0.4)
			(max_length 1)
			(best_width_ratio 0.9)
			(max_width 2)
			(curved_edges yes)
			(filter_ratio 0.9)
			(enabled yes)
			(allow_two_segments yes)
			(prefer_zone_connections yes)
		)
		(net 52)
	)
	(via
		(at 293.099999 99.9395)
		(size 0.45)
		(drill 0.1)
		(layers "F.Cu" "B.Cu")
		(remove_unused_layers yes)
		(keep_end_layers yes)
		(free yes)
		(zone_layer_connections "In3.Cu")
		(teardrops
			(best_length_ratio 0.4)
			(max_length 1)
			(best_width_ratio 0.9)
			(max_width 2)
			(curved_edges yes)
			(filter_ratio 0.9)
			(enabled yes)
			(allow_two_segments yes)
			(prefer_zone_connections yes)
		)
		(net 52)
	)
	(via
		(at 293.1 98.9395)
		(size 0.45)
		(drill 0.1)
		(layers "F.Cu" "B.Cu")
		(remove_unused_layers yes)
		(keep_end_layers yes)
		(free yes)
		(zone_layer_connections "In3.Cu")
		(teardrops
			(best_length_ratio 0.4)
			(max_length 1)
			(best_width_ratio 0.9)
			(max_width 2)
			(curved_edges yes)
			(filter_ratio 0.9)
			(enabled yes)
			(allow_two_segments yes)
			(prefer_zone_connections yes)
		)
		(net 52)
	)
	(via
		(at 292.1 100.9395)
		(size 0.45)
		(drill 0.1)
		(layers "F.Cu" "B.Cu")
		(remove_unused_layers yes)
		(keep_end_layers yes)
		(free yes)
		(zone_layer_connections "In3.Cu")
		(teardrops
			(best_length_ratio 0.4)
			(max_length 1)
			(best_width_ratio 0.9)
			(max_width 2)
			(curved_edges yes)
			(filter_ratio 0.9)
			(enabled yes)
			(allow_two_segments yes)
			(prefer_zone_connections yes)
		)
		(net 52)
	)
	(via
		(at 119.05 85.91)
		(size 0.45)
		(drill 0.1)
		(layers "F.Cu" "B.Cu")
		(remove_unused_layers yes)
		(keep_end_layers yes)
		(zone_layer_connections "In3.Cu")
		(teardrops
			(best_length_ratio 0.4)
			(max_length 1)
			(best_width_ratio 0.9)
			(max_width 2)
			(curved_edges yes)
			(filter_ratio 0.9)
			(enabled yes)
			(allow_two_segments yes)
			(prefer_zone_connections yes)
		)
		(net 52)
	)
	(via
		(at 292.1 98.9395)
		(size 0.45)
		(drill 0.1)
		(layers "F.Cu" "B.Cu")
		(remove_unused_layers yes)
		(keep_end_layers yes)
		(free yes)
		(zone_layer_connections "In3.Cu")
		(teardrops
			(best_length_ratio 0.4)
			(max_length 1)
			(best_width_ratio 0.9)
			(max_width 2)
			(curved_edges yes)
			(filter_ratio 0.9)
			(enabled yes)
			(allow_two_segments yes)
			(prefer_zone_connections yes)
		)
		(net 52)
	)
	(segment
		(start 298.05 98.51)
		(end 295.6205 100.9395)
		(width 0.125)
		(layer "B.Cu")
		(net 52)
	)
	(segment
		(start 105.15 151.35)
		(end 105.15 150.75)
		(width 0.5)
		(layer "B.Cu")
		(net 52)
	)
	(segment
		(start 106.05 152.65)
		(end 105.25 151.85)
		(width 0.5)
		(layer "B.Cu")
		(net 52)
	)
	(segment
		(start 105.25 151.85)
		(end 105.15 151.75)
		(width 0.5)
		(layer "B.Cu")
		(net 52)
	)
	(segment
		(start 307.55 98.51)
		(end 298.05 98.51)
		(width 0.125)
		(layer "B.Cu")
		(net 52)
	)
	(segment
		(start 295.6205 100.9395)
		(end 294.1 100.9395)
		(width 0.125)
		(layer "B.Cu")
		(net 52)
	)
	(segment
		(start 309.824999 100.784999)
		(end 307.55 98.51)
		(width 0.125)
		(layer "B.Cu")
		(net 52)
	)
	(segment
		(start 106.14 152.65)
		(end 106.05 152.65)
		(width 0.5)
		(layer "B.Cu")
		(net 52)
	)
	(segment
		(start 105.15 151.75)
		(end 105.15 151.35)
		(width 0.5)
		(layer "B.Cu")
		(net 52)
	)
	(segment
		(start 309.824999 101.28)
		(end 309.824999 100.784999)
		(width 0.125)
		(layer "B.Cu")
		(net 52)
	)
	(segment
		(start 262.910708 77.479292)
		(end 262.910708 75.76)
		(width 0.125)
		(layer "In5.Cu")
		(net 52)
	)
	(segment
		(start 258.785 81.605)
		(end 262.910708 77.479292)
		(width 0.125)
		(layer "In5.Cu")
		(net 52)
	)
	(segment
		(start 252.185 86.449999)
		(end 257.029999 81.605)
		(width 0.125)
		(layer "In5.Cu")
		(net 52)
	)
	(segment
		(start 257.029999 81.605)
		(end 258.785 81.605)
		(width 0.125)
		(layer "In5.Cu")
		(net 52)
	)
	(segment
		(start 109.87 169.435)
		(end 108.45 169.435)
		(width 0.3)
		(layer "B.Cu")
		(net 53)
	)
	(segment
		(start 152.25 159.75)
		(end 152.25 158.51)
		(width 0.3)
		(layer "B.Cu")
		(net 53)
	)
	(segment
		(start 116.45 169.435)
		(end 117.975 169.435)
		(width 0.3)
		(layer "B.Cu")
		(net 53)
	)
	(segment
		(start 123.03 169.435)
		(end 124.45 169.435)
		(width 0.3)
		(layer "B.Cu")
		(net 53)
	)
	(segment
		(start 108.26 156.54)
		(end 108.26 155.375)
		(width 0.3)
		(layer "B.Cu")
		(net 53)
	)
	(segment
		(start 118 169.46)
		(end 118 169.96)
		(width 0.3)
		(layer "B.Cu")
		(net 53)
	)
	(segment
		(start 118 168.91)
		(end 118 169.46)
		(width 0.3)
		(layer "B.Cu")
		(net 53)
	)
	(segment
		(start 117.975 169.435)
		(end 118 169.46)
		(width 0.3)
		(layer "B.Cu")
		(net 53)
	)
	(segment
		(start 124.45 155.185)
		(end 124.45 156.66)
		(width 0.3)
		(layer "B.Cu")
		(net 53)
	)
	(segment
		(start 132.45 155.185)
		(end 132.45 156.66)
		(width 0.3)
		(layer "B.Cu")
		(net 53)
	)
	(segment
		(start 130.98 169.435)
		(end 132.45 169.435)
		(width 0.3)
		(layer "B.Cu")
		(net 53)
	)
	(segment
		(start 152.05 166.31)
		(end 152.05 167.76)
		(width 0.3)
		(layer "B.Cu")
		(net 53)
	)
	(segment
		(start 152.05 158.31)
		(end 152.05 166.31)
		(width 0.3)
		(layer "In2.Cu")
		(net 53)
	)
	(segment
		(start 106.424 81.947)
		(end 98.325 81.947)
		(width 0.5)
		(layer "B.Cu")
		(net 54)
	)
	(segment
		(start 98.325 81.947)
		(end 96.925 83.347)
		(width 0.5)
		(layer "B.Cu")
		(net 54)
	)
	(segment
		(start 96.925 86.547)
		(end 98.325 87.947)
		(width 0.5)
		(layer "B.Cu")
		(net 54)
	)
	(segment
		(start 106.424 87.947)
		(end 98.325 87.947)
		(width 0.5)
		(layer "B.Cu")
		(net 54)
	)
	(segment
		(start 96.925 83.347)
		(end 96.925 86.547)
		(width 0.5)
		(layer "B.Cu")
		(net 54)
	)
	(segment
		(start 107.739 78.81)
		(end 107.279 78.35)
		(width 0.185)
		(layer "F.Cu")
		(net 55)
	)
	(segment
		(start 110.037 75.636001)
		(end 109.756999 75.356)
		(width 0.185)
		(layer "F.Cu")
		(net 55)
	)
	(segment
		(start 106.13 79.131298)
		(end 106.451298 78.81)
		(width 0.185)
		(layer "F.Cu")
		(net 55)
	)
	(segment
		(start 105.651298 79.96)
		(end 106.13 79.481298)
		(width 0.185)
		(layer "F.Cu")
		(net 55)
	)
	(segment
		(start 108.825298 75.636)
		(end 108.14 76.321298)
		(width 0.185)
		(layer "F.Cu")
		(net 55)
	)
	(segment
		(start 106.819 78.81)
		(end 107.279 78.35)
		(width 0.185)
		(layer "F.Cu")
		(net 55)
	)
	(segment
		(start 108.14 76.321298)
		(end 108.14 78.621298)
		(width 0.185)
		(layer "F.Cu")
		(net 55)
	)
	(segment
		(start 106.451298 78.81)
		(end 106.819 78.81)
		(width 0.185)
		(layer "F.Cu")
		(net 55)
	)
	(segment
		(start 110.726999 75.326)
		(end 110.416998 75.636001)
		(width 0.185)
		(layer "F.Cu")
		(net 55)
	)
	(segment
		(start 107.951298 78.81)
		(end 107.739 78.81)
		(width 0.185)
		(layer "F.Cu")
		(net 55)
	)
	(segment
		(start 109.476999 75.636)
		(end 108.825298 75.636)
		(width 0.185)
		(layer "F.Cu")
		(net 55)
	)
	(segment
		(start 109.756999 75.356)
		(end 109.476999 75.636)
		(width 0.185)
		(layer "F.Cu")
		(net 55)
	)
	(segment
		(start 106.13 79.481298)
		(end 106.13 79.131298)
		(width 0.185)
		(layer "F.Cu")
		(net 55)
	)
	(segment
		(start 102.500265 82.241033)
		(end 104.781298 79.96)
		(width 0.185)
		(layer "F.Cu")
		(net 55)
	)
	(segment
		(start 104.781298 79.96)
		(end 105.651298 79.96)
		(width 0.185)
		(layer "F.Cu")
		(net 55)
	)
	(segment
		(start 110.416998 75.636001)
		(end 110.037 75.636001)
		(width 0.185)
		(layer "F.Cu")
		(net 55)
	)
	(segment
		(start 108.14 78.621298)
		(end 107.951298 78.81)
		(width 0.185)
		(layer "F.Cu")
		(net 55)
	)
	(segment
		(start 102.1 83.1225)
		(end 102.16 83.0625)
		(width 0.185)
		(layer "F.Cu")
		(net 55)
	)
	(via
		(at 102.100002 84.529351)
		(size 0.45)
		(drill 0.1)
		(layers "F.Cu" "B.Cu")
		(remove_unused_layers yes)
		(keep_end_layers yes)
		(zone_layer_connections)
		(teardrops
			(best_length_ratio 0.4)
			(max_length 1)
			(best_width_ratio 0.9)
			(max_width 2)
			(curved_edges yes)
			(filter_ratio 0.9)
			(enabled yes)
			(allow_two_segments yes)
			(prefer_zone_connections yes)
		)
		(net 55)
	)
	(via
		(at 102.600875 85.370878)
		(size 0.45)
		(drill 0.1)
		(layers "F.Cu" "B.Cu")
		(remove_unused_layers yes)
		(keep_end_layers yes)
		(zone_layer_connections)
		(teardrops
			(best_length_ratio 0.4)
			(max_length 1)
			(best_width_ratio 0.9)
			(max_width 2)
			(curved_edges yes)
			(filter_ratio 0.9)
			(enabled yes)
			(allow_two_segments yes)
			(prefer_zone_connections yes)
		)
		(net 55)
	)
	(arc
		(start 102.16 83.0625)
		(mid 102.248432 82.617927)
		(end 102.500265 82.241033)
		(width 0.185)
		(layer "F.Cu")
		(net 55)
	)
	(segment
		(start 102.100002 84.870005)
		(end 102.600875 85.370878)
		(width 0.185)
		(layer "B.Cu")
		(net 55)
	)
	(segment
		(start 102.100002 84.529351)
		(end 102.100002 84.870005)
		(width 0.185)
		(layer "B.Cu")
		(net 55)
	)
	(segment
		(start 102.6 84.7)
		(end 102.1 85.2)
		(width 0.185)
		(layer "F.Cu")
		(net 56)
	)
	(segment
		(start 103.973664 81.305038)
		(end 104.071429 81.207276)
		(width 0.185)
		(layer "F.Cu")
		(net 56)
	)
	(segment
		(start 107.739 79.19)
		(end 107.279 79.65)
		(width 0.185)
		(layer "F.Cu")
		(net 56)
	)
	(segment
		(start 109.757 76.296)
		(end 109.477 76.016)
		(width 0.185)
		(layer "F.Cu")
		(net 56)
	)
	(segment
		(start 110.036999 76.016001)
		(end 109.757 76.296)
		(width 0.185)
		(layer "F.Cu")
		(net 56)
	)
	(segment
		(start 108.982702 76.016)
		(end 108.52 76.478702)
		(width 0.185)
		(layer "F.Cu")
		(net 56)
	)
	(segment
		(start 103.505742 81.772963)
		(end 103.505741 81.772964)
		(width 0.185)
		(layer "F.Cu")
		(net 56)
	)
	(segment
		(start 104.441585 81.207276)
		(end 104.539351 81.109509)
		(width 0.185)
		(layer "F.Cu")
		(net 56)
	)
	(segment
		(start 103.875898 81.772963)
		(end 103.973664 81.675196)
		(width 0.185)
		(layer "F.Cu")
		(net 56)
	)
	(segment
		(start 102.6 83.81)
		(end 102.6 84.7)
		(width 0.185)
		(layer "F.Cu")
		(net 56)
	)
	(segment
		(start 106.608702 79.19)
		(end 106.819 79.19)
		(width 0.185)
		(layer "F.Cu")
		(net 56)
	)
	(segment
		(start 104.53935 80.924431)
		(end 104.539351 80.924431)
		(width 0.185)
		(layer "F.Cu")
		(net 56)
	)
	(segment
		(start 103.973663 81.490118)
		(end 103.973664 81.490118)
		(width 0.185)
		(layer "F.Cu")
		(net 56)
	)
	(segment
		(start 106.464351 79.334351)
		(end 106.608702 79.19)
		(width 0.185)
		(layer "F.Cu")
		(net 56)
	)
	(segment
		(start 102.6 83.1225)
		(end 102.54 83.0625)
		(width 0.185)
		(layer "F.Cu")
		(net 56)
	)
	(segment
		(start 104.071429 81.207276)
		(end 104.071428 81.207277)
		(width 0.185)
		(layer "F.Cu")
		(net 56)
	)
	(segment
		(start 110.726998 76.326)
		(end 110.416998 76.016001)
		(width 0.185)
		(layer "F.Cu")
		(net 56)
	)
	(segment
		(start 106.464351 79.684351)
		(end 106.464351 79.334351)
		(width 0.185)
		(layer "F.Cu")
		(net 56)
	)
	(segment
		(start 104.539351 81.109509)
		(end 104.539351 81.10951)
		(width 0.185)
		(layer "F.Cu")
		(net 56)
	)
	(segment
		(start 104.539351 80.739351)
		(end 104.938702 80.34)
		(width 0.185)
		(layer "F.Cu")
		(net 56)
	)
	(segment
		(start 108.52 76.478702)
		(end 108.52 78.778702)
		(width 0.185)
		(layer "F.Cu")
		(net 56)
	)
	(segment
		(start 108.108702 79.19)
		(end 107.739 79.19)
		(width 0.185)
		(layer "F.Cu")
		(net 56)
	)
	(segment
		(start 102.1 85.2)
		(end 102.1 86.084)
		(width 0.185)
		(layer "F.Cu")
		(net 56)
	)
	(segment
		(start 105.808702 80.34)
		(end 106.464351 79.684351)
		(width 0.185)
		(layer "F.Cu")
		(net 56)
	)
	(segment
		(start 102.768941 82.509761)
		(end 103.505742 81.772963)
		(width 0.185)
		(layer "F.Cu")
		(net 56)
	)
	(segment
		(start 108.52 78.778702)
		(end 108.108702 79.19)
		(width 0.185)
		(layer "F.Cu")
		(net 56)
	)
	(segment
		(start 110.416998 76.016001)
		(end 110.036999 76.016001)
		(width 0.185)
		(layer "F.Cu")
		(net 56)
	)
	(segment
		(start 109.477 76.016)
		(end 108.982702 76.016)
		(width 0.185)
		(layer "F.Cu")
		(net 56)
	)
	(segment
		(start 104.938702 80.34)
		(end 105.808702 80.34)
		(width 0.185)
		(layer "F.Cu")
		(net 56)
	)
	(segment
		(start 106.819 79.19)
		(end 107.279 79.65)
		(width 0.185)
		(layer "F.Cu")
		(net 56)
	)
	(segment
		(start 103.973664 81.675196)
		(end 103.973664 81.675197)
		(width 0.185)
		(layer "F.Cu")
		(net 56)
	)
	(arc
		(start 103.69082 81.772963)
		(mid 103.783359 81.811294)
		(end 103.875898 81.772963)
		(width 0.185)
		(layer "F.Cu")
		(net 56)
	)
	(arc
		(start 103.973664 81.490118)
		(mid 103.935332 81.397579)
		(end 103.973664 81.305038)
		(width 0.185)
		(layer "F.Cu")
		(net 56)
	)
	(arc
		(start 104.256507 81.207276)
		(mid 104.349046 81.245607)
		(end 104.441585 81.207276)
		(width 0.185)
		(layer "F.Cu")
		(net 56)
	)
	(arc
		(start 104.539351 80.924431)
		(mid 104.501019 80.831892)
		(end 104.539351 80.739351)
		(width 0.185)
		(layer "F.Cu")
		(net 56)
	)
	(arc
		(start 103.505741 81.772964)
		(mid 103.598281 81.734631)
		(end 103.69082 81.772963)
		(width 0.185)
		(layer "F.Cu")
		(net 56)
	)
	(arc
		(start 103.973664 81.675197)
		(mid 104.011996 81.582656)
		(end 103.973663 81.490118)
		(width 0.185)
		(layer "F.Cu")
		(net 56)
	)
	(arc
		(start 102.54 83.0625)
		(mid 102.5995 82.763347)
		(end 102.768941 82.509761)
		(width 0.185)
		(layer "F.Cu")
		(net 56)
	)
	(arc
		(start 104.071428 81.207277)
		(mid 104.163968 81.168944)
		(end 104.256507 81.207276)
		(width 0.185)
		(layer "F.Cu")
		(net 56)
	)
	(arc
		(start 104.539351 81.10951)
		(mid 104.577683 81.016969)
		(end 104.53935 80.924431)
		(width 0.185)
		(layer "F.Cu")
		(net 56)
	)
	(segment
		(start 112.784999 76.800001)
		(end 112.66 76.925)
		(width 0.125)
		(layer "F.Cu")
		(net 57)
	)
	(segment
		(start 112.794999 78.710001)
		(end 113.219999 78.71)
		(width 0.125)
		(layer "F.Cu")
		(net 57)
	)
	(segment
		(start 112.659999 78.575)
		(end 112.794999 78.710001)
		(width 0.125)
		(layer "F.Cu")
		(net 57)
	)
	(segment
		(start 112.66 76.925)
		(end 112.659999 78.575)
		(width 0.125)
		(layer "F.Cu")
		(net 57)
	)
	(segment
		(start 113.26 76.8)
		(end 112.784999 76.800001)
		(width 0.125)
		(layer "F.Cu")
		(net 57)
	)
	(via
		(at 116.134999 73.925)
		(size 0.45)
		(drill 0.1)
		(layers "F.Cu" "B.Cu")
		(remove_unused_layers yes)
		(keep_end_layers yes)
		(zone_layer_connections)
		(teardrops
			(best_length_ratio 0.4)
			(max_length 1)
			(best_width_ratio 0.9)
			(max_width 2)
			(curved_edges yes)
			(filter_ratio 0.9)
			(enabled yes)
			(allow_two_segments yes)
			(prefer_zone_connections yes)
		)
		(net 57)
	)
	(via
		(at 113.26 76.8)
		(size 0.45)
		(drill 0.1)
		(layers "F.Cu" "B.Cu")
		(remove_unused_layers yes)
		(keep_end_layers yes)
		(zone_layer_connections)
		(teardrops
			(best_length_ratio 0.4)
			(max_length 1)
			(best_width_ratio 0.9)
			(max_width 2)
			(curved_edges yes)
			(filter_ratio 0.9)
			(enabled yes)
			(allow_two_segments yes)
			(prefer_zone_connections yes)
		)
		(net 57)
	)
	(segment
		(start 112.4 70.34)
		(end 112.4 74.19)
		(width 0.3)
		(layer "B.Cu")
		(net 57)
	)
	(segment
		(start 113.26 75.05)
		(end 114.385 73.925)
		(width 0.3)
		(layer "B.Cu")
		(net 57)
	)
	(segment
		(start 113.26 76.8)
		(end 113.26 75.05)
		(width 0.3)
		(layer "B.Cu")
		(net 57)
	)
	(segment
		(start 112.4 74.19)
		(end 113.26 75.05)
		(width 0.3)
		(layer "B.Cu")
		(net 57)
	)
	(segment
		(start 110.9 70.34)
		(end 112.4 70.34)
		(width 0.3)
		(layer "B.Cu")
		(net 57)
	)
	(segment
		(start 114.385 73.925)
		(end 116.134999 73.925)
		(width 0.3)
		(layer "B.Cu")
		(net 57)
	)
	(segment
		(start 120.687 71.459)
		(end 120.687 72.943)
		(width 0.3)
		(layer "F.Cu")
		(net 58)
	)
	(segment
		(start 120.687 72.943)
		(end 120.5 73.13)
		(width 0.3)
		(layer "F.Cu")
		(net 58)
	)
	(via
		(at 101.1 83.81)
		(size 0.45)
		(drill 0.1)
		(layers "F.Cu" "B.Cu")
		(remove_unused_layers yes)
		(keep_end_layers yes)
		(zone_layer_connections)
		(teardrops
			(best_length_ratio 0.4)
			(max_length 1)
			(best_width_ratio 0.9)
			(max_width 2)
			(curved_edges yes)
			(filter_ratio 0.9)
			(enabled yes)
			(allow_two_segments yes)
			(prefer_zone_connections yes)
		)
		(net 58)
	)
	(via
		(at 120.5 73.13)
		(size 0.45)
		(drill 0.1)
		(layers "F.Cu" "B.Cu")
		(remove_unused_layers yes)
		(keep_end_layers yes)
		(zone_layer_connections "In2.Cu")
		(teardrops
			(best_length_ratio 0.4)
			(max_length 1)
			(best_width_ratio 0.9)
			(max_width 2)
			(curved_edges yes)
			(filter_ratio 0.9)
			(enabled yes)
			(allow_two_segments yes)
			(prefer_zone_connections yes)
		)
		(net 58)
	)
	(via
		(at 101.1 86.084)
		(size 0.45)
		(drill 0.1)
		(layers "F.Cu" "B.Cu")
		(remove_unused_layers yes)
		(keep_end_layers yes)
		(zone_layer_connections)
		(teardrops
			(best_length_ratio 0.4)
			(max_length 1)
			(best_width_ratio 0.9)
			(max_width 2)
			(curved_edges yes)
			(filter_ratio 0.9)
			(enabled yes)
			(allow_two_segments yes)
			(prefer_zone_connections yes)
		)
		(net 58)
	)
	(via
		(at 103.6 83.81)
		(size 0.45)
		(drill 0.1)
		(layers "F.Cu" "B.Cu")
		(remove_unused_layers yes)
		(keep_end_layers yes)
		(zone_layer_connections)
		(teardrops
			(best_length_ratio 0.4)
			(max_length 1)
			(best_width_ratio 0.9)
			(max_width 2)
			(curved_edges yes)
			(filter_ratio 0.9)
			(enabled yes)
			(allow_two_segments yes)
			(prefer_zone_connections yes)
		)
		(net 58)
	)
	(via
		(at 103.6 86.084)
		(size 0.45)
		(drill 0.1)
		(layers "F.Cu" "B.Cu")
		(remove_unused_layers yes)
		(keep_end_layers yes)
		(zone_layer_connections)
		(teardrops
			(best_length_ratio 0.4)
			(max_length 1)
			(best_width_ratio 0.9)
			(max_width 2)
			(curved_edges yes)
			(filter_ratio 0.9)
			(enabled yes)
			(allow_two_segments yes)
			(prefer_zone_connections yes)
		)
		(net 58)
	)
	(via
		(at 114.834999 77.725)
		(size 0.45)
		(drill 0.1)
		(layers "F.Cu" "B.Cu")
		(remove_unused_layers yes)
		(keep_end_layers yes)
		(zone_layer_connections "In2.Cu")
		(teardrops
			(best_length_ratio 0.4)
			(max_length 1)
			(best_width_ratio 0.9)
			(max_width 2)
			(curved_edges yes)
			(filter_ratio 0.9)
			(enabled yes)
			(allow_two_segments yes)
			(prefer_zone_connections yes)
		)
		(net 58)
	)
	(segment
		(start 103.274 84.136)
		(end 103.274 84.947)
		(width 0.5)
		(layer "B.Cu")
		(net 58)
	)
	(segment
		(start 103.6 83.81)
		(end 103.274 84.136)
		(width 0.5)
		(layer "B.Cu")
		(net 58)
	)
	(segment
		(start 101.1 86.084)
		(end 103.6 86.084)
		(width 0.5)
		(layer "B.Cu")
		(net 58)
	)
	(segment
		(start 101.1 86.084)
		(end 101.1 83.81)
		(width 0.5)
		(layer "In2.Cu")
		(net 58)
	)
	(segment
		(start 107.71 78.11)
		(end 114.449999 78.11)
		(width 0.5)
		(layer "In2.Cu")
		(net 58)
	)
	(segment
		(start 103.6 86.084)
		(end 103.6 83.81)
		(width 0.5)
		(layer "In2.Cu")
		(net 58)
	)
	(segment
		(start 120.5 73.13)
		(end 115.905 77.725)
		(width 0.3)
		(layer "In2.Cu")
		(net 58)
	)
	(segment
		(start 104.45 82.96)
		(end 104.45 81.37)
		(width 0.5)
		(layer "In2.Cu")
		(net 58)
	)
	(segment
		(start 104.45 81.37)
		(end 107.71 78.11)
		(width 0.5)
		(layer "In2.Cu")
		(net 58)
	)
	(segment
		(start 114.449999 78.11)
		(end 114.834999 77.725)
		(width 0.5)
		(layer "In2.Cu")
		(net 58)
	)
	(segment
		(start 103.6 83.81)
		(end 104.45 82.96)
		(width 0.5)
		(layer "In2.Cu")
		(net 58)
	)
	(segment
		(start 115.905 77.725)
		(end 114.834999 77.725)
		(width 0.3)
		(layer "In2.Cu")
		(net 58)
	)
	(segment
		(start 101.1 83.81)
		(end 103.6 83.81)
		(width 0.5)
		(layer "In2.Cu")
		(net 58)
	)
	(segment
		(start 103.96 155.66)
		(end 103.96 156.85)
		(width 0.3)
		(layer "B.Cu")
		(net 59)
	)
	(segment
		(start 103.205 157.605)
		(end 103.95 156.86)
		(width 0.3)
		(layer "B.Cu")
		(net 59)
	)
	(segment
		(start 102.465 157.605)
		(end 103.205 157.605)
		(width 0.3)
		(layer "B.Cu")
		(net 59)
	)
	(segment
		(start 102.64 167.99)
		(end 101.67 167.99)
		(width 0.2)
		(layer "B.Cu")
		(net 60)
	)
	(segment
		(start 101.67 167.99)
		(end 101.38 167.7)
		(width 0.2)
		(layer "B.Cu")
		(net 60)
	)
	(segment
		(start 103.06 168.41)
		(end 103.41 168.76)
		(width 0.3)
		(layer "B.Cu")
		(net 60)
	)
	(segment
		(start 103.41 168.76)
		(end 103.95 168.76)
		(width 0.3)
		(layer "B.Cu")
		(net 60)
	)
	(segment
		(start 101.38 167.7)
		(end 101.38 167.697107)
		(width 0.3)
		(layer "B.Cu")
		(net 60)
	)
	(segment
		(start 101.38 167.697107)
		(end 100.782893 167.1)
		(width 0.3)
		(layer "B.Cu")
		(net 60)
	)
	(segment
		(start 100.782893 167.1)
		(end 100.21 167.1)
		(width 0.3)
		(layer "B.Cu")
		(net 60)
	)
	(segment
		(start 103.06 168.41)
		(end 102.64 167.99)
		(width 0.2)
		(layer "B.Cu")
		(net 60)
	)
	(segment
		(start 103.95 168.76)
		(end 103.95 169.95)
		(width 0.3)
		(layer "B.Cu")
		(net 60)
	)
	(via
		(at 103.56 167.59)
		(size 0.45)
		(drill 0.1)
		(layers "F.Cu" "B.Cu")
		(remove_unused_layers yes)
		(keep_end_layers yes)
		(zone_layer_connections "In3.Cu")
		(teardrops
			(best_length_ratio 0.4)
			(max_length 1)
			(best_width_ratio 0.9)
			(max_width 2)
			(curved_edges yes)
			(filter_ratio 0.9)
			(enabled yes)
			(allow_two_segments yes)
			(prefer_zone_connections yes)
		)
		(net 61)
	)
	(via
		(at 101.16 157.08)
		(size 0.45)
		(drill 0.1)
		(layers "F.Cu" "B.Cu")
		(remove_unused_layers yes)
		(keep_end_layers yes)
		(zone_layer_connections "In3.Cu")
		(teardrops
			(best_length_ratio 0.4)
			(max_length 1)
			(best_width_ratio 0.9)
			(max_width 2)
			(curved_edges yes)
			(filter_ratio 0.9)
			(enabled yes)
			(allow_two_segments yes)
			(prefer_zone_connections yes)
		)
		(net 61)
	)
	(via
		(at 103.95 154.46)
		(size 0.45)
		(drill 0.1)
		(layers "F.Cu" "B.Cu")
		(remove_unused_layers yes)
		(keep_end_layers yes)
		(zone_layer_connections "In3.Cu")
		(teardrops
			(best_length_ratio 0.4)
			(max_length 1)
			(best_width_ratio 0.9)
			(max_width 2)
			(curved_edges yes)
			(filter_ratio 0.9)
			(enabled yes)
			(allow_two_segments yes)
			(prefer_zone_connections yes)
		)
		(net 61)
	)
	(via
		(at 103.94 152.835)
		(size 0.45)
		(drill 0.1)
		(layers "F.Cu" "B.Cu")
		(remove_unused_layers yes)
		(keep_end_layers yes)
		(zone_layer_connections "In3.Cu")
		(teardrops
			(best_length_ratio 0.4)
			(max_length 1)
			(best_width_ratio 0.9)
			(max_width 2)
			(curved_edges yes)
			(filter_ratio 0.9)
			(enabled yes)
			(allow_two_segments yes)
			(prefer_zone_connections yes)
		)
		(net 61)
	)
	(segment
		(start 100.21 157.1)
		(end 101.14 157.1)
		(width 0.3)
		(layer "B.Cu")
		(net 61)
	)
	(segment
		(start 103.54 167.61)
		(end 102.47 167.61)
		(width 0.3)
		(layer "B.Cu")
		(net 61)
	)
	(segment
		(start 103.94 152.65)
		(end 103.94 154.45)
		(width 0.3)
		(layer "B.Cu")
		(net 61)
	)
	(segment
		(start 103.56 167.59)
		(end 103.54 167.61)
		(width 0.3)
		(layer "B.Cu")
		(net 61)
	)
	(segment
		(start 101.14 157.1)
		(end 101.16 157.08)
		(width 0.3)
		(layer "B.Cu")
		(net 61)
	)
	(segment
		(start 313.648999 120.558999)
		(end 313.114999 120.558999)
		(width 0.2)
		(layer "F.Cu")
		(net 62)
	)
	(segment
		(start 310.85 143.61)
		(end 310.85 144.285)
		(width 0.125)
		(layer "F.Cu")
		(net 62)
	)
	(segment
		(start 313.648999 104.748999)
		(end 313.114999 104.748999)
		(width 0.2)
		(layer "F.Cu")
		(net 62)
	)
	(segment
		(start 310.6 144.535)
		(end 308.175 144.535)
		(width 0.125)
		(layer "F.Cu")
		(net 62)
	)
	(segment
		(start 313.648999 120.108999)
		(end 313.114999 120.108999)
		(width 0.2)
		(layer "F.Cu")
		(net 62)
	)
	(segment
		(start 305.827 146.883)
		(end 305.827 147.809)
		(width 0.125)
		(layer "F.Cu")
		(net 62)
	)
	(segment
		(start 313.566001 121.013999)
		(end 313.114999 121.013999)
		(width 0.2)
		(layer "F.Cu")
		(net 62)
	)
	(segment
		(start 199.05861 74.102163)
		(end 199.70861 74.102163)
		(width 0.2)
		(layer "F.Cu")
		(net 62)
	)
	(segment
		(start 199.70861 74.102163)
		(end 201.70861 74.102163)
		(width 0.2)
		(layer "F.Cu")
		(net 62)
	)
	(segment
		(start 313.114999 103.848999)
		(end 313.648999 103.848999)
		(width 0.2)
		(layer "F.Cu")
		(net 62)
	)
	(segment
		(start 308.175 144.535)
		(end 305.827 146.883)
		(width 0.125)
		(layer "F.Cu")
		(net 62)
	)
	(segment
		(start 310.85 144.285)
		(end 310.6 144.535)
		(width 0.125)
		(layer "F.Cu")
		(net 62)
	)
	(segment
		(start 313.114999 119.658999)
		(end 313.648999 119.658999)
		(width 0.2)
		(layer "F.Cu")
		(net 62)
	)
	(segment
		(start 313.648999 104.298999)
		(end 313.114999 104.298999)
		(width 0.2)
		(layer "F.Cu")
		(net 62)
	)
	(segment
		(start 313.73 120.85)
		(end 313.566001 121.013999)
		(width 0.2)
		(layer "F.Cu")
		(net 62)
	)
	(segment
		(start 313.73 105.04)
		(end 313.566001 105.203999)
		(width 0.2)
		(layer "F.Cu")
		(net 62)
	)
	(segment
		(start 186.70861 74.102163)
		(end 186.70861 72.802163)
		(width 0.2)
		(layer "F.Cu")
		(net 62)
	)
	(segment
		(start 313.566001 105.203999)
		(end 313.114999 105.203999)
		(width 0.2)
		(layer "F.Cu")
		(net 62)
	)
	(segment
		(start 198.73361 69.552163)
		(end 198.73361 73.777163)
		(width 0.2)
		(layer "F.Cu")
		(net 62)
	)
	(segment
		(start 198.73361 73.777163)
		(end 199.05861 74.102163)
		(width 0.2)
		(layer "F.Cu")
		(net 62)
	)
	(via
		(at 312.35 142.76)
		(size 0.45)
		(drill 0.1)
		(layers "F.Cu" "B.Cu")
		(remove_unused_layers yes)
		(keep_end_layers yes)
		(zone_layer_connections "In3.Cu")
		(teardrops
			(best_length_ratio 0.4)
			(max_length 1)
			(best_width_ratio 0.9)
			(max_width 2)
			(curved_edges yes)
			(filter_ratio 0.9)
			(enabled yes)
			(allow_two_segments yes)
			(prefer_zone_connections yes)
		)
		(net 62)
	)
	(via
		(at 314.464501 93.6365)
		(size 0.45)
		(drill 0.1)
		(layers "F.Cu" "B.Cu")
		(remove_unused_layers yes)
		(keep_end_layers yes)
		(zone_layer_connections "In3.Cu" "In5.Cu")
		(teardrops
			(best_length_ratio 0.4)
			(max_length 1)
			(best_width_ratio 0.9)
			(max_width 2)
			(curved_edges yes)
			(filter_ratio 0.9)
			(enabled yes)
			(allow_two_segments yes)
			(prefer_zone_connections yes)
		)
		(net 62)
	)
	(via
		(at 315.899999 110.06)
		(size 0.45)
		(drill 0.1)
		(layers "F.Cu" "B.Cu")
		(remove_unused_layers yes)
		(keep_end_layers yes)
		(free yes)
		(zone_layer_connections "In3.Cu")
		(teardrops
			(best_length_ratio 0.4)
			(max_length 1)
			(best_width_ratio 0.9)
			(max_width 2)
			(curved_edges yes)
			(filter_ratio 0.9)
			(enabled yes)
			(allow_two_segments yes)
			(prefer_zone_connections yes)
		)
		(net 62)
	)
	(via
		(at 311.35 141.76)
		(size 0.45)
		(drill 0.1)
		(layers "F.Cu" "B.Cu")
		(remove_unused_layers yes)
		(keep_end_layers yes)
		(zone_layer_connections "In3.Cu")
		(teardrops
			(best_length_ratio 0.4)
			(max_length 1)
			(best_width_ratio 0.9)
			(max_width 2)
			(curved_edges yes)
			(filter_ratio 0.9)
			(enabled yes)
			(allow_two_segments yes)
			(prefer_zone_connections yes)
		)
		(net 62)
	)
	(via
		(at 317.464501 94.6365)
		(size 0.45)
		(drill 0.1)
		(layers "F.Cu" "B.Cu")
		(remove_unused_layers yes)
		(keep_end_layers yes)
		(zone_layer_connections "In3.Cu")
		(teardrops
			(best_length_ratio 0.4)
			(max_length 1)
			(best_width_ratio 0.9)
			(max_width 2)
			(curved_edges yes)
			(filter_ratio 0.9)
			(enabled yes)
			(allow_two_segments yes)
			(prefer_zone_connections yes)
		)
		(net 62)
	)
	(via
		(at 318.464501 94.6365)
		(size 0.45)
		(drill 0.1)
		(layers "F.Cu" "B.Cu")
		(remove_unused_layers yes)
		(keep_end_layers yes)
		(zone_layer_connections "In3.Cu")
		(teardrops
			(best_length_ratio 0.4)
			(max_length 1)
			(best_width_ratio 0.9)
			(max_width 2)
			(curved_edges yes)
			(filter_ratio 0.9)
			(enabled yes)
			(allow_two_segments yes)
			(prefer_zone_connections yes)
		)
		(net 62)
	)
	(via
		(at 317.464501 93.6365)
		(size 0.45)
		(drill 0.1)
		(layers "F.Cu" "B.Cu")
		(remove_unused_layers yes)
		(keep_end_layers yes)
		(zone_layer_connections "In3.Cu")
		(teardrops
			(best_length_ratio 0.4)
			(max_length 1)
			(best_width_ratio 0.9)
			(max_width 2)
			(curved_edges yes)
			(filter_ratio 0.9)
			(enabled yes)
			(allow_two_segments yes)
			(prefer_zone_connections yes)
		)
		(net 62)
	)
	(via
		(at 314.4895 132.71)
		(size 0.45)
		(drill 0.1)
		(layers "F.Cu" "B.Cu")
		(remove_unused_layers yes)
		(keep_end_layers yes)
		(zone_layer_connections "In3.Cu")
		(teardrops
			(best_length_ratio 0.4)
			(max_length 1)
			(best_width_ratio 0.9)
			(max_width 2)
			(curved_edges yes)
			(filter_ratio 0.9)
			(enabled yes)
			(allow_two_segments yes)
			(prefer_zone_connections yes)
		)
		(net 62)
	)
	(via
		(at 317.9 110.06)
		(size 0.45)
		(drill 0.1)
		(layers "F.Cu" "B.Cu")
		(remove_unused_layers yes)
		(keep_end_layers yes)
		(free yes)
		(zone_layer_connections "In3.Cu")
		(teardrops
			(best_length_ratio 0.4)
			(max_length 1)
			(best_width_ratio 0.9)
			(max_width 2)
			(curved_edges yes)
			(filter_ratio 0.9)
			(enabled yes)
			(allow_two_segments yes)
			(prefer_zone_connections yes)
		)
		(net 62)
	)
	(via
		(at 315.9 109.06)
		(size 0.45)
		(drill 0.1)
		(layers "F.Cu" "B.Cu")
		(remove_unused_layers yes)
		(keep_end_layers yes)
		(free yes)
		(zone_layer_connections "In3.Cu")
		(teardrops
			(best_length_ratio 0.4)
			(max_length 1)
			(best_width_ratio 0.9)
			(max_width 2)
			(curved_edges yes)
			(filter_ratio 0.9)
			(enabled yes)
			(allow_two_segments yes)
			(prefer_zone_connections yes)
		)
		(net 62)
	)
	(via
		(at 315.9 108.06)
		(size 0.45)
		(drill 0.1)
		(layers "F.Cu" "B.Cu")
		(remove_unused_layers yes)
		(keep_end_layers yes)
		(free yes)
		(zone_layer_connections "In3.Cu")
		(teardrops
			(best_length_ratio 0.4)
			(max_length 1)
			(best_width_ratio 0.9)
			(max_width 2)
			(curved_edges yes)
			(filter_ratio 0.9)
			(enabled yes)
			(allow_two_segments yes)
			(prefer_zone_connections yes)
		)
		(net 62)
	)
	(via
		(at 312.35 143.76)
		(size 0.45)
		(drill 0.1)
		(layers "F.Cu" "B.Cu")
		(remove_unused_layers yes)
		(keep_end_layers yes)
		(zone_layer_connections "In3.Cu")
		(teardrops
			(best_length_ratio 0.4)
			(max_length 1)
			(best_width_ratio 0.9)
			(max_width 2)
			(curved_edges yes)
			(filter_ratio 0.9)
			(enabled yes)
			(allow_two_segments yes)
			(prefer_zone_connections yes)
		)
		(net 62)
	)
	(via
		(at 310.35 140.76)
		(size 0.45)
		(drill 0.1)
		(layers "F.Cu" "B.Cu")
		(remove_unused_layers yes)
		(keep_end_layers yes)
		(zone_layer_connections "In3.Cu")
		(teardrops
			(best_length_ratio 0.4)
			(max_length 1)
			(best_width_ratio 0.9)
			(max_width 2)
			(curved_edges yes)
			(filter_ratio 0.9)
			(enabled yes)
			(allow_two_segments yes)
			(prefer_zone_connections yes)
		)
		(net 62)
	)
	(via
		(at 317.9 123.86)
		(size 0.45)
		(drill 0.1)
		(layers "F.Cu" "B.Cu")
		(remove_unused_layers yes)
		(keep_end_layers yes)
		(free yes)
		(zone_layer_connections "In3.Cu")
		(teardrops
			(best_length_ratio 0.4)
			(max_length 1)
			(best_width_ratio 0.9)
			(max_width 2)
			(curved_edges yes)
			(filter_ratio 0.9)
			(enabled yes)
			(allow_two_segments yes)
			(prefer_zone_connections yes)
		)
		(net 62)
	)
	(via
		(at 310.35 141.76)
		(size 0.45)
		(drill 0.1)
		(layers "F.Cu" "B.Cu")
		(remove_unused_layers yes)
		(keep_end_layers yes)
		(zone_layer_connections "In3.Cu")
		(teardrops
			(best_length_ratio 0.4)
			(max_length 1)
			(best_width_ratio 0.9)
			(max_width 2)
			(curved_edges yes)
			(filter_ratio 0.9)
			(enabled yes)
			(allow_two_segments yes)
			(prefer_zone_connections yes)
		)
		(net 62)
	)
	(via
		(at 312.35 139.76)
		(size 0.45)
		(drill 0.1)
		(layers "F.Cu" "B.Cu")
		(remove_unused_layers yes)
		(keep_end_layers yes)
		(zone_layer_connections "In3.Cu")
		(teardrops
			(best_length_ratio 0.4)
			(max_length 1)
			(best_width_ratio 0.9)
			(max_width 2)
			(curved_edges yes)
			(filter_ratio 0.9)
			(enabled yes)
			(allow_two_segments yes)
			(prefer_zone_connections yes)
		)
		(net 62)
	)
	(via
		(at 315.4895 132.71)
		(size 0.45)
		(drill 0.1)
		(layers "F.Cu" "B.Cu")
		(remove_unused_layers yes)
		(keep_end_layers yes)
		(zone_layer_connections "In3.Cu")
		(teardrops
			(best_length_ratio 0.4)
			(max_length 1)
			(best_width_ratio 0.9)
			(max_width 2)
			(curved_edges yes)
			(filter_ratio 0.9)
			(enabled yes)
			(allow_two_segments yes)
			(prefer_zone_connections yes)
		)
		(net 62)
	)
	(via
		(at 316.4895 133.71)
		(size 0.45)
		(drill 0.1)
		(layers "F.Cu" "B.Cu")
		(remove_unused_layers yes)
		(keep_end_layers yes)
		(zone_layer_connections "In3.Cu")
		(teardrops
			(best_length_ratio 0.4)
			(max_length 1)
			(best_width_ratio 0.9)
			(max_width 2)
			(curved_edges yes)
			(filter_ratio 0.9)
			(enabled yes)
			(allow_two_segments yes)
			(prefer_zone_connections yes)
		)
		(net 62)
	)
	(via
		(at 310.35 138.76)
		(size 0.45)
		(drill 0.1)
		(layers "F.Cu" "B.Cu")
		(remove_unused_layers yes)
		(keep_end_layers yes)
		(zone_layer_connections "In3.Cu")
		(teardrops
			(best_length_ratio 0.4)
			(max_length 1)
			(best_width_ratio 0.9)
			(max_width 2)
			(curved_edges yes)
			(filter_ratio 0.9)
			(enabled yes)
			(allow_two_segments yes)
			(prefer_zone_connections yes)
		)
		(net 62)
	)
	(via
		(at 318.4895 132.71)
		(size 0.45)
		(drill 0.1)
		(layers "F.Cu" "B.Cu")
		(remove_unused_layers yes)
		(keep_end_layers yes)
		(zone_layer_connections "In3.Cu")
		(teardrops
			(best_length_ratio 0.4)
			(max_length 1)
			(best_width_ratio 0.9)
			(max_width 2)
			(curved_edges yes)
			(filter_ratio 0.9)
			(enabled yes)
			(allow_two_segments yes)
			(prefer_zone_connections yes)
		)
		(net 62)
	)
	(via
		(at 317.9 109.06)
		(size 0.45)
		(drill 0.1)
		(layers "F.Cu" "B.Cu")
		(remove_unused_layers yes)
		(keep_end_layers yes)
		(free yes)
		(zone_layer_connections "In3.Cu")
		(teardrops
			(best_length_ratio 0.4)
			(max_length 1)
			(best_width_ratio 0.9)
			(max_width 2)
			(curved_edges yes)
			(filter_ratio 0.9)
			(enabled yes)
			(allow_two_segments yes)
			(prefer_zone_connections yes)
		)
		(net 62)
	)
	(via
		(at 311.35 140.76)
		(size 0.45)
		(drill 0.1)
		(layers "F.Cu" "B.Cu")
		(remove_unused_layers yes)
		(keep_end_layers yes)
		(zone_layer_connections "In3.Cu")
		(teardrops
			(best_length_ratio 0.4)
			(max_length 1)
			(best_width_ratio 0.9)
			(max_width 2)
			(curved_edges yes)
			(filter_ratio 0.9)
			(enabled yes)
			(allow_two_segments yes)
			(prefer_zone_connections yes)
		)
		(net 62)
	)
	(via
		(at 310.35 139.76)
		(size 0.45)
		(drill 0.1)
		(layers "F.Cu" "B.Cu")
		(remove_unused_layers yes)
		(keep_end_layers yes)
		(zone_layer_connections "In3.Cu")
		(teardrops
			(best_length_ratio 0.4)
			(max_length 1)
			(best_width_ratio 0.9)
			(max_width 2)
			(curved_edges yes)
			(filter_ratio 0.9)
			(enabled yes)
			(allow_two_segments yes)
			(prefer_zone_connections yes)
		)
		(net 62)
	)
	(via
		(at 317.9 108.06)
		(size 0.45)
		(drill 0.1)
		(layers "F.Cu" "B.Cu")
		(remove_unused_layers yes)
		(keep_end_layers yes)
		(free yes)
		(zone_layer_connections "In3.Cu")
		(teardrops
			(best_length_ratio 0.4)
			(max_length 1)
			(best_width_ratio 0.9)
			(max_width 2)
			(curved_edges yes)
			(filter_ratio 0.9)
			(enabled yes)
			(allow_two_segments yes)
			(prefer_zone_connections yes)
		)
		(net 62)
	)
	(via
		(at 310.35 142.76)
		(size 0.45)
		(drill 0.1)
		(layers "F.Cu" "B.Cu")
		(remove_unused_layers yes)
		(keep_end_layers yes)
		(zone_layer_connections "In3.Cu")
		(teardrops
			(best_length_ratio 0.4)
			(max_length 1)
			(best_width_ratio 0.9)
			(max_width 2)
			(curved_edges yes)
			(filter_ratio 0.9)
			(enabled yes)
			(allow_two_segments yes)
			(prefer_zone_connections yes)
		)
		(net 62)
	)
	(via
		(at 310.35 143.76)
		(size 0.45)
		(drill 0.1)
		(layers "F.Cu" "B.Cu")
		(remove_unused_layers yes)
		(keep_end_layers yes)
		(zone_layer_connections "In3.Cu")
		(teardrops
			(best_length_ratio 0.4)
			(max_length 1)
			(best_width_ratio 0.9)
			(max_width 2)
			(curved_edges yes)
			(filter_ratio 0.9)
			(enabled yes)
			(allow_two_segments yes)
			(prefer_zone_connections yes)
		)
		(net 62)
	)
	(via
		(at 316.9 125.86)
		(size 0.45)
		(drill 0.1)
		(layers "F.Cu" "B.Cu")
		(remove_unused_layers yes)
		(keep_end_layers yes)
		(free yes)
		(zone_layer_connections "In3.Cu")
		(teardrops
			(best_length_ratio 0.4)
			(max_length 1)
			(best_width_ratio 0.9)
			(max_width 2)
			(curved_edges yes)
			(filter_ratio 0.9)
			(enabled yes)
			(allow_two_segments yes)
			(prefer_zone_connections yes)
		)
		(net 62)
	)
	(via
		(at 186.70861 74.102163)
		(size 0.45)
		(drill 0.1)
		(layers "F.Cu" "B.Cu")
		(remove_unused_layers yes)
		(keep_end_layers yes)
		(zone_layer_connections "In5.Cu")
		(teardrops
			(best_length_ratio 0.4)
			(max_length 1)
			(best_width_ratio 0.9)
			(max_width 2)
			(curved_edges yes)
			(filter_ratio 0.9)
			(enabled yes)
			(allow_two_segments yes)
			(prefer_zone_connections yes)
		)
		(net 62)
	)
	(via
		(at 316.9 110.06)
		(size 0.45)
		(drill 0.1)
		(layers "F.Cu" "B.Cu")
		(remove_unused_layers yes)
		(keep_end_layers yes)
		(free yes)
		(zone_layer_connections "In3.Cu")
		(teardrops
			(best_length_ratio 0.4)
			(max_length 1)
			(best_width_ratio 0.9)
			(max_width 2)
			(curved_edges yes)
			(filter_ratio 0.9)
			(enabled yes)
			(allow_two_segments yes)
			(prefer_zone_connections yes)
		)
		(net 62)
	)
	(via
		(at 309.35 138.76)
		(size 0.45)
		(drill 0.1)
		(layers "F.Cu" "B.Cu")
		(remove_unused_layers yes)
		(keep_end_layers yes)
		(zone_layer_connections "In3.Cu")
		(teardrops
			(best_length_ratio 0.4)
			(max_length 1)
			(best_width_ratio 0.9)
			(max_width 2)
			(curved_edges yes)
			(filter_ratio 0.9)
			(enabled yes)
			(allow_two_segments yes)
			(prefer_zone_connections yes)
		)
		(net 62)
	)
	(via
		(at 316.464501 94.6365)
		(size 0.45)
		(drill 0.1)
		(layers "F.Cu" "B.Cu")
		(remove_unused_layers yes)
		(keep_end_layers yes)
		(zone_layer_connections "In3.Cu")
		(teardrops
			(best_length_ratio 0.4)
			(max_length 1)
			(best_width_ratio 0.9)
			(max_width 2)
			(curved_edges yes)
			(filter_ratio 0.9)
			(enabled yes)
			(allow_two_segments yes)
			(prefer_zone_connections yes)
		)
		(net 62)
	)
	(via
		(at 309.35 141.76)
		(size 0.45)
		(drill 0.1)
		(layers "F.Cu" "B.Cu")
		(remove_unused_layers yes)
		(keep_end_layers yes)
		(zone_layer_connections "In3.Cu")
		(teardrops
			(best_length_ratio 0.4)
			(max_length 1)
			(best_width_ratio 0.9)
			(max_width 2)
			(curved_edges yes)
			(filter_ratio 0.9)
			(enabled yes)
			(allow_two_segments yes)
			(prefer_zone_connections yes)
		)
		(net 62)
	)
	(via
		(at 316.9 124.86)
		(size 0.45)
		(drill 0.1)
		(layers "F.Cu" "B.Cu")
		(remove_unused_layers yes)
		(keep_end_layers yes)
		(free yes)
		(zone_layer_connections "In3.Cu")
		(teardrops
			(best_length_ratio 0.4)
			(max_length 1)
			(best_width_ratio 0.9)
			(max_width 2)
			(curved_edges yes)
			(filter_ratio 0.9)
			(enabled yes)
			(allow_two_segments yes)
			(prefer_zone_connections yes)
		)
		(net 62)
	)
	(via
		(at 315.464501 93.6365)
		(size 0.45)
		(drill 0.1)
		(layers "F.Cu" "B.Cu")
		(remove_unused_layers yes)
		(keep_end_layers yes)
		(zone_layer_connections "In3.Cu")
		(teardrops
			(best_length_ratio 0.4)
			(max_length 1)
			(best_width_ratio 0.9)
			(max_width 2)
			(curved_edges yes)
			(filter_ratio 0.9)
			(enabled yes)
			(allow_two_segments yes)
			(prefer_zone_connections yes)
		)
		(net 62)
	)
	(via
		(at 318.4895 133.71)
		(size 0.45)
		(drill 0.1)
		(layers "F.Cu" "B.Cu")
		(remove_unused_layers yes)
		(keep_end_layers yes)
		(zone_layer_connections "In3.Cu")
		(teardrops
			(best_length_ratio 0.4)
			(max_length 1)
			(best_width_ratio 0.9)
			(max_width 2)
			(curved_edges yes)
			(filter_ratio 0.9)
			(enabled yes)
			(allow_two_segments yes)
			(prefer_zone_connections yes)
		)
		(net 62)
	)
	(via
		(at 317.4895 133.71)
		(size 0.45)
		(drill 0.1)
		(layers "F.Cu" "B.Cu")
		(remove_unused_layers yes)
		(keep_end_layers yes)
		(zone_layer_connections "In3.Cu")
		(teardrops
			(best_length_ratio 0.4)
			(max_length 1)
			(best_width_ratio 0.9)
			(max_width 2)
			(curved_edges yes)
			(filter_ratio 0.9)
			(enabled yes)
			(allow_two_segments yes)
			(prefer_zone_connections yes)
		)
		(net 62)
	)
	(via
		(at 309.35 142.76)
		(size 0.45)
		(drill 0.1)
		(layers "F.Cu" "B.Cu")
		(remove_unused_layers yes)
		(keep_end_layers yes)
		(zone_layer_connections "In3.Cu")
		(teardrops
			(best_length_ratio 0.4)
			(max_length 1)
			(best_width_ratio 0.9)
			(max_width 2)
			(curved_edges yes)
			(filter_ratio 0.9)
			(enabled yes)
			(allow_two_segments yes)
			(prefer_zone_connections yes)
		)
		(net 62)
	)
	(via
		(at 312.35 138.76)
		(size 0.45)
		(drill 0.1)
		(layers "F.Cu" "B.Cu")
		(remove_unused_layers yes)
		(keep_end_layers yes)
		(zone_layer_connections "In3.Cu")
		(teardrops
			(best_length_ratio 0.4)
			(max_length 1)
			(best_width_ratio 0.9)
			(max_width 2)
			(curved_edges yes)
			(filter_ratio 0.9)
			(enabled yes)
			(allow_two_segments yes)
			(prefer_zone_connections yes)
		)
		(net 62)
	)
	(via
		(at 315.9 124.86)
		(size 0.45)
		(drill 0.1)
		(layers "F.Cu" "B.Cu")
		(remove_unused_layers yes)
		(keep_end_layers yes)
		(free yes)
		(zone_layer_connections "In3.Cu")
		(teardrops
			(best_length_ratio 0.4)
			(max_length 1)
			(best_width_ratio 0.9)
			(max_width 2)
			(curved_edges yes)
			(filter_ratio 0.9)
			(enabled yes)
			(allow_two_segments yes)
			(prefer_zone_connections yes)
		)
		(net 62)
	)
	(via
		(at 317.9 125.86)
		(size 0.45)
		(drill 0.1)
		(layers "F.Cu" "B.Cu")
		(remove_unused_layers yes)
		(keep_end_layers yes)
		(free yes)
		(zone_layer_connections "In3.Cu")
		(teardrops
			(best_length_ratio 0.4)
			(max_length 1)
			(best_width_ratio 0.9)
			(max_width 2)
			(curved_edges yes)
			(filter_ratio 0.9)
			(enabled yes)
			(allow_two_segments yes)
			(prefer_zone_connections yes)
		)
		(net 62)
	)
	(via
		(at 312.35 141.76)
		(size 0.45)
		(drill 0.1)
		(layers "F.Cu" "B.Cu")
		(remove_unused_layers yes)
		(keep_end_layers yes)
		(zone_layer_connections "In3.Cu")
		(teardrops
			(best_length_ratio 0.4)
			(max_length 1)
			(best_width_ratio 0.9)
			(max_width 2)
			(curved_edges yes)
			(filter_ratio 0.9)
			(enabled yes)
			(allow_two_segments yes)
			(prefer_zone_connections yes)
		)
		(net 62)
	)
	(via
		(at 309.35 140.76)
		(size 0.45)
		(drill 0.1)
		(layers "F.Cu" "B.Cu")
		(remove_unused_layers yes)
		(keep_end_layers yes)
		(zone_layer_connections "In3.Cu")
		(teardrops
			(best_length_ratio 0.4)
			(max_length 1)
			(best_width_ratio 0.9)
			(max_width 2)
			(curved_edges yes)
			(filter_ratio 0.9)
			(enabled yes)
			(allow_two_segments yes)
			(prefer_zone_connections yes)
		)
		(net 62)
	)
	(via
		(at 311.35 138.76)
		(size 0.45)
		(drill 0.1)
		(layers "F.Cu" "B.Cu")
		(remove_unused_layers yes)
		(keep_end_layers yes)
		(zone_layer_connections "In3.Cu")
		(teardrops
			(best_length_ratio 0.4)
			(max_length 1)
			(best_width_ratio 0.9)
			(max_width 2)
			(curved_edges yes)
			(filter_ratio 0.9)
			(enabled yes)
			(allow_two_segments yes)
			(prefer_zone_connections yes)
		)
		(net 62)
	)
	(via
		(at 316.9 108.06)
		(size 0.45)
		(drill 0.1)
		(layers "F.Cu" "B.Cu")
		(remove_unused_layers yes)
		(keep_end_layers yes)
		(free yes)
		(zone_layer_connections "In3.Cu")
		(teardrops
			(best_length_ratio 0.4)
			(max_length 1)
			(best_width_ratio 0.9)
			(max_width 2)
			(curved_edges yes)
			(filter_ratio 0.9)
			(enabled yes)
			(allow_two_segments yes)
			(prefer_zone_connections yes)
		)
		(net 62)
	)
	(via
		(at 311.35 139.76)
		(size 0.45)
		(drill 0.1)
		(layers "F.Cu" "B.Cu")
		(remove_unused_layers yes)
		(keep_end_layers yes)
		(zone_layer_connections "In3.Cu")
		(teardrops
			(best_length_ratio 0.4)
			(max_length 1)
			(best_width_ratio 0.9)
			(max_width 2)
			(curved_edges yes)
			(filter_ratio 0.9)
			(enabled yes)
			(allow_two_segments yes)
			(prefer_zone_connections yes)
		)
		(net 62)
	)
	(via
		(at 198.73361 69.552163)
		(size 0.45)
		(drill 0.1)
		(layers "F.Cu" "B.Cu")
		(remove_unused_layers yes)
		(keep_end_layers yes)
		(zone_layer_connections "In5.Cu")
		(teardrops
			(best_length_ratio 0.4)
			(max_length 1)
			(best_width_ratio 0.9)
			(max_width 2)
			(curved_edges yes)
			(filter_ratio 0.9)
			(enabled yes)
			(allow_two_segments yes)
			(prefer_zone_connections yes)
		)
		(net 62)
	)
	(via
		(at 316.9 109.06)
		(size 0.45)
		(drill 0.1)
		(layers "F.Cu" "B.Cu")
		(remove_unused_layers yes)
		(keep_end_layers yes)
		(free yes)
		(zone_layer_connections "In3.Cu")
		(teardrops
			(best_length_ratio 0.4)
			(max_length 1)
			(best_width_ratio 0.9)
			(max_width 2)
			(curved_edges yes)
			(filter_ratio 0.9)
			(enabled yes)
			(allow_two_segments yes)
			(prefer_zone_connections yes)
		)
		(net 62)
	)
	(via
		(at 318.464501 93.6365)
		(size 0.45)
		(drill 0.1)
		(layers "F.Cu" "B.Cu")
		(remove_unused_layers yes)
		(keep_end_layers yes)
		(zone_layer_connections "In3.Cu")
		(teardrops
			(best_length_ratio 0.4)
			(max_length 1)
			(best_width_ratio 0.9)
			(max_width 2)
			(curved_edges yes)
			(filter_ratio 0.9)
			(enabled yes)
			(allow_two_segments yes)
			(prefer_zone_connections yes)
		)
		(net 62)
	)
	(via
		(at 317.4895 132.71)
		(size 0.45)
		(drill 0.1)
		(layers "F.Cu" "B.Cu")
		(remove_unused_layers yes)
		(keep_end_layers yes)
		(zone_layer_connections "In3.Cu")
		(teardrops
			(best_length_ratio 0.4)
			(max_length 1)
			(best_width_ratio 0.9)
			(max_width 2)
			(curved_edges yes)
			(filter_ratio 0.9)
			(enabled yes)
			(allow_two_segments yes)
			(prefer_zone_connections yes)
		)
		(net 62)
	)
	(via
		(at 312.765499 97.9165)
		(size 0.45)
		(drill 0.1)
		(layers "F.Cu" "B.Cu")
		(remove_unused_layers yes)
		(keep_end_layers yes)
		(zone_layer_connections "In3.Cu")
		(teardrops
			(best_length_ratio 0.4)
			(max_length 1)
			(best_width_ratio 0.9)
			(max_width 2)
			(curved_edges yes)
			(filter_ratio 0.9)
			(enabled yes)
			(allow_two_segments yes)
			(prefer_zone_connections yes)
		)
		(net 62)
	)
	(via
		(at 311.35 142.76)
		(size 0.45)
		(drill 0.1)
		(layers "F.Cu" "B.Cu")
		(remove_unused_layers yes)
		(keep_end_layers yes)
		(zone_layer_connections "In3.Cu")
		(teardrops
			(best_length_ratio 0.4)
			(max_length 1)
			(best_width_ratio 0.9)
			(max_width 2)
			(curved_edges yes)
			(filter_ratio 0.9)
			(enabled yes)
			(allow_two_segments yes)
			(prefer_zone_connections yes)
		)
		(net 62)
	)
	(via
		(at 309.35 143.76)
		(size 0.45)
		(drill 0.1)
		(layers "F.Cu" "B.Cu")
		(remove_unused_layers yes)
		(keep_end_layers yes)
		(zone_layer_connections "In3.Cu")
		(teardrops
			(best_length_ratio 0.4)
			(max_length 1)
			(best_width_ratio 0.9)
			(max_width 2)
			(curved_edges yes)
			(filter_ratio 0.9)
			(enabled yes)
			(allow_two_segments yes)
			(prefer_zone_connections yes)
		)
		(net 62)
	)
	(via
		(at 316.9 123.86)
		(size 0.45)
		(drill 0.1)
		(layers "F.Cu" "B.Cu")
		(remove_unused_layers yes)
		(keep_end_layers yes)
		(free yes)
		(zone_layer_connections "In3.Cu")
		(teardrops
			(best_length_ratio 0.4)
			(max_length 1)
			(best_width_ratio 0.9)
			(max_width 2)
			(curved_edges yes)
			(filter_ratio 0.9)
			(enabled yes)
			(allow_two_segments yes)
			(prefer_zone_connections yes)
		)
		(net 62)
	)
	(via
		(at 312.35 140.76)
		(size 0.45)
		(drill 0.1)
		(layers "F.Cu" "B.Cu")
		(remove_unused_layers yes)
		(keep_end_layers yes)
		(zone_layer_connections "In3.Cu")
		(teardrops
			(best_length_ratio 0.4)
			(max_length 1)
			(best_width_ratio 0.9)
			(max_width 2)
			(curved_edges yes)
			(filter_ratio 0.9)
			(enabled yes)
			(allow_two_segments yes)
			(prefer_zone_connections yes)
		)
		(net 62)
	)
	(via
		(at 317.9 124.86)
		(size 0.45)
		(drill 0.1)
		(layers "F.Cu" "B.Cu")
		(remove_unused_layers yes)
		(keep_end_layers yes)
		(free yes)
		(zone_layer_connections "In3.Cu")
		(teardrops
			(best_length_ratio 0.4)
			(max_length 1)
			(best_width_ratio 0.9)
			(max_width 2)
			(curved_edges yes)
			(filter_ratio 0.9)
			(enabled yes)
			(allow_two_segments yes)
			(prefer_zone_connections yes)
		)
		(net 62)
	)
	(via
		(at 311.35 143.76)
		(size 0.45)
		(drill 0.1)
		(layers "F.Cu" "B.Cu")
		(remove_unused_layers yes)
		(keep_end_layers yes)
		(zone_layer_connections "In3.Cu")
		(teardrops
			(best_length_ratio 0.4)
			(max_length 1)
			(best_width_ratio 0.9)
			(max_width 2)
			(curved_edges yes)
			(filter_ratio 0.9)
			(enabled yes)
			(allow_two_segments yes)
			(prefer_zone_connections yes)
		)
		(net 62)
	)
	(via
		(at 315.9 123.86)
		(size 0.45)
		(drill 0.1)
		(layers "F.Cu" "B.Cu")
		(remove_unused_layers yes)
		(keep_end_layers yes)
		(free yes)
		(zone_layer_connections "In3.Cu")
		(teardrops
			(best_length_ratio 0.4)
			(max_length 1)
			(best_width_ratio 0.9)
			(max_width 2)
			(curved_edges yes)
			(filter_ratio 0.9)
			(enabled yes)
			(allow_two_segments yes)
			(prefer_zone_connections yes)
		)
		(net 62)
	)
	(via
		(at 309.35 139.76)
		(size 0.45)
		(drill 0.1)
		(layers "F.Cu" "B.Cu")
		(remove_unused_layers yes)
		(keep_end_layers yes)
		(zone_layer_connections "In3.Cu")
		(teardrops
			(best_length_ratio 0.4)
			(max_length 1)
			(best_width_ratio 0.9)
			(max_width 2)
			(curved_edges yes)
			(filter_ratio 0.9)
			(enabled yes)
			(allow_two_segments yes)
			(prefer_zone_connections yes)
		)
		(net 62)
	)
	(via
		(at 316.4895 132.71)
		(size 0.45)
		(drill 0.1)
		(layers "F.Cu" "B.Cu")
		(remove_unused_layers yes)
		(keep_end_layers yes)
		(zone_layer_connections "In3.Cu")
		(teardrops
			(best_length_ratio 0.4)
			(max_length 1)
			(best_width_ratio 0.9)
			(max_width 2)
			(curved_edges yes)
			(filter_ratio 0.9)
			(enabled yes)
			(allow_two_segments yes)
			(prefer_zone_connections yes)
		)
		(net 62)
	)
	(via
		(at 315.899999 125.86)
		(size 0.45)
		(drill 0.1)
		(layers "F.Cu" "B.Cu")
		(remove_unused_layers yes)
		(keep_end_layers yes)
		(free yes)
		(zone_layer_connections "In3.Cu")
		(teardrops
			(best_length_ratio 0.4)
			(max_length 1)
			(best_width_ratio 0.9)
			(max_width 2)
			(curved_edges yes)
			(filter_ratio 0.9)
			(enabled yes)
			(allow_two_segments yes)
			(prefer_zone_connections yes)
		)
		(net 62)
	)
	(via
		(at 316.464501 93.6365)
		(size 0.45)
		(drill 0.1)
		(layers "F.Cu" "B.Cu")
		(remove_unused_layers yes)
		(keep_end_layers yes)
		(zone_layer_connections "In3.Cu")
		(teardrops
			(best_length_ratio 0.4)
			(max_length 1)
			(best_width_ratio 0.9)
			(max_width 2)
			(curved_edges yes)
			(filter_ratio 0.9)
			(enabled yes)
			(allow_two_segments yes)
			(prefer_zone_connections yes)
		)
		(net 62)
	)
	(segment
		(start 312.142163 69.102163)
		(end 199.18361 69.102163)
		(width 0.2)
		(layer "In5.Cu")
		(net 62)
	)
	(segment
		(start 199.18361 69.102163)
		(end 198.73361 69.552163)
		(width 0.2)
		(layer "In5.Cu")
		(net 62)
	)
	(segment
		(start 186.70861 73.16139)
		(end 190.317837 69.552163)
		(width 0.2)
		(layer "In5.Cu")
		(net 62)
	)
	(segment
		(start 190.317837 69.552163)
		(end 198.73361 69.552163)
		(width 0.2)
		(layer "In5.Cu")
		(net 62)
	)
	(segment
		(start 186.70861 74.102163)
		(end 186.70861 73.16139)
		(width 0.2)
		(layer "In5.Cu")
		(net 62)
	)
	(segment
		(start 314.464501 71.424501)
		(end 312.142163 69.102163)
		(width 0.2)
		(layer "In5.Cu")
		(net 62)
	)
	(segment
		(start 314.464501 93.6365)
		(end 314.464501 71.424501)
		(width 0.2)
		(layer "In5.Cu")
		(net 62)
	)
	(segment
		(start 311.264999 122.46)
		(end 311.264999 121.959999)
		(width 0.125)
		(layer "F.Cu")
		(net 63)
	)
	(via
		(at 311.264999 122.46)
		(size 0.45)
		(drill 0.1)
		(layers "F.Cu" "B.Cu")
		(remove_unused_layers yes)
		(keep_end_layers yes)
		(zone_layer_connections)
		(teardrops
			(best_length_ratio 0.4)
			(max_length 1)
			(best_width_ratio 0.9)
			(max_width 2)
			(curved_edges yes)
			(filter_ratio 0.9)
			(enabled yes)
			(allow_two_segments yes)
			(prefer_zone_connections yes)
		)
		(net 63)
	)
	(segment
		(start 309.824999 122.44)
		(end 311.274999 122.44)
		(width 0.125)
		(layer "B.Cu")
		(net 63)
	)
	(segment
		(start 311.264999 106.65)
		(end 311.264999 106.149999)
		(width 0.125)
		(layer "F.Cu")
		(net 64)
	)
	(via
		(at 311.264999 106.65)
		(size 0.45)
		(drill 0.1)
		(layers "F.Cu" "B.Cu")
		(remove_unused_layers yes)
		(keep_end_layers yes)
		(zone_layer_connections)
		(teardrops
			(best_length_ratio 0.4)
			(max_length 1)
			(best_width_ratio 0.9)
			(max_width 2)
			(curved_edges yes)
			(filter_ratio 0.9)
			(enabled yes)
			(allow_two_segments yes)
			(prefer_zone_connections yes)
		)
		(net 64)
	)
	(segment
		(start 309.824999 106.63)
		(end 311.274999 106.63)
		(width 0.125)
		(layer "B.Cu")
		(net 64)
	)
	(segment
		(start 313.024999 106.63)
		(end 311.274999 106.63)
		(width 0.125)
		(layer "B.Cu")
		(net 64)
	)
	(segment
		(start 228.525 168.685)
		(end 228.525 163.135)
		(width 0.3)
		(layer "F.Cu")
		(net 65)
	)
	(segment
		(start 228.525 156.685)
		(end 228.525 163.135)
		(width 0.3)
		(layer "F.Cu")
		(net 65)
	)
	(segment
		(start 193.70861 74.102163)
		(end 193.70861 72.802163)
		(width 0.2)
		(layer "F.Cu")
		(net 65)
	)
	(segment
		(start 230.025 156.685)
		(end 230.025 151.135)
		(width 0.3)
		(layer "F.Cu")
		(net 65)
	)
	(segment
		(start 229.025 163.135)
		(end 229.025 156.685)
		(width 0.3)
		(layer "F.Cu")
		(net 65)
	)
	(segment
		(start 228.025 163.135)
		(end 228.025 168.685)
		(width 0.3)
		(layer "F.Cu")
		(net 65)
	)
	(segment
		(start 228.025 163.135)
		(end 228.025 156.685)
		(width 0.3)
		(layer "F.Cu")
		(net 65)
	)
	(segment
		(start 230.025 163.135)
		(end 230.025 168.685)
		(width 0.3)
		(layer "F.Cu")
		(net 65)
	)
	(segment
		(start 229.025 156.685)
		(end 229.025 151.135)
		(width 0.3)
		(layer "F.Cu")
		(net 65)
	)
	(segment
		(start 227.525 151.135)
		(end 227.525 156.685)
		(width 0.3)
		(layer "F.Cu")
		(net 65)
	)
	(segment
		(start 227.525 168.685)
		(end 227.525 163.135)
		(width 0.3)
		(layer "F.Cu")
		(net 65)
	)
	(segment
		(start 229.525 151.135)
		(end 229.525 156.685)
		(width 0.3)
		(layer "F.Cu")
		(net 65)
	)
	(segment
		(start 229.525 156.685)
		(end 229.525 163.135)
		(width 0.3)
		(layer "F.Cu")
		(net 65)
	)
	(segment
		(start 227.525 156.685)
		(end 227.525 163.135)
		(width 0.3)
		(layer "F.Cu")
		(net 65)
	)
	(segment
		(start 230.025 156.685)
		(end 230.025 163.135)
		(width 0.3)
		(layer "F.Cu")
		(net 65)
	)
	(segment
		(start 229.525 168.685)
		(end 229.525 163.135)
		(width 0.3)
		(layer "F.Cu")
		(net 65)
	)
	(segment
		(start 229.025 163.135)
		(end 229.025 168.685)
		(width 0.3)
		(layer "F.Cu")
		(net 65)
	)
	(segment
		(start 228.525 151.135)
		(end 228.525 156.685)
		(width 0.3)
		(layer "F.Cu")
		(net 65)
	)
	(segment
		(start 228.025 156.685)
		(end 228.025 151.135)
		(width 0.3)
		(layer "F.Cu")
		(net 65)
	)
	(via
		(at 302.05 142.785)
		(size 0.45)
		(drill 0.1)
		(layers "F.Cu" "B.Cu")
		(remove_unused_layers yes)
		(keep_end_layers yes)
		(free yes)
		(zone_layer_connections "In3.Cu")
		(teardrops
			(best_length_ratio 0.4)
			(max_length 1)
			(best_width_ratio 0.9)
			(max_width 2)
			(curved_edges yes)
			(filter_ratio 0.9)
			(enabled yes)
			(allow_two_segments yes)
			(prefer_zone_connections yes)
		)
		(net 65)
	)
	(via
		(at 305.05 140.785)
		(size 0.45)
		(drill 0.1)
		(layers "F.Cu" "B.Cu")
		(remove_unused_layers yes)
		(keep_end_layers yes)
		(free yes)
		(zone_layer_connections "In3.Cu")
		(teardrops
			(best_length_ratio 0.4)
			(max_length 1)
			(best_width_ratio 0.9)
			(max_width 2)
			(curved_edges yes)
			(filter_ratio 0.9)
			(enabled yes)
			(allow_two_segments yes)
			(prefer_zone_connections yes)
		)
		(net 65)
	)
	(via
		(at 304.05 141.785)
		(size 0.45)
		(drill 0.1)
		(layers "F.Cu" "B.Cu")
		(remove_unused_layers yes)
		(keep_end_layers yes)
		(free yes)
		(zone_layer_connections "In3.Cu")
		(teardrops
			(best_length_ratio 0.4)
			(max_length 1)
			(best_width_ratio 0.9)
			(max_width 2)
			(curved_edges yes)
			(filter_ratio 0.9)
			(enabled yes)
			(allow_two_segments yes)
			(prefer_zone_connections yes)
		)
		(net 65)
	)
	(via
		(at 301.05 143.785)
		(size 0.45)
		(drill 0.1)
		(layers "F.Cu" "B.Cu")
		(remove_unused_layers yes)
		(keep_end_layers yes)
		(free yes)
		(zone_layer_connections "In3.Cu")
		(teardrops
			(best_length_ratio 0.4)
			(max_length 1)
			(best_width_ratio 0.9)
			(max_width 2)
			(curved_edges yes)
			(filter_ratio 0.9)
			(enabled yes)
			(allow_two_segments yes)
			(prefer_zone_connections yes)
		)
		(net 65)
	)
	(via
		(at 237.5 158.8)
		(size 0.45)
		(drill 0.1)
		(layers "F.Cu" "B.Cu")
		(free yes)
		(teardrops
			(best_length_ratio 0.4)
			(max_length 1)
			(best_width_ratio 0.9)
			(max_width 2)
			(curved_edges yes)
			(filter_ratio 0.9)
			(enabled yes)
			(allow_two_segments yes)
			(prefer_zone_connections yes)
		)
		(net 65)
	)
	(via
		(at 302.05 140.785)
		(size 0.45)
		(drill 0.1)
		(layers "F.Cu" "B.Cu")
		(remove_unused_layers yes)
		(keep_end_layers yes)
		(free yes)
		(zone_layer_connections "In3.Cu")
		(teardrops
			(best_length_ratio 0.4)
			(max_length 1)
			(best_width_ratio 0.9)
			(max_width 2)
			(curved_edges yes)
			(filter_ratio 0.9)
			(enabled yes)
			(allow_two_segments yes)
			(prefer_zone_connections yes)
		)
		(net 65)
	)
	(via
		(at 239 160.3)
		(size 0.45)
		(drill 0.1)
		(layers "F.Cu" "B.Cu")
		(free yes)
		(teardrops
			(best_length_ratio 0.4)
			(max_length 1)
			(best_width_ratio 0.9)
			(max_width 2)
			(curved_edges yes)
			(filter_ratio 0.9)
			(enabled yes)
			(allow_two_segments yes)
			(prefer_zone_connections yes)
		)
		(net 65)
	)
	(via
		(at 238.5 159.8)
		(size 0.45)
		(drill 0.1)
		(layers "F.Cu" "B.Cu")
		(free yes)
		(teardrops
			(best_length_ratio 0.4)
			(max_length 1)
			(best_width_ratio 0.9)
			(max_width 2)
			(curved_edges yes)
			(filter_ratio 0.9)
			(enabled yes)
			(allow_two_segments yes)
			(prefer_zone_connections yes)
		)
		(net 65)
	)
	(via
		(at 300.05 140.785)
		(size 0.45)
		(drill 0.1)
		(layers "F.Cu" "B.Cu")
		(remove_unused_layers yes)
		(keep_end_layers yes)
		(free yes)
		(zone_layer_connections "In3.Cu")
		(teardrops
			(best_length_ratio 0.4)
			(max_length 1)
			(best_width_ratio 0.9)
			(max_width 2)
			(curved_edges yes)
			(filter_ratio 0.9)
			(enabled yes)
			(allow_two_segments yes)
			(prefer_zone_connections yes)
		)
		(net 65)
	)
	(via
		(at 302.05 143.785)
		(size 0.45)
		(drill 0.1)
		(layers "F.Cu" "B.Cu")
		(remove_unused_layers yes)
		(keep_end_layers yes)
		(free yes)
		(zone_layer_connections "In3.Cu")
		(teardrops
			(best_length_ratio 0.4)
			(max_length 1)
			(best_width_ratio 0.9)
			(max_width 2)
			(curved_edges yes)
			(filter_ratio 0.9)
			(enabled yes)
			(allow_two_segments yes)
			(prefer_zone_connections yes)
		)
		(net 65)
	)
	(via
		(at 301.05 140.785)
		(size 0.45)
		(drill 0.1)
		(layers "F.Cu" "B.Cu")
		(remove_unused_layers yes)
		(keep_end_layers yes)
		(free yes)
		(zone_layer_connections "In3.Cu")
		(teardrops
			(best_length_ratio 0.4)
			(max_length 1)
			(best_width_ratio 0.9)
			(max_width 2)
			(curved_edges yes)
			(filter_ratio 0.9)
			(enabled yes)
			(allow_two_segments yes)
			(prefer_zone_connections yes)
		)
		(net 65)
	)
	(via
		(at 303.05 143.785)
		(size 0.45)
		(drill 0.1)
		(layers "F.Cu" "B.Cu")
		(remove_unused_layers yes)
		(keep_end_layers yes)
		(free yes)
		(zone_layer_connections "In3.Cu")
		(teardrops
			(best_length_ratio 0.4)
			(max_length 1)
			(best_width_ratio 0.9)
			(max_width 2)
			(curved_edges yes)
			(filter_ratio 0.9)
			(enabled yes)
			(allow_two_segments yes)
			(prefer_zone_connections yes)
		)
		(net 65)
	)
	(via
		(at 305.05 143.785)
		(size 0.45)
		(drill 0.1)
		(layers "F.Cu" "B.Cu")
		(remove_unused_layers yes)
		(keep_end_layers yes)
		(free yes)
		(zone_layer_connections "In3.Cu")
		(teardrops
			(best_length_ratio 0.4)
			(max_length 1)
			(best_width_ratio 0.9)
			(max_width 2)
			(curved_edges yes)
			(filter_ratio 0.9)
			(enabled yes)
			(allow_two_segments yes)
			(prefer_zone_connections yes)
		)
		(net 65)
	)
	(via
		(at 300.05 143.785)
		(size 0.45)
		(drill 0.1)
		(layers "F.Cu" "B.Cu")
		(remove_unused_layers yes)
		(keep_end_layers yes)
		(free yes)
		(zone_layer_connections "In3.Cu")
		(teardrops
			(best_length_ratio 0.4)
			(max_length 1)
			(best_width_ratio 0.9)
			(max_width 2)
			(curved_edges yes)
			(filter_ratio 0.9)
			(enabled yes)
			(allow_two_segments yes)
			(prefer_zone_connections yes)
		)
		(net 65)
	)
	(via
		(at 303.049999 140.785)
		(size 0.45)
		(drill 0.1)
		(layers "F.Cu" "B.Cu")
		(remove_unused_layers yes)
		(keep_end_layers yes)
		(free yes)
		(zone_layer_connections "In3.Cu")
		(teardrops
			(best_length_ratio 0.4)
			(max_length 1)
			(best_width_ratio 0.9)
			(max_width 2)
			(curved_edges yes)
			(filter_ratio 0.9)
			(enabled yes)
			(allow_two_segments yes)
			(prefer_zone_connections yes)
		)
		(net 65)
	)
	(via
		(at 287.47 101.86)
		(size 0.45)
		(drill 0.1)
		(layers "F.Cu" "B.Cu")
		(remove_unused_layers yes)
		(keep_end_layers yes)
		(zone_layer_connections)
		(teardrops
			(best_length_ratio 0.4)
			(max_length 1)
			(best_width_ratio 0.9)
			(max_width 2)
			(curved_edges yes)
			(filter_ratio 0.9)
			(enabled yes)
			(allow_two_segments yes)
			(prefer_zone_connections yes)
		)
		(net 65)
	)
	(via
		(at 301.05 141.785)
		(size 0.45)
		(drill 0.1)
		(layers "F.Cu" "B.Cu")
		(remove_unused_layers yes)
		(keep_end_layers yes)
		(free yes)
		(zone_layer_connections "In3.Cu")
		(teardrops
			(best_length_ratio 0.4)
			(max_length 1)
			(best_width_ratio 0.9)
			(max_width 2)
			(curved_edges yes)
			(filter_ratio 0.9)
			(enabled yes)
			(allow_two_segments yes)
			(prefer_zone_connections yes)
		)
		(net 65)
	)
	(via
		(at 301.049999 142.785)
		(size 0.45)
		(drill 0.1)
		(layers "F.Cu" "B.Cu")
		(remove_unused_layers yes)
		(keep_end_layers yes)
		(free yes)
		(zone_layer_connections "In3.Cu")
		(teardrops
			(best_length_ratio 0.4)
			(max_length 1)
			(best_width_ratio 0.9)
			(max_width 2)
			(curved_edges yes)
			(filter_ratio 0.9)
			(enabled yes)
			(allow_two_segments yes)
			(prefer_zone_connections yes)
		)
		(net 65)
	)
	(via
		(at 239 159.3)
		(size 0.45)
		(drill 0.1)
		(layers "F.Cu" "B.Cu")
		(free yes)
		(teardrops
			(best_length_ratio 0.4)
			(max_length 1)
			(best_width_ratio 0.9)
			(max_width 2)
			(curved_edges yes)
			(filter_ratio 0.9)
			(enabled yes)
			(allow_two_segments yes)
			(prefer_zone_connections yes)
		)
		(net 65)
	)
	(via
		(at 305.05 142.785001)
		(size 0.45)
		(drill 0.1)
		(layers "F.Cu" "B.Cu")
		(remove_unused_layers yes)
		(keep_end_layers yes)
		(free yes)
		(zone_layer_connections "In3.Cu")
		(teardrops
			(best_length_ratio 0.4)
			(max_length 1)
			(best_width_ratio 0.9)
			(max_width 2)
			(curved_edges yes)
			(filter_ratio 0.9)
			(enabled yes)
			(allow_two_segments yes)
			(prefer_zone_connections yes)
		)
		(net 65)
	)
	(via
		(at 252.185001 87.449999)
		(size 0.45)
		(drill 0.1)
		(layers "F.Cu" "B.Cu")
		(remove_unused_layers yes)
		(keep_end_layers yes)
		(zone_layer_connections "In5.Cu")
		(teardrops
			(best_length_ratio 0.4)
			(max_length 1)
			(best_width_ratio 0.9)
			(max_width 2)
			(curved_edges yes)
			(filter_ratio 0.9)
			(enabled yes)
			(allow_two_segments yes)
			(prefer_zone_connections yes)
		)
		(net 65)
	)
	(via
		(at 304.05 143.785)
		(size 0.45)
		(drill 0.1)
		(layers "F.Cu" "B.Cu")
		(remove_unused_layers yes)
		(keep_end_layers yes)
		(free yes)
		(zone_layer_connections "In3.Cu")
		(teardrops
			(best_length_ratio 0.4)
			(max_length 1)
			(best_width_ratio 0.9)
			(max_width 2)
			(curved_edges yes)
			(filter_ratio 0.9)
			(enabled yes)
			(allow_two_segments yes)
			(prefer_zone_connections yes)
		)
		(net 65)
	)
	(via
		(at 239.5 159.8)
		(size 0.45)
		(drill 0.1)
		(layers "F.Cu" "B.Cu")
		(free yes)
		(teardrops
			(best_length_ratio 0.4)
			(max_length 1)
			(best_width_ratio 0.9)
			(max_width 2)
			(curved_edges yes)
			(filter_ratio 0.9)
			(enabled yes)
			(allow_two_segments yes)
			(prefer_zone_connections yes)
		)
		(net 65)
	)
	(via
		(at 303.05 141.785)
		(size 0.45)
		(drill 0.1)
		(layers "F.Cu" "B.Cu")
		(remove_unused_layers yes)
		(keep_end_layers yes)
		(free yes)
		(zone_layer_connections "In3.Cu")
		(teardrops
			(best_length_ratio 0.4)
			(max_length 1)
			(best_width_ratio 0.9)
			(max_width 2)
			(curved_edges yes)
			(filter_ratio 0.9)
			(enabled yes)
			(allow_two_segments yes)
			(prefer_zone_connections yes)
		)
		(net 65)
	)
	(via
		(at 237.5 160.8)
		(size 0.45)
		(drill 0.1)
		(layers "F.Cu" "B.Cu")
		(free yes)
		(teardrops
			(best_length_ratio 0.4)
			(max_length 1)
			(best_width_ratio 0.9)
			(max_width 2)
			(curved_edges yes)
			(filter_ratio 0.9)
			(enabled yes)
			(allow_two_segments yes)
			(prefer_zone_connections yes)
		)
		(net 65)
	)
	(via
		(at 239.5 160.8)
		(size 0.45)
		(drill 0.1)
		(layers "F.Cu" "B.Cu")
		(free yes)
		(teardrops
			(best_length_ratio 0.4)
			(max_length 1)
			(best_width_ratio 0.9)
			(max_width 2)
			(curved_edges yes)
			(filter_ratio 0.9)
			(enabled yes)
			(allow_two_segments yes)
			(prefer_zone_connections yes)
		)
		(net 65)
	)
	(via
		(at 193.70861 74.102163)
		(size 0.45)
		(drill 0.1)
		(layers "F.Cu" "B.Cu")
		(remove_unused_layers yes)
		(keep_end_layers yes)
		(zone_layer_connections "In5.Cu")
		(teardrops
			(best_length_ratio 0.4)
			(max_length 1)
			(best_width_ratio 0.9)
			(max_width 2)
			(curved_edges yes)
			(filter_ratio 0.9)
			(enabled yes)
			(allow_two_segments yes)
			(prefer_zone_connections yes)
		)
		(net 65)
	)
	(via
		(at 282.4 86.01)
		(size 0.45)
		(drill 0.1)
		(layers "F.Cu" "B.Cu")
		(remove_unused_layers yes)
		(keep_end_layers yes)
		(zone_layer_connections "In5.Cu")
		(teardrops
			(best_length_ratio 0.4)
			(max_length 1)
			(best_width_ratio 0.9)
			(max_width 2)
			(curved_edges yes)
			(filter_ratio 0.9)
			(enabled yes)
			(allow_two_segments yes)
			(prefer_zone_connections yes)
		)
		(net 65)
	)
	(via
		(at 238 159.3)
		(size 0.45)
		(drill 0.1)
		(layers "F.Cu" "B.Cu")
		(free yes)
		(teardrops
			(best_length_ratio 0.4)
			(max_length 1)
			(best_width_ratio 0.9)
			(max_width 2)
			(curved_edges yes)
			(filter_ratio 0.9)
			(enabled yes)
			(allow_two_segments yes)
			(prefer_zone_connections yes)
		)
		(net 65)
	)
	(via
		(at 300.050001 142.785)
		(size 0.45)
		(drill 0.1)
		(layers "F.Cu" "B.Cu")
		(remove_unused_layers yes)
		(keep_end_layers yes)
		(free yes)
		(zone_layer_connections "In3.Cu")
		(teardrops
			(best_length_ratio 0.4)
			(max_length 1)
			(best_width_ratio 0.9)
			(max_width 2)
			(curved_edges yes)
			(filter_ratio 0.9)
			(enabled yes)
			(allow_two_segments yes)
			(prefer_zone_connections yes)
		)
		(net 65)
	)
	(via
		(at 303.05 142.785)
		(size 0.45)
		(drill 0.1)
		(layers "F.Cu" "B.Cu")
		(remove_unused_layers yes)
		(keep_end_layers yes)
		(free yes)
		(zone_layer_connections "In3.Cu")
		(teardrops
			(best_length_ratio 0.4)
			(max_length 1)
			(best_width_ratio 0.9)
			(max_width 2)
			(curved_edges yes)
			(filter_ratio 0.9)
			(enabled yes)
			(allow_two_segments yes)
			(prefer_zone_connections yes)
		)
		(net 65)
	)
	(via
		(at 302.05 141.785)
		(size 0.45)
		(drill 0.1)
		(layers "F.Cu" "B.Cu")
		(remove_unused_layers yes)
		(keep_end_layers yes)
		(free yes)
		(zone_layer_connections "In3.Cu")
		(teardrops
			(best_length_ratio 0.4)
			(max_length 1)
			(best_width_ratio 0.9)
			(max_width 2)
			(curved_edges yes)
			(filter_ratio 0.9)
			(enabled yes)
			(allow_two_segments yes)
			(prefer_zone_connections yes)
		)
		(net 65)
	)
	(via
		(at 238.5 158.8)
		(size 0.45)
		(drill 0.1)
		(layers "F.Cu" "B.Cu")
		(free yes)
		(teardrops
			(best_length_ratio 0.4)
			(max_length 1)
			(best_width_ratio 0.9)
			(max_width 2)
			(curved_edges yes)
			(filter_ratio 0.9)
			(enabled yes)
			(allow_two_segments yes)
			(prefer_zone_connections yes)
		)
		(net 65)
	)
	(via
		(at 239.5 158.8)
		(size 0.45)
		(drill 0.1)
		(layers "F.Cu" "B.Cu")
		(free yes)
		(teardrops
			(best_length_ratio 0.4)
			(max_length 1)
			(best_width_ratio 0.9)
			(max_width 2)
			(curved_edges yes)
			(filter_ratio 0.9)
			(enabled yes)
			(allow_two_segments yes)
			(prefer_zone_connections yes)
		)
		(net 65)
	)
	(via
		(at 306.05 142.785001)
		(size 0.45)
		(drill 0.1)
		(layers "F.Cu" "B.Cu")
		(remove_unused_layers yes)
		(keep_end_layers yes)
		(free yes)
		(zone_layer_connections "In3.Cu")
		(teardrops
			(best_length_ratio 0.4)
			(max_length 1)
			(best_width_ratio 0.9)
			(max_width 2)
			(curved_edges yes)
			(filter_ratio 0.9)
			(enabled yes)
			(allow_two_segments yes)
			(prefer_zone_connections yes)
		)
		(net 65)
	)
	(via
		(at 305.05 141.785)
		(size 0.45)
		(drill 0.1)
		(layers "F.Cu" "B.Cu")
		(remove_unused_layers yes)
		(keep_end_layers yes)
		(free yes)
		(zone_layer_connections "In3.Cu")
		(teardrops
			(best_length_ratio 0.4)
			(max_length 1)
			(best_width_ratio 0.9)
			(max_width 2)
			(curved_edges yes)
			(filter_ratio 0.9)
			(enabled yes)
			(allow_two_segments yes)
			(prefer_zone_connections yes)
		)
		(net 65)
	)
	(via
		(at 238.5 160.8)
		(size 0.45)
		(drill 0.1)
		(layers "F.Cu" "B.Cu")
		(free yes)
		(teardrops
			(best_length_ratio 0.4)
			(max_length 1)
			(best_width_ratio 0.9)
			(max_width 2)
			(curved_edges yes)
			(filter_ratio 0.9)
			(enabled yes)
			(allow_two_segments yes)
			(prefer_zone_connections yes)
		)
		(net 65)
	)
	(via
		(at 306.05 141.785)
		(size 0.45)
		(drill 0.1)
		(layers "F.Cu" "B.Cu")
		(remove_unused_layers yes)
		(keep_end_layers yes)
		(free yes)
		(zone_layer_connections "In3.Cu")
		(teardrops
			(best_length_ratio 0.4)
			(max_length 1)
			(best_width_ratio 0.9)
			(max_width 2)
			(curved_edges yes)
			(filter_ratio 0.9)
			(enabled yes)
			(allow_two_segments yes)
			(prefer_zone_connections yes)
		)
		(net 65)
	)
	(via
		(at 304.05 142.785)
		(size 0.45)
		(drill 0.1)
		(layers "F.Cu" "B.Cu")
		(remove_unused_layers yes)
		(keep_end_layers yes)
		(free yes)
		(zone_layer_connections "In3.Cu")
		(teardrops
			(best_length_ratio 0.4)
			(max_length 1)
			(best_width_ratio 0.9)
			(max_width 2)
			(curved_edges yes)
			(filter_ratio 0.9)
			(enabled yes)
			(allow_two_segments yes)
			(prefer_zone_connections yes)
		)
		(net 65)
	)
	(via
		(at 300.05 141.785)
		(size 0.45)
		(drill 0.1)
		(layers "F.Cu" "B.Cu")
		(remove_unused_layers yes)
		(keep_end_layers yes)
		(free yes)
		(zone_layer_connections "In3.Cu")
		(teardrops
			(best_length_ratio 0.4)
			(max_length 1)
			(best_width_ratio 0.9)
			(max_width 2)
			(curved_edges yes)
			(filter_ratio 0.9)
			(enabled yes)
			(allow_two_segments yes)
			(prefer_zone_connections yes)
		)
		(net 65)
	)
	(via
		(at 304.05 140.785)
		(size 0.45)
		(drill 0.1)
		(layers "F.Cu" "B.Cu")
		(remove_unused_layers yes)
		(keep_end_layers yes)
		(free yes)
		(zone_layer_connections "In3.Cu")
		(teardrops
			(best_length_ratio 0.4)
			(max_length 1)
			(best_width_ratio 0.9)
			(max_width 2)
			(curved_edges yes)
			(filter_ratio 0.9)
			(enabled yes)
			(allow_two_segments yes)
			(prefer_zone_connections yes)
		)
		(net 65)
	)
	(via
		(at 237.5 159.8)
		(size 0.45)
		(drill 0.1)
		(layers "F.Cu" "B.Cu")
		(free yes)
		(teardrops
			(best_length_ratio 0.4)
			(max_length 1)
			(best_width_ratio 0.9)
			(max_width 2)
			(curved_edges yes)
			(filter_ratio 0.9)
			(enabled yes)
			(allow_two_segments yes)
			(prefer_zone_connections yes)
		)
		(net 65)
	)
	(via
		(at 238 160.3)
		(size 0.45)
		(drill 0.1)
		(layers "F.Cu" "B.Cu")
		(free yes)
		(teardrops
			(best_length_ratio 0.4)
			(max_length 1)
			(best_width_ratio 0.9)
			(max_width 2)
			(curved_edges yes)
			(filter_ratio 0.9)
			(enabled yes)
			(allow_two_segments yes)
			(prefer_zone_connections yes)
		)
		(net 65)
	)
	(segment
		(start 282.8 86.01)
		(end 287.47 90.68)
		(width 0.125)
		(layer "B.Cu")
		(net 65)
	)
	(segment
		(start 287.47 101.86)
		(end 287.47 128.205)
		(width 0.125)
		(layer "B.Cu")
		(net 65)
	)
	(segment
		(start 282.4 86.01)
		(end 282.8 86.01)
		(width 0.125)
		(layer "B.Cu")
		(net 65)
	)
	(segment
		(start 287.47 90.68)
		(end 287.47 101.86)
		(width 0.125)
		(layer "B.Cu")
		(net 65)
	)
	(segment
		(start 287.47 128.205)
		(end 300.05 140.785)
		(width 0.125)
		(layer "B.Cu")
		(net 65)
	)
	(segment
		(start 230.9 81.26)
		(end 245.995002 81.26)
		(width 0.2)
		(layer "In5.Cu")
		(net 65)
	)
	(segment
		(start 195.610773 72.2)
		(end 193.70861 74.102163)
		(width 0.2)
		(layer "In5.Cu")
		(net 65)
	)
	(segment
		(start 245.995002 81.26)
		(end 252.185001 87.449999)
		(width 0.2)
		(layer "In5.Cu")
		(net 65)
	)
	(segment
		(start 230.9 81.26)
		(end 221.84 72.2)
		(width 0.2)
		(layer "In5.Cu")
		(net 65)
	)
	(segment
		(start 221.84 72.2)
		(end 195.610773 72.2)
		(width 0.2)
		(layer "In5.Cu")
		(net 65)
	)
	(segment
		(start 252.185001 87.449999)
		(end 256.660001 87.449999)
		(width 0.2)
		(layer "In5.Cu")
		(net 65)
	)
	(segment
		(start 256.660001 87.449999)
		(end 259.01 85.1)
		(width 0.2)
		(layer "In5.Cu")
		(net 65)
	)
	(segment
		(start 282.227158 85.837158)
		(end 282.4 86.01)
		(width 0.2)
		(layer "In5.Cu")
		(net 65)
	)
	(segment
		(start 261.787158 85.837158)
		(end 282.227158 85.837158)
		(width 0.2)
		(layer "In5.Cu")
		(net 65)
	)
	(segment
		(start 261.05 85.1)
		(end 261.787158 85.837158)
		(width 0.2)
		(layer "In5.Cu")
		(net 65)
	)
	(segment
		(start 259.01 85.1)
		(end 261.05 85.1)
		(width 0.2)
		(layer "In5.Cu")
		(net 65)
	)
	(segment
		(start 313.115999 121.461999)
		(end 314.113 121.461999)
		(width 0.125)
		(layer "F.Cu")
		(net 66)
	)
	(segment
		(start 312.169999 121.958999)
		(end 312.169999 122.369999)
		(width 0.2)
		(layer "F.Cu")
		(net 67)
	)
	(segment
		(start 312.619999 121.958999)
		(end 312.619999 122.369999)
		(width 0.2)
		(layer "F.Cu")
		(net 67)
	)
	(segment
		(start 312.524999 121.66)
		(end 312.524999 119.608057)
		(width 0.125)
		(layer "F.Cu")
		(net 67)
	)
	(segment
		(start 312.617999 121.753)
		(end 312.524999 121.66)
		(width 0.125)
		(layer "F.Cu")
		(net 67)
	)
	(segment
		(start 312.524999 119.608057)
		(end 312.617999 119.515057)
		(width 0.125)
		(layer "F.Cu")
		(net 67)
	)
	(segment
		(start 312.617999 119.515057)
		(end 312.617999 119.160999)
		(width 0.125)
		(layer "F.Cu")
		(net 67)
	)
	(segment
		(start 313.115999 105.651999)
		(end 314.113 105.651999)
		(width 0.125)
		(layer "F.Cu")
		(net 68)
	)
	(segment
		(start 312.524999 105.85)
		(end 312.524999 103.798057)
		(width 0.125)
		(layer "F.Cu")
		(net 69)
	)
	(segment
		(start 312.617999 103.705057)
		(end 312.617999 103.350999)
		(width 0.125)
		(layer "F.Cu")
		(net 69)
	)
	(segment
		(start 312.617999 105.943)
		(end 312.524999 105.85)
		(width 0.125)
		(layer "F.Cu")
		(net 69)
	)
	(segment
		(start 312.169999 106.148999)
		(end 312.169999 106.559999)
		(width 0.2)
		(layer "F.Cu")
		(net 69)
	)
	(segment
		(start 312.619999 106.148999)
		(end 312.619999 106.559999)
		(width 0.2)
		(layer "F.Cu")
		(net 69)
	)
	(segment
		(start 312.524999 103.798057)
		(end 312.617999 103.705057)
		(width 0.125)
		(layer "F.Cu")
		(net 69)
	)
	(segment
		(start 304.5 100.81)
		(end 304.5 103.71)
		(width 0.125)
		(layer "F.Cu")
		(net 71)
	)
	(segment
		(start 304.67 100.64)
		(end 304.5 100.81)
		(width 0.125)
		(layer "F.Cu")
		(net 71)
	)
	(segment
		(start 304.125 104.085)
		(end 304.125 104.809)
		(width 0.125)
		(layer "F.Cu")
		(net 71)
	)
	(segment
		(start 305.35 100.64)
		(end 304.67 100.64)
		(width 0.125)
		(layer "F.Cu")
		(net 71)
	)
	(segment
		(start 304.5 103.71)
		(end 304.125 104.085)
		(width 0.125)
		(layer "F.Cu")
		(net 71)
	)
	(segment
		(start 304.62 129.059)
		(end 304.62 127.79)
		(width 0.125)
		(layer "F.Cu")
		(net 72)
	)
	(segment
		(start 304.62 126.79)
		(end 304.62 127.79)
		(width 0.125)
		(layer "F.Cu")
		(net 72)
	)
	(segment
		(start 237.09 151.1)
		(end 302.32 151.1)
		(width 0.3)
		(layer "F.Cu")
		(net 73)
	)
	(segment
		(start 301.839 130.09)
		(end 300.65 130.09)
		(width 0.5)
		(layer "F.Cu")
		(net 73)
	)
	(segment
		(start 220.5475 80.61)
		(end 221.5 81.5625)
		(width 0.5)
		(layer "F.Cu")
		(net 73)
	)
	(segment
		(start 251.625 131.88)
		(end 251.255 131.51)
		(width 0.125)
		(layer "F.Cu")
		(net 73)
	)
	(segment
		(start 236.18 153.98)
		(end 236.7 153.98)
		(width 0.125)
		(layer "F.Cu")
		(net 73)
	)
	(segment
		(start 238.27 157.409999)
		(end 236.199999 157.409999)
		(width 0.125)
		(layer "F.Cu")
		(net 73)
	)
	(segment
		(start 303.477 106.762001)
		(end 303.477 107.41)
		(width 0.125)
		(layer "F.Cu")
		(net 73)
	)
	(segment
		(start 236 154.16)
		(end 236.18 153.98)
		(width 0.125)
		(layer "F.Cu")
		(net 73)
	)
	(segment
		(start 304.37 146.61)
		(end 304.527 146.767)
		(width 0.45)
		(layer "F.Cu")
		(net 73)
	)
	(segment
		(start 282.4 104.435)
		(end 291.375 104.435)
		(width 0.45)
		(layer "F.Cu")
		(net 73)
	)
	(segment
		(start 221.5 81.5625)
		(end 221.5 82.66)
		(width 0.5)
		(layer "F.Cu")
		(net 73)
	)
	(segment
		(start 302.177 105.462)
		(end 302.177 104.809)
		(width 0.125)
		(layer "F.Cu")
		(net 73)
	)
	(segment
		(start 238.749 157.290999)
		(end 238.63 157.409999)
		(width 0.125)
		(layer "F.Cu")
		(net 73)
	)
	(segment
		(start 250.467 132.887)
		(end 250.467 131.772)
		(width 0.3)
		(layer "F.Cu")
		(net 73)
	)
	(segment
		(start 190.70861 74.102163)
		(end 190.70861 72.802163)
		(width 0.2)
		(layer "F.Cu")
		(net 73)
	)
	(segment
		(start 302.32 151.1)
		(end 304.525 148.895)
		(width 0.3)
		(layer "F.Cu")
		(net 73)
	)
	(segment
		(start 236.7 153.98)
		(end 236.7 151.49)
		(width 0.3)
		(layer "F.Cu")
		(net 73)
	)
	(segment
		(start 251.255 131.51)
		(end 250.205 131.51)
		(width 0.125)
		(layer "F.Cu")
		(net 73)
	)
	(segment
		(start 302.177 103.767)
		(end 302.177 104.809)
		(width 0.45)
		(layer "F.Cu")
		(net 73)
	)
	(segment
		(start 238.4095 126.39)
		(end 238.4095 125.7405)
		(width 0.2)
		(layer "F.Cu")
		(net 73)
	)
	(segment
		(start 238.749001 156.861)
		(end 238.749 157.290999)
		(width 0.125)
		(layer "F.Cu")
		(net 73)
	)
	(segment
		(start 306.65 153.35)
		(end 307.41 153.35)
		(width 0.3)
		(layer "F.Cu")
		(net 73)
	)
	(segment
		(start 237.751 153.961999)
		(end 236.718 153.962)
		(width 0.2)
		(layer "F.Cu")
		(net 73)
	)
	(segment
		(start 304.527 146.767)
		(end 304.527 147.809)
		(width 0.45)
		(layer "F.Cu")
		(net 73)
	)
	(segment
		(start 238.4095 125.7405)
		(end 238.73 125.42)
		(width 0.2)
		(layer "F.Cu")
		(net 73)
	)
	(segment
		(start 298.15 103.94)
		(end 299.05 103.94)
		(width 0.45)
		(layer "F.Cu")
		(net 73)
	)
	(segment
		(start 238.27 157.409999)
		(end 238.25 157.389999)
		(width 0.125)
		(layer "F.Cu")
		(net 73)
	)
	(segment
		(start 243.87 125.42)
		(end 244.53 126.08)
		(width 0.2)
		(layer "F.Cu")
		(net 73)
	)
	(segment
		(start 245.025 127.205)
		(end 244.53 126.71)
		(width 0.3)
		(layer "F.Cu")
		(net 73)
	)
	(segment
		(start 236.199999 157.409999)
		(end 236 157.21)
		(width 0.125)
		(layer "F.Cu")
		(net 73)
	)
	(segment
		(start 237.29 152.95)
		(end 237.751 153.411)
		(width 0.125)
		(layer "F.Cu")
		(net 73)
	)
	(segment
		(start 291.375 104.435)
		(end 291.9 103.91)
		(width 0.45)
		(layer "F.Cu")
		(net 73)
	)
	(segment
		(start 307.41 153.35)
		(end 307.758 153.002)
		(width 0.3)
		(layer "F.Cu")
		(net 73)
	)
	(segment
		(start 222.4475 80.61)
		(end 221.5 81.5575)
		(width 0.5)
		(layer "F.Cu")
		(net 73)
	)
	(segment
		(start 247.76 131.88)
		(end 246.8 132.84)
		(width 0.125)
		(layer "F.Cu")
		(net 73)
	)
	(segment
		(start 303.477 106.762001)
		(end 302.177 105.462)
		(width 0.125)
		(layer "F.Cu")
		(net 73)
	)
	(segment
		(start 236 157.21)
		(end 236 154.16)
		(width 0.125)
		(layer "F.Cu")
		(net 73)
	)
	(segment
		(start 302.177 90.217)
		(end 302.177 91.259)
		(width 0.45)
		(layer "F.Cu")
		(net 73)
	)
	(segment
		(start 253.32825 127.171748)
		(end 254.462252 127.171748)
		(width 0.125)
		(layer "F.Cu")
		(net 73)
	)
	(segment
		(start 238.73 125.42)
		(end 243.87 125.42)
		(width 0.2)
		(layer "F.Cu")
		(net 73)
	)
	(segment
		(start 246.35 127.83)
		(end 245.154 127.83)
		(width 0.125)
		(layer "F.Cu")
		(net 73)
	)
	(segment
		(start 238.63 157.409999)
		(end 238.27 157.409999)
		(width 0.125)
		(layer "F.Cu")
		(net 73)
	)
	(segment
		(start 302.02 103.61)
		(end 302.177 103.767)
		(width 0.45)
		(layer "F.Cu")
		(net 73)
	)
	(segment
		(start 237.751 156.861)
		(end 237.751 157.408999)
		(width 0.125)
		(layer "F.Cu")
		(net 73)
	)
	(segment
		(start 238.25 157.389999)
		(end 238.25 156.861)
		(width 0.125)
		(layer "F.Cu")
		(net 73)
	)
	(segment
		(start 307.758 153.002)
		(end 307.758 152.433)
		(width 0.3)
		(layer "F.Cu")
		(net 73)
	)
	(segment
		(start 302.02 90.06)
		(end 302.177 90.217)
		(width 0.45)
		(layer "F.Cu")
		(net 73)
	)
	(segment
		(start 250.467 131.772)
		(end 250.205 131.51)
		(width 0.3)
		(layer "F.Cu")
		(net 73)
	)
	(segment
		(start 245.025 127.959)
		(end 245.025 127.205)
		(width 0.3)
		(layer "F.Cu")
		(net 73)
	)
	(segment
		(start 237.751 153.411)
		(end 237.751 153.962)
		(width 0.125)
		(layer "F.Cu")
		(net 73)
	)
	(segment
		(start 304.525 148.895)
		(end 304.525 147.81)
		(width 0.3)
		(layer "F.Cu")
		(net 73)
	)
	(segment
		(start 221.5 81.5575)
		(end 221.5 81.5625)
		(width 0.5)
		(layer "F.Cu")
		(net 73)
	)
	(segment
		(start 236.7 151.49)
		(end 237.09 151.1)
		(width 0.3)
		(layer "F.Cu")
		(net 73)
	)
	(segment
		(start 244.53 126.08)
		(end 244.53 126.71)
		(width 0.2)
		(layer "F.Cu")
		(net 73)
	)
	(via
		(at 300.64 130.08)
		(size 0.45)
		(drill 0.1)
		(layers "F.Cu" "B.Cu")
		(remove_unused_layers yes)
		(keep_end_layers yes)
		(zone_layer_connections)
		(teardrops
			(best_length_ratio 0.4)
			(max_length 1)
			(best_width_ratio 0.9)
			(max_width 2)
			(curved_edges yes)
			(filter_ratio 0.9)
			(enabled yes)
			(allow_two_segments yes)
			(prefer_zone_connections yes)
		)
		(net 73)
	)
	(via
		(at 302.02 90.06)
		(size 0.45)
		(drill 0.1)
		(layers "F.Cu" "B.Cu")
		(remove_unused_layers yes)
		(keep_end_layers yes)
		(zone_layer_connections)
		(teardrops
			(best_length_ratio 0.4)
			(max_length 1)
			(best_width_ratio 0.9)
			(max_width 2)
			(curved_edges yes)
			(filter_ratio 0.9)
			(enabled yes)
			(allow_two_segments yes)
			(prefer_zone_connections yes)
		)
		(net 73)
	)
	(via
		(at 291.9 103.91)
		(size 0.45)
		(drill 0.1)
		(layers "F.Cu" "B.Cu")
		(remove_unused_layers yes)
		(keep_end_layers yes)
		(zone_layer_connections)
		(teardrops
			(best_length_ratio 0.4)
			(max_length 1)
			(best_width_ratio 0.9)
			(max_width 2)
			(curved_edges yes)
			(filter_ratio 0.9)
			(enabled yes)
			(allow_two_segments yes)
			(prefer_zone_connections yes)
		)
		(net 73)
	)
	(via
		(at 255.975 131.88)
		(size 0.45)
		(drill 0.1)
		(layers "F.Cu" "B.Cu")
		(remove_unused_layers yes)
		(keep_end_layers yes)
		(zone_layer_connections "In3.Cu")
		(teardrops
			(best_length_ratio 0.4)
			(max_length 1)
			(best_width_ratio 0.9)
			(max_width 2)
			(curved_edges yes)
			(filter_ratio 0.9)
			(enabled yes)
			(allow_two_segments yes)
			(prefer_zone_connections yes)
		)
		(net 73)
	)
	(via
		(at 304.37 146.61)
		(size 0.45)
		(drill 0.1)
		(layers "F.Cu" "B.Cu")
		(remove_unused_layers yes)
		(keep_end_layers yes)
		(zone_layer_connections)
		(teardrops
			(best_length_ratio 0.4)
			(max_length 1)
			(best_width_ratio 0.9)
			(max_width 2)
			(curved_edges yes)
			(filter_ratio 0.9)
			(enabled yes)
			(allow_two_segments yes)
			(prefer_zone_connections yes)
		)
		(net 73)
	)
	(via
		(at 221.5 82.66)
		(size 0.45)
		(drill 0.1)
		(layers "F.Cu" "B.Cu")
		(remove_unused_layers yes)
		(keep_end_layers yes)
		(zone_layer_connections "In5.Cu")
		(teardrops
			(best_length_ratio 0.4)
			(max_length 1)
			(best_width_ratio 0.9)
			(max_width 2)
			(curved_edges yes)
			(filter_ratio 0.9)
			(enabled yes)
			(allow_two_segments yes)
			(prefer_zone_connections yes)
		)
		(net 73)
	)
	(via
		(at 282.4 104.435)
		(size 0.45)
		(drill 0.1)
		(layers "F.Cu" "B.Cu")
		(remove_unused_layers yes)
		(keep_end_layers yes)
		(zone_layer_connections)
		(teardrops
			(best_length_ratio 0.4)
			(max_length 1)
			(best_width_ratio 0.9)
			(max_width 2)
			(curved_edges yes)
			(filter_ratio 0.9)
			(enabled yes)
			(allow_two_segments yes)
			(prefer_zone_connections yes)
		)
		(net 73)
	)
	(via
		(at 250.205 131.51)
		(size 0.45)
		(drill 0.1)
		(layers "F.Cu" "B.Cu")
		(remove_unused_layers yes)
		(keep_end_layers yes)
		(zone_layer_connections "In3.Cu")
		(teardrops
			(best_length_ratio 0.4)
			(max_length 1)
			(best_width_ratio 0.9)
			(max_width 2)
			(curved_edges yes)
			(filter_ratio 0.9)
			(enabled yes)
			(allow_two_segments yes)
			(prefer_zone_connections yes)
		)
		(net 73)
	)
	(via
		(at 299.05 103.94)
		(size 0.45)
		(drill 0.1)
		(layers "F.Cu" "B.Cu")
		(remove_unused_layers yes)
		(keep_end_layers yes)
		(zone_layer_connections)
		(teardrops
			(best_length_ratio 0.4)
			(max_length 1)
			(best_width_ratio 0.9)
			(max_width 2)
			(curved_edges yes)
			(filter_ratio 0.9)
			(enabled yes)
			(allow_two_segments yes)
			(prefer_zone_connections yes)
		)
		(net 73)
	)
	(via
		(at 306.65 153.35)
		(size 0.45)
		(drill 0.1)
		(layers "F.Cu" "B.Cu")
		(remove_unused_layers yes)
		(keep_end_layers yes)
		(zone_layer_connections)
		(teardrops
			(best_length_ratio 0.4)
			(max_length 1)
			(best_width_ratio 0.9)
			(max_width 2)
			(curved_edges yes)
			(filter_ratio 0.9)
			(enabled yes)
			(allow_two_segments yes)
			(prefer_zone_connections yes)
		)
		(net 73)
	)
	(via
		(at 242.8 132.84)
		(size 0.45)
		(drill 0.1)
		(layers "F.Cu" "B.Cu")
		(remove_unused_layers yes)
		(keep_end_layers yes)
		(zone_layer_connections "In3.Cu")
		(teardrops
			(best_length_ratio 0.4)
			(max_length 1)
			(best_width_ratio 0.9)
			(max_width 2)
			(curved_edges yes)
			(filter_ratio 0.9)
			(enabled yes)
			(allow_two_segments yes)
			(prefer_zone_connections yes)
		)
		(net 73)
	)
	(via
		(at 253.32825 127.171748)
		(size 0.45)
		(drill 0.1)
		(layers "F.Cu" "B.Cu")
		(remove_unused_layers yes)
		(keep_end_layers yes)
		(zone_layer_connections "In3.Cu")
		(teardrops
			(best_length_ratio 0.4)
			(max_length 1)
			(best_width_ratio 0.9)
			(max_width 2)
			(curved_edges yes)
			(filter_ratio 0.9)
			(enabled yes)
			(allow_two_segments yes)
			(prefer_zone_connections yes)
		)
		(net 73)
	)
	(via
		(at 190.70861 74.102163)
		(size 0.45)
		(drill 0.1)
		(layers "F.Cu" "B.Cu")
		(remove_unused_layers yes)
		(keep_end_layers yes)
		(zone_layer_connections "In5.Cu")
		(teardrops
			(best_length_ratio 0.4)
			(max_length 1)
			(best_width_ratio 0.9)
			(max_width 2)
			(curved_edges yes)
			(filter_ratio 0.9)
			(enabled yes)
			(allow_two_segments yes)
			(prefer_zone_connections yes)
		)
		(net 73)
	)
	(via
		(at 246.8 132.84)
		(size 0.45)
		(drill 0.1)
		(layers "F.Cu" "B.Cu")
		(remove_unused_layers yes)
		(keep_end_layers yes)
		(zone_layer_connections "In3.Cu")
		(teardrops
			(best_length_ratio 0.4)
			(max_length 1)
			(best_width_ratio 0.9)
			(max_width 2)
			(curved_edges yes)
			(filter_ratio 0.9)
			(enabled yes)
			(allow_two_segments yes)
			(prefer_zone_connections yes)
		)
		(net 73)
	)
	(via
		(at 298.15 103.94)
		(size 0.45)
		(drill 0.1)
		(layers "F.Cu" "B.Cu")
		(remove_unused_layers yes)
		(keep_end_layers yes)
		(zone_layer_connections)
		(teardrops
			(best_length_ratio 0.4)
			(max_length 1)
			(best_width_ratio 0.9)
			(max_width 2)
			(curved_edges yes)
			(filter_ratio 0.9)
			(enabled yes)
			(allow_two_segments yes)
			(prefer_zone_connections yes)
		)
		(net 73)
	)
	(via
		(at 244.53 126.71)
		(size 0.45)
		(drill 0.1)
		(layers "F.Cu" "B.Cu")
		(remove_unused_layers yes)
		(keep_end_layers yes)
		(zone_layer_connections "In3.Cu")
		(teardrops
			(best_length_ratio 0.4)
			(max_length 1)
			(best_width_ratio 0.9)
			(max_width 2)
			(curved_edges yes)
			(filter_ratio 0.9)
			(enabled yes)
			(allow_two_segments yes)
			(prefer_zone_connections yes)
		)
		(net 73)
	)
	(via
		(at 302.02 103.61)
		(size 0.45)
		(drill 0.1)
		(layers "F.Cu" "B.Cu")
		(remove_unused_layers yes)
		(keep_end_layers yes)
		(zone_layer_connections)
		(teardrops
			(best_length_ratio 0.4)
			(max_length 1)
			(best_width_ratio 0.9)
			(max_width 2)
			(curved_edges yes)
			(filter_ratio 0.9)
			(enabled yes)
			(allow_two_segments yes)
			(prefer_zone_connections yes)
		)
		(net 73)
	)
	(segment
		(start 299.05 103.94)
		(end 301.69 103.94)
		(width 0.45)
		(layer "In2.Cu")
		(net 73)
	)
	(segment
		(start 301.69 103.94)
		(end 302.02 103.61)
		(width 0.45)
		(layer "In2.Cu")
		(net 73)
	)
	(segment
		(start 304.89 153.35)
		(end 306.65 153.35)
		(width 0.45)
		(layer "In2.Cu")
		(net 73)
	)
	(segment
		(start 307.1 134.51)
		(end 307.1 143.88)
		(width 0.45)
		(layer "In2.Cu")
		(net 73)
	)
	(segment
		(start 302.67 130.08)
		(end 307.1 134.51)
		(width 0.45)
		(layer "In2.Cu")
		(net 73)
	)
	(segment
		(start 271.125 104.435)
		(end 282.4 104.435)
		(width 0.45)
		(layer "In2.Cu")
		(net 73)
	)
	(segment
		(start 291.9 103.91)
		(end 291.93 103.94)
		(width 0.45)
		(layer "In2.Cu")
		(net 73)
	)
	(segment
		(start 221.5 82.66)
		(end 228.783075 89.943075)
		(width 0.45)
		(layer "In2.Cu")
		(net 73)
	)
	(segment
		(start 302.02 90.06)
		(end 302.02 91.94)
		(width 0.45)
		(layer "In2.Cu")
		(net 73)
	)
	(segment
		(start 303.5 151.96)
		(end 304.89 153.35)
		(width 0.45)
		(layer "In2.Cu")
		(net 73)
	)
	(segment
		(start 300.64 130.08)
		(end 302.67 130.08)
		(width 0.45)
		(layer "In2.Cu")
		(net 73)
	)
	(segment
		(start 299.05 103.94)
		(end 299.05 128.49)
		(width 0.45)
		(layer "In2.Cu")
		(net 73)
	)
	(segment
		(start 228.783075 89.943075)
		(end 256.633075 89.943075)
		(width 0.45)
		(layer "In2.Cu")
		(net 73)
	)
	(segment
		(start 299.05 103.76)
		(end 299.05 103.94)
		(width 0.45)
		(layer "In2.Cu")
		(net 73)
	)
	(segment
		(start 256.633075 89.943075)
		(end 271.125 104.435)
		(width 0.45)
		(layer "In2.Cu")
		(net 73)
	)
	(segment
		(start 307.1 143.88)
		(end 304.37 146.61)
		(width 0.45)
		(layer "In2.Cu")
		(net 73)
	)
	(segment
		(start 304.37 146.61)
		(end 303.5 147.48)
		(width 0.45)
		(layer "In2.Cu")
		(net 73)
	)
	(segment
		(start 302.02 91.94)
		(end 299.05 94.91)
		(width 0.45)
		(layer "In2.Cu")
		(net 73)
	)
	(segment
		(start 303.5 147.48)
		(end 303.5 151.96)
		(width 0.45)
		(layer "In2.Cu")
		(net 73)
	)
	(segment
		(start 299.05 94.91)
		(end 299.05 103.76)
		(width 0.45)
		(layer "In2.Cu")
		(net 73)
	)
	(segment
		(start 291.93 103.94)
		(end 299.05 103.94)
		(width 0.45)
		(layer "In2.Cu")
		(net 73)
	)
	(segment
		(start 299.05 128.49)
		(end 300.64 130.08)
		(width 0.45)
		(layer "In2.Cu")
		(net 73)
	)
	(segment
		(start 272.8 124.01)
		(end 264.65 132.16)
		(width 0.45)
		(layer "In3.Cu")
		(net 73)
	)
	(segment
		(start 288.6 124.01)
		(end 299.25 113.36)
		(width 0.45)
		(layer "In3.Cu")
		(net 73)
	)
	(segment
		(start 264.65 132.16)
		(end 260 132.16)
		(width 0.45)
		(layer "In3.Cu")
		(net 73)
	)
	(segment
		(start 302.02 104.03)
		(end 302.5 104.51)
		(width 0.45)
		(layer "In3.Cu")
		(net 73)
	)
	(segment
		(start 302.85 113.36)
		(end 299.25 113.36)
		(width 0.45)
		(layer "In3.Cu")
		(net 73)
	)
	(segment
		(start 303.7 105.71)
		(end 303.7 112.46)
		(width 0.45)
		(layer "In3.Cu")
		(net 73)
	)
	(segment
		(start 272.8 124.01)
		(end 288.6 124.01)
		(width 0.45)
		(layer "In3.Cu")
		(net 73)
	)
	(segment
		(start 302.5 104.51)
		(end 303.7 105.71)
		(width 0.45)
		(layer "In3.Cu")
		(net 73)
	)
	(segment
		(start 260 132.16)
		(end 259.2 131.36)
		(width 0.45)
		(layer "In3.Cu")
		(net 73)
	)
	(segment
		(start 303.7 112.46)
		(end 302.85 113.31)
		(width 0.45)
		(layer "In3.Cu")
		(net 73)
	)
	(segment
		(start 302.85 113.31)
		(end 302.85 113.36)
		(width 0.45)
		(layer "In3.Cu")
		(net 73)
	)
	(segment
		(start 302.02 103.61)
		(end 302.02 104.03)
		(width 0.45)
		(layer "In3.Cu")
		(net 73)
	)
	(segment
		(start 221.5 82.66)
		(end 218.8 79.96)
		(width 0.2)
		(layer "In5.Cu")
		(net 73)
	)
	(segment
		(start 190.70861 76.16861)
		(end 190.70861 74.102163)
		(width 0.2)
		(layer "In5.Cu")
		(net 73)
	)
	(segment
		(start 194.5 79.96)
		(end 190.70861 76.16861)
		(width 0.2)
		(layer "In5.Cu")
		(net 73)
	)
	(segment
		(start 218.8 79.96)
		(end 194.5 79.96)
		(width 0.2)
		(layer "In5.Cu")
		(net 73)
	)
	(segment
		(start 202.65861 72.802163)
		(end 201.70861 72.802163)
		(width 0.2)
		(layer "F.Cu")
		(net 74)
	)
	(segment
		(start 203.1 73.243553)
		(end 203.1 80.65)
		(width 0.2)
		(layer "F.Cu")
		(net 74)
	)
	(segment
		(start 202.65861 72.802163)
		(end 203.1 73.243553)
		(width 0.2)
		(layer "F.Cu")
		(net 74)
	)
	(segment
		(start 202.48239 81.26761)
		(end 202.48239 83.347837)
		(width 0.2)
		(layer "F.Cu")
		(net 74)
	)
	(segment
		(start 203.1 80.65)
		(end 202.48239 81.26761)
		(width 0.2)
		(layer "F.Cu")
		(net 74)
	)
	(via
		(at 149.45 136.86)
		(size 0.45)
		(drill 0.1)
		(layers "F.Cu" "B.Cu")
		(remove_unused_layers yes)
		(keep_end_layers yes)
		(zone_layer_connections "In3.Cu")
		(teardrops
			(best_length_ratio 0.4)
			(max_length 1)
			(best_width_ratio 0.9)
			(max_width 2)
			(curved_edges yes)
			(filter_ratio 0.9)
			(enabled yes)
			(allow_two_segments yes)
			(prefer_zone_connections yes)
		)
		(net 74)
	)
	(via
		(at 149.45 138.86)
		(size 0.45)
		(drill 0.1)
		(layers "F.Cu" "B.Cu")
		(remove_unused_layers yes)
		(keep_end_layers yes)
		(zone_layer_connections "In3.Cu")
		(teardrops
			(best_length_ratio 0.4)
			(max_length 1)
			(best_width_ratio 0.9)
			(max_width 2)
			(curved_edges yes)
			(filter_ratio 0.9)
			(enabled yes)
			(allow_two_segments yes)
			(prefer_zone_connections yes)
		)
		(net 74)
	)
	(via
		(at 132.29 140.86)
		(size 0.45)
		(drill 0.1)
		(layers "F.Cu" "B.Cu")
		(remove_unused_layers yes)
		(keep_end_layers yes)
		(zone_layer_connections "In3.Cu")
		(teardrops
			(best_length_ratio 0.4)
			(max_length 1)
			(best_width_ratio 0.9)
			(max_width 2)
			(curved_edges yes)
			(filter_ratio 0.9)
			(enabled yes)
			(allow_two_segments yes)
			(prefer_zone_connections yes)
		)
		(net 74)
	)
	(via
		(at 134.29 136.86)
		(size 0.45)
		(drill 0.1)
		(layers "F.Cu" "B.Cu")
		(remove_unused_layers yes)
		(keep_end_layers yes)
		(zone_layer_connections "In3.Cu")
		(teardrops
			(best_length_ratio 0.4)
			(max_length 1)
			(best_width_ratio 0.9)
			(max_width 2)
			(curved_edges yes)
			(filter_ratio 0.9)
			(enabled yes)
			(allow_two_segments yes)
			(prefer_zone_connections yes)
		)
		(net 74)
	)
	(via
		(at 300.040001 116.44)
		(size 0.45)
		(drill 0.1)
		(layers "F.Cu" "B.Cu")
		(remove_unused_layers yes)
		(keep_end_layers yes)
		(free yes)
		(zone_layer_connections "In3.Cu")
		(teardrops
			(best_length_ratio 0.4)
			(max_length 1)
			(best_width_ratio 0.9)
			(max_width 2)
			(curved_edges yes)
			(filter_ratio 0.9)
			(enabled yes)
			(allow_two_segments yes)
			(prefer_zone_connections yes)
		)
		(net 74)
	)
	(via
		(at 136.29 137.86)
		(size 0.45)
		(drill 0.1)
		(layers "F.Cu" "B.Cu")
		(remove_unused_layers yes)
		(keep_end_layers yes)
		(zone_layer_connections "In3.Cu")
		(teardrops
			(best_length_ratio 0.4)
			(max_length 1)
			(best_width_ratio 0.9)
			(max_width 2)
			(curved_edges yes)
			(filter_ratio 0.9)
			(enabled yes)
			(allow_two_segments yes)
			(prefer_zone_connections yes)
		)
		(net 74)
	)
	(via
		(at 300.04 117.44)
		(size 0.45)
		(drill 0.1)
		(layers "F.Cu" "B.Cu")
		(remove_unused_layers yes)
		(keep_end_layers yes)
		(free yes)
		(zone_layer_connections "In3.Cu")
		(teardrops
			(best_length_ratio 0.4)
			(max_length 1)
			(best_width_ratio 0.9)
			(max_width 2)
			(curved_edges yes)
			(filter_ratio 0.9)
			(enabled yes)
			(allow_two_segments yes)
			(prefer_zone_connections yes)
		)
		(net 74)
	)
	(via
		(at 133.29 139.86)
		(size 0.45)
		(drill 0.1)
		(layers "F.Cu" "B.Cu")
		(remove_unused_layers yes)
		(keep_end_layers yes)
		(zone_layer_connections "In3.Cu")
		(teardrops
			(best_length_ratio 0.4)
			(max_length 1)
			(best_width_ratio 0.9)
			(max_width 2)
			(curved_edges yes)
			(filter_ratio 0.9)
			(enabled yes)
			(allow_two_segments yes)
			(prefer_zone_connections yes)
		)
		(net 74)
	)
	(via
		(at 150.45 140.86)
		(size 0.45)
		(drill 0.1)
		(layers "F.Cu" "B.Cu")
		(remove_unused_layers yes)
		(keep_end_layers yes)
		(zone_layer_connections "In3.Cu")
		(teardrops
			(best_length_ratio 0.4)
			(max_length 1)
			(best_width_ratio 0.9)
			(max_width 2)
			(curved_edges yes)
			(filter_ratio 0.9)
			(enabled yes)
			(allow_two_segments yes)
			(prefer_zone_connections yes)
		)
		(net 74)
	)
	(via
		(at 301.04 117.44)
		(size 0.45)
		(drill 0.1)
		(layers "F.Cu" "B.Cu")
		(remove_unused_layers yes)
		(keep_end_layers yes)
		(free yes)
		(zone_layer_connections "In3.Cu")
		(teardrops
			(best_length_ratio 0.4)
			(max_length 1)
			(best_width_ratio 0.9)
			(max_width 2)
			(curved_edges yes)
			(filter_ratio 0.9)
			(enabled yes)
			(allow_two_segments yes)
			(prefer_zone_connections yes)
		)
		(net 74)
	)
	(via
		(at 300.04 115.44)
		(size 0.45)
		(drill 0.1)
		(layers "F.Cu" "B.Cu")
		(remove_unused_layers yes)
		(keep_end_layers yes)
		(free yes)
		(zone_layer_connections "In3.Cu")
		(teardrops
			(best_length_ratio 0.4)
			(max_length 1)
			(best_width_ratio 0.9)
			(max_width 2)
			(curved_edges yes)
			(filter_ratio 0.9)
			(enabled yes)
			(allow_two_segments yes)
			(prefer_zone_connections yes)
		)
		(net 74)
	)
	(via
		(at 153.45 137.86)
		(size 0.45)
		(drill 0.1)
		(layers "F.Cu" "B.Cu")
		(remove_unused_layers yes)
		(keep_end_layers yes)
		(zone_layer_connections "In3.Cu")
		(teardrops
			(best_length_ratio 0.4)
			(max_length 1)
			(best_width_ratio 0.9)
			(max_width 2)
			(curved_edges yes)
			(filter_ratio 0.9)
			(enabled yes)
			(allow_two_segments yes)
			(prefer_zone_connections yes)
		)
		(net 74)
	)
	(via
		(at 132.29 134.86)
		(size 0.45)
		(drill 0.1)
		(layers "F.Cu" "B.Cu")
		(remove_unused_layers yes)
		(keep_end_layers yes)
		(zone_layer_connections "In3.Cu")
		(teardrops
			(best_length_ratio 0.4)
			(max_length 1)
			(best_width_ratio 0.9)
			(max_width 2)
			(curved_edges yes)
			(filter_ratio 0.9)
			(enabled yes)
			(allow_two_segments yes)
			(prefer_zone_connections yes)
		)
		(net 74)
	)
	(via
		(at 252.184999 88.449999)
		(size 0.45)
		(drill 0.1)
		(layers "F.Cu" "B.Cu")
		(remove_unused_layers yes)
		(keep_end_layers yes)
		(zone_layer_connections "In5.Cu")
		(teardrops
			(best_length_ratio 0.4)
			(max_length 1)
			(best_width_ratio 0.9)
			(max_width 2)
			(curved_edges yes)
			(filter_ratio 0.9)
			(enabled yes)
			(allow_two_segments yes)
			(prefer_zone_connections yes)
		)
		(net 74)
	)
	(via
		(at 150.45 138.86)
		(size 0.45)
		(drill 0.1)
		(layers "F.Cu" "B.Cu")
		(remove_unused_layers yes)
		(keep_end_layers yes)
		(zone_layer_connections "In3.Cu")
		(teardrops
			(best_length_ratio 0.4)
			(max_length 1)
			(best_width_ratio 0.9)
			(max_width 2)
			(curved_edges yes)
			(filter_ratio 0.9)
			(enabled yes)
			(allow_two_segments yes)
			(prefer_zone_connections yes)
		)
		(net 74)
	)
	(via
		(at 150.45 136.86)
		(size 0.45)
		(drill 0.1)
		(layers "F.Cu" "B.Cu")
		(remove_unused_layers yes)
		(keep_end_layers yes)
		(zone_layer_connections "In3.Cu")
		(teardrops
			(best_length_ratio 0.4)
			(max_length 1)
			(best_width_ratio 0.9)
			(max_width 2)
			(curved_edges yes)
			(filter_ratio 0.9)
			(enabled yes)
			(allow_two_segments yes)
			(prefer_zone_connections yes)
		)
		(net 74)
	)
	(via
		(at 151.45 141.86)
		(size 0.45)
		(drill 0.1)
		(layers "F.Cu" "B.Cu")
		(remove_unused_layers yes)
		(keep_end_layers yes)
		(zone_layer_connections "In3.Cu")
		(teardrops
			(best_length_ratio 0.4)
			(max_length 1)
			(best_width_ratio 0.9)
			(max_width 2)
			(curved_edges yes)
			(filter_ratio 0.9)
			(enabled yes)
			(allow_two_segments yes)
			(prefer_zone_connections yes)
		)
		(net 74)
	)
	(via
		(at 132.29 132.86)
		(size 0.45)
		(drill 0.1)
		(layers "F.Cu" "B.Cu")
		(remove_unused_layers yes)
		(keep_end_layers yes)
		(zone_layer_connections "In3.Cu")
		(teardrops
			(best_length_ratio 0.4)
			(max_length 1)
			(best_width_ratio 0.9)
			(max_width 2)
			(curved_edges yes)
			(filter_ratio 0.9)
			(enabled yes)
			(allow_two_segments yes)
			(prefer_zone_connections yes)
		)
		(net 74)
	)
	(via
		(at 151.45 134.86)
		(size 0.45)
		(drill 0.1)
		(layers "F.Cu" "B.Cu")
		(remove_unused_layers yes)
		(keep_end_layers yes)
		(zone_layer_connections "In3.Cu")
		(teardrops
			(best_length_ratio 0.4)
			(max_length 1)
			(best_width_ratio 0.9)
			(max_width 2)
			(curved_edges yes)
			(filter_ratio 0.9)
			(enabled yes)
			(allow_two_segments yes)
			(prefer_zone_connections yes)
		)
		(net 74)
	)
	(via
		(at 132.29 136.86)
		(size 0.45)
		(drill 0.1)
		(layers "F.Cu" "B.Cu")
		(remove_unused_layers yes)
		(keep_end_layers yes)
		(zone_layer_connections "In3.Cu")
		(teardrops
			(best_length_ratio 0.4)
			(max_length 1)
			(best_width_ratio 0.9)
			(max_width 2)
			(curved_edges yes)
			(filter_ratio 0.9)
			(enabled yes)
			(allow_two_segments yes)
			(prefer_zone_connections yes)
		)
		(net 74)
	)
	(via
		(at 152.45 136.86)
		(size 0.45)
		(drill 0.1)
		(layers "F.Cu" "B.Cu")
		(remove_unused_layers yes)
		(keep_end_layers yes)
		(zone_layer_connections "In3.Cu")
		(teardrops
			(best_length_ratio 0.4)
			(max_length 1)
			(best_width_ratio 0.9)
			(max_width 2)
			(curved_edges yes)
			(filter_ratio 0.9)
			(enabled yes)
			(allow_two_segments yes)
			(prefer_zone_connections yes)
		)
		(net 74)
	)
	(via
		(at 134.29 138.86)
		(size 0.45)
		(drill 0.1)
		(layers "F.Cu" "B.Cu")
		(remove_unused_layers yes)
		(keep_end_layers yes)
		(zone_layer_connections "In3.Cu")
		(teardrops
			(best_length_ratio 0.4)
			(max_length 1)
			(best_width_ratio 0.9)
			(max_width 2)
			(curved_edges yes)
			(filter_ratio 0.9)
			(enabled yes)
			(allow_two_segments yes)
			(prefer_zone_connections yes)
		)
		(net 74)
	)
	(via
		(at 135.29 137.86)
		(size 0.45)
		(drill 0.1)
		(layers "F.Cu" "B.Cu")
		(remove_unused_layers yes)
		(keep_end_layers yes)
		(zone_layer_connections "In3.Cu")
		(teardrops
			(best_length_ratio 0.4)
			(max_length 1)
			(best_width_ratio 0.9)
			(max_width 2)
			(curved_edges yes)
			(filter_ratio 0.9)
			(enabled yes)
			(allow_two_segments yes)
			(prefer_zone_connections yes)
		)
		(net 74)
	)
	(via
		(at 129.29 137.86)
		(size 0.45)
		(drill 0.1)
		(layers "F.Cu" "B.Cu")
		(remove_unused_layers yes)
		(keep_end_layers yes)
		(zone_layer_connections "In3.Cu")
		(teardrops
			(best_length_ratio 0.4)
			(max_length 1)
			(best_width_ratio 0.9)
			(max_width 2)
			(curved_edges yes)
			(filter_ratio 0.9)
			(enabled yes)
			(allow_two_segments yes)
			(prefer_zone_connections yes)
		)
		(net 74)
	)
	(via
		(at 133.29 132.86)
		(size 0.45)
		(drill 0.1)
		(layers "F.Cu" "B.Cu")
		(remove_unused_layers yes)
		(keep_end_layers yes)
		(zone_layer_connections "In3.Cu")
		(teardrops
			(best_length_ratio 0.4)
			(max_length 1)
			(best_width_ratio 0.9)
			(max_width 2)
			(curved_edges yes)
			(filter_ratio 0.9)
			(enabled yes)
			(allow_two_segments yes)
			(prefer_zone_connections yes)
		)
		(net 74)
	)
	(via
		(at 135.29 132.86)
		(size 0.45)
		(drill 0.1)
		(layers "F.Cu" "B.Cu")
		(remove_unused_layers yes)
		(keep_end_layers yes)
		(zone_layer_connections "In3.Cu")
		(teardrops
			(best_length_ratio 0.4)
			(max_length 1)
			(best_width_ratio 0.9)
			(max_width 2)
			(curved_edges yes)
			(filter_ratio 0.9)
			(enabled yes)
			(allow_two_segments yes)
			(prefer_zone_connections yes)
		)
		(net 74)
	)
	(via
		(at 134.29 137.86)
		(size 0.45)
		(drill 0.1)
		(layers "F.Cu" "B.Cu")
		(remove_unused_layers yes)
		(keep_end_layers yes)
		(zone_layer_connections "In3.Cu")
		(teardrops
			(best_length_ratio 0.4)
			(max_length 1)
			(best_width_ratio 0.9)
			(max_width 2)
			(curved_edges yes)
			(filter_ratio 0.9)
			(enabled yes)
			(allow_two_segments yes)
			(prefer_zone_connections yes)
		)
		(net 74)
	)
	(via
		(at 301.039999 116.44)
		(size 0.45)
		(drill 0.1)
		(layers "F.Cu" "B.Cu")
		(remove_unused_layers yes)
		(keep_end_layers yes)
		(free yes)
		(zone_layer_connections "In3.Cu")
		(teardrops
			(best_length_ratio 0.4)
			(max_length 1)
			(best_width_ratio 0.9)
			(max_width 2)
			(curved_edges yes)
			(filter_ratio 0.9)
			(enabled yes)
			(allow_two_segments yes)
			(prefer_zone_connections yes)
		)
		(net 74)
	)
	(via
		(at 147.45 137.86)
		(size 0.45)
		(drill 0.1)
		(layers "F.Cu" "B.Cu")
		(remove_unused_layers yes)
		(keep_end_layers yes)
		(zone_layer_connections "In3.Cu")
		(teardrops
			(best_length_ratio 0.4)
			(max_length 1)
			(best_width_ratio 0.9)
			(max_width 2)
			(curved_edges yes)
			(filter_ratio 0.9)
			(enabled yes)
			(allow_two_segments yes)
			(prefer_zone_connections yes)
		)
		(net 74)
	)
	(via
		(at 153.45 132.86)
		(size 0.45)
		(drill 0.1)
		(layers "F.Cu" "B.Cu")
		(remove_unused_layers yes)
		(keep_end_layers yes)
		(zone_layer_connections "In3.Cu")
		(teardrops
			(best_length_ratio 0.4)
			(max_length 1)
			(best_width_ratio 0.9)
			(max_width 2)
			(curved_edges yes)
			(filter_ratio 0.9)
			(enabled yes)
			(allow_two_segments yes)
			(prefer_zone_connections yes)
		)
		(net 74)
	)
	(via
		(at 302.04 115.44)
		(size 0.45)
		(drill 0.1)
		(layers "F.Cu" "B.Cu")
		(remove_unused_layers yes)
		(keep_end_layers yes)
		(free yes)
		(zone_layer_connections "In3.Cu" "In5.Cu")
		(teardrops
			(best_length_ratio 0.4)
			(max_length 1)
			(best_width_ratio 0.9)
			(max_width 2)
			(curved_edges yes)
			(filter_ratio 0.9)
			(enabled yes)
			(allow_two_segments yes)
			(prefer_zone_connections yes)
		)
		(net 74)
	)
	(via
		(at 152.45 137.86)
		(size 0.45)
		(drill 0.1)
		(layers "F.Cu" "B.Cu")
		(remove_unused_layers yes)
		(keep_end_layers yes)
		(zone_layer_connections "In3.Cu")
		(teardrops
			(best_length_ratio 0.4)
			(max_length 1)
			(best_width_ratio 0.9)
			(max_width 2)
			(curved_edges yes)
			(filter_ratio 0.9)
			(enabled yes)
			(allow_two_segments yes)
			(prefer_zone_connections yes)
		)
		(net 74)
	)
	(via
		(at 150.45 134.86)
		(size 0.45)
		(drill 0.1)
		(layers "F.Cu" "B.Cu")
		(remove_unused_layers yes)
		(keep_end_layers yes)
		(zone_layer_connections "In3.Cu")
		(teardrops
			(best_length_ratio 0.4)
			(max_length 1)
			(best_width_ratio 0.9)
			(max_width 2)
			(curved_edges yes)
			(filter_ratio 0.9)
			(enabled yes)
			(allow_two_segments yes)
			(prefer_zone_connections yes)
		)
		(net 74)
	)
	(via
		(at 151.45 136.86)
		(size 0.45)
		(drill 0.1)
		(layers "F.Cu" "B.Cu")
		(remove_unused_layers yes)
		(keep_end_layers yes)
		(zone_layer_connections "In3.Cu")
		(teardrops
			(best_length_ratio 0.4)
			(max_length 1)
			(best_width_ratio 0.9)
			(max_width 2)
			(curved_edges yes)
			(filter_ratio 0.9)
			(enabled yes)
			(allow_two_segments yes)
			(prefer_zone_connections yes)
		)
		(net 74)
	)
	(via
		(at 202.65861 72.802163)
		(size 0.45)
		(drill 0.1)
		(layers "F.Cu" "B.Cu")
		(remove_unused_layers yes)
		(keep_end_layers yes)
		(zone_layer_connections "In5.Cu")
		(teardrops
			(best_length_ratio 0.4)
			(max_length 1)
			(best_width_ratio 0.9)
			(max_width 2)
			(curved_edges yes)
			(filter_ratio 0.9)
			(enabled yes)
			(allow_two_segments yes)
			(prefer_zone_connections yes)
		)
		(net 74)
	)
	(via
		(at 302.04 117.44)
		(size 0.45)
		(drill 0.1)
		(layers "F.Cu" "B.Cu")
		(remove_unused_layers yes)
		(keep_end_layers yes)
		(free yes)
		(zone_layer_connections "In3.Cu")
		(teardrops
			(best_length_ratio 0.4)
			(max_length 1)
			(best_width_ratio 0.9)
			(max_width 2)
			(curved_edges yes)
			(filter_ratio 0.9)
			(enabled yes)
			(allow_two_segments yes)
			(prefer_zone_connections yes)
		)
		(net 74)
	)
	(via
		(at 132.29 138.86)
		(size 0.45)
		(drill 0.1)
		(layers "F.Cu" "B.Cu")
		(remove_unused_layers yes)
		(keep_end_layers yes)
		(zone_layer_connections "In3.Cu")
		(teardrops
			(best_length_ratio 0.4)
			(max_length 1)
			(best_width_ratio 0.9)
			(max_width 2)
			(curved_edges yes)
			(filter_ratio 0.9)
			(enabled yes)
			(allow_two_segments yes)
			(prefer_zone_connections yes)
		)
		(net 74)
	)
	(via
		(at 152.45 138.86)
		(size 0.45)
		(drill 0.1)
		(layers "F.Cu" "B.Cu")
		(remove_unused_layers yes)
		(keep_end_layers yes)
		(zone_layer_connections "In3.Cu")
		(teardrops
			(best_length_ratio 0.4)
			(max_length 1)
			(best_width_ratio 0.9)
			(max_width 2)
			(curved_edges yes)
			(filter_ratio 0.9)
			(enabled yes)
			(allow_two_segments yes)
			(prefer_zone_connections yes)
		)
		(net 74)
	)
	(via
		(at 301.04 115.44)
		(size 0.45)
		(drill 0.1)
		(layers "F.Cu" "B.Cu")
		(remove_unused_layers yes)
		(keep_end_layers yes)
		(free yes)
		(zone_layer_connections "In3.Cu")
		(teardrops
			(best_length_ratio 0.4)
			(max_length 1)
			(best_width_ratio 0.9)
			(max_width 2)
			(curved_edges yes)
			(filter_ratio 0.9)
			(enabled yes)
			(allow_two_segments yes)
			(prefer_zone_connections yes)
		)
		(net 74)
	)
	(via
		(at 302.04 116.44)
		(size 0.45)
		(drill 0.1)
		(layers "F.Cu" "B.Cu")
		(remove_unused_layers yes)
		(keep_end_layers yes)
		(free yes)
		(zone_layer_connections "In3.Cu")
		(teardrops
			(best_length_ratio 0.4)
			(max_length 1)
			(best_width_ratio 0.9)
			(max_width 2)
			(curved_edges yes)
			(filter_ratio 0.9)
			(enabled yes)
			(allow_two_segments yes)
			(prefer_zone_connections yes)
		)
		(net 74)
	)
	(via
		(at 150.45 132.86)
		(size 0.45)
		(drill 0.1)
		(layers "F.Cu" "B.Cu")
		(remove_unused_layers yes)
		(keep_end_layers yes)
		(zone_layer_connections "In3.Cu")
		(teardrops
			(best_length_ratio 0.4)
			(max_length 1)
			(best_width_ratio 0.9)
			(max_width 2)
			(curved_edges yes)
			(filter_ratio 0.9)
			(enabled yes)
			(allow_two_segments yes)
			(prefer_zone_connections yes)
		)
		(net 74)
	)
	(via
		(at 133.29 136.86)
		(size 0.45)
		(drill 0.1)
		(layers "F.Cu" "B.Cu")
		(remove_unused_layers yes)
		(keep_end_layers yes)
		(zone_layer_connections "In3.Cu")
		(teardrops
			(best_length_ratio 0.4)
			(max_length 1)
			(best_width_ratio 0.9)
			(max_width 2)
			(curved_edges yes)
			(filter_ratio 0.9)
			(enabled yes)
			(allow_two_segments yes)
			(prefer_zone_connections yes)
		)
		(net 74)
	)
	(via
		(at 151.45 137.86)
		(size 0.45)
		(drill 0.1)
		(layers "F.Cu" "B.Cu")
		(remove_unused_layers yes)
		(keep_end_layers yes)
		(zone_layer_connections "In3.Cu")
		(teardrops
			(best_length_ratio 0.4)
			(max_length 1)
			(best_width_ratio 0.9)
			(max_width 2)
			(curved_edges yes)
			(filter_ratio 0.9)
			(enabled yes)
			(allow_two_segments yes)
			(prefer_zone_connections yes)
		)
		(net 74)
	)
	(via
		(at 148.45 132.86)
		(size 0.45)
		(drill 0.1)
		(layers "F.Cu" "B.Cu")
		(remove_unused_layers yes)
		(keep_end_layers yes)
		(zone_layer_connections "In3.Cu")
		(teardrops
			(best_length_ratio 0.4)
			(max_length 1)
			(best_width_ratio 0.9)
			(max_width 2)
			(curved_edges yes)
			(filter_ratio 0.9)
			(enabled yes)
			(allow_two_segments yes)
			(prefer_zone_connections yes)
		)
		(net 74)
	)
	(via
		(at 133.29 137.86)
		(size 0.45)
		(drill 0.1)
		(layers "F.Cu" "B.Cu")
		(remove_unused_layers yes)
		(keep_end_layers yes)
		(zone_layer_connections "In3.Cu")
		(teardrops
			(best_length_ratio 0.4)
			(max_length 1)
			(best_width_ratio 0.9)
			(max_width 2)
			(curved_edges yes)
			(filter_ratio 0.9)
			(enabled yes)
			(allow_two_segments yes)
			(prefer_zone_connections yes)
		)
		(net 74)
	)
	(via
		(at 130.29 132.86)
		(size 0.45)
		(drill 0.1)
		(layers "F.Cu" "B.Cu")
		(remove_unused_layers yes)
		(keep_end_layers yes)
		(zone_layer_connections "In3.Cu")
		(teardrops
			(best_length_ratio 0.4)
			(max_length 1)
			(best_width_ratio 0.9)
			(max_width 2)
			(curved_edges yes)
			(filter_ratio 0.9)
			(enabled yes)
			(allow_two_segments yes)
			(prefer_zone_connections yes)
		)
		(net 74)
	)
	(via
		(at 133.29 141.86)
		(size 0.45)
		(drill 0.1)
		(layers "F.Cu" "B.Cu")
		(remove_unused_layers yes)
		(keep_end_layers yes)
		(zone_layer_connections "In3.Cu")
		(teardrops
			(best_length_ratio 0.4)
			(max_length 1)
			(best_width_ratio 0.9)
			(max_width 2)
			(curved_edges yes)
			(filter_ratio 0.9)
			(enabled yes)
			(allow_two_segments yes)
			(prefer_zone_connections yes)
		)
		(net 74)
	)
	(via
		(at 154.45 137.86)
		(size 0.45)
		(drill 0.1)
		(layers "F.Cu" "B.Cu")
		(remove_unused_layers yes)
		(keep_end_layers yes)
		(zone_layer_connections "In3.Cu")
		(teardrops
			(best_length_ratio 0.4)
			(max_length 1)
			(best_width_ratio 0.9)
			(max_width 2)
			(curved_edges yes)
			(filter_ratio 0.9)
			(enabled yes)
			(allow_two_segments yes)
			(prefer_zone_connections yes)
		)
		(net 74)
	)
	(via
		(at 131.29 137.86)
		(size 0.45)
		(drill 0.1)
		(layers "F.Cu" "B.Cu")
		(remove_unused_layers yes)
		(keep_end_layers yes)
		(zone_layer_connections "In3.Cu")
		(teardrops
			(best_length_ratio 0.4)
			(max_length 1)
			(best_width_ratio 0.9)
			(max_width 2)
			(curved_edges yes)
			(filter_ratio 0.9)
			(enabled yes)
			(allow_two_segments yes)
			(prefer_zone_connections yes)
		)
		(net 74)
	)
	(via
		(at 151.45 132.86)
		(size 0.45)
		(drill 0.1)
		(layers "F.Cu" "B.Cu")
		(remove_unused_layers yes)
		(keep_end_layers yes)
		(zone_layer_connections "In3.Cu")
		(teardrops
			(best_length_ratio 0.4)
			(max_length 1)
			(best_width_ratio 0.9)
			(max_width 2)
			(curved_edges yes)
			(filter_ratio 0.9)
			(enabled yes)
			(allow_two_segments yes)
			(prefer_zone_connections yes)
		)
		(net 74)
	)
	(via
		(at 151.45 139.86)
		(size 0.45)
		(drill 0.1)
		(layers "F.Cu" "B.Cu")
		(remove_unused_layers yes)
		(keep_end_layers yes)
		(zone_layer_connections "In3.Cu")
		(teardrops
			(best_length_ratio 0.4)
			(max_length 1)
			(best_width_ratio 0.9)
			(max_width 2)
			(curved_edges yes)
			(filter_ratio 0.9)
			(enabled yes)
			(allow_two_segments yes)
			(prefer_zone_connections yes)
		)
		(net 74)
	)
	(via
		(at 133.29 134.86)
		(size 0.45)
		(drill 0.1)
		(layers "F.Cu" "B.Cu")
		(remove_unused_layers yes)
		(keep_end_layers yes)
		(zone_layer_connections "In3.Cu")
		(teardrops
			(best_length_ratio 0.4)
			(max_length 1)
			(best_width_ratio 0.9)
			(max_width 2)
			(curved_edges yes)
			(filter_ratio 0.9)
			(enabled yes)
			(allow_two_segments yes)
			(prefer_zone_connections yes)
		)
		(net 74)
	)
	(via
		(at 131.29 138.86)
		(size 0.45)
		(drill 0.1)
		(layers "F.Cu" "B.Cu")
		(remove_unused_layers yes)
		(keep_end_layers yes)
		(zone_layer_connections "In3.Cu")
		(teardrops
			(best_length_ratio 0.4)
			(max_length 1)
			(best_width_ratio 0.9)
			(max_width 2)
			(curved_edges yes)
			(filter_ratio 0.9)
			(enabled yes)
			(allow_two_segments yes)
			(prefer_zone_connections yes)
		)
		(net 74)
	)
	(via
		(at 131.29 136.86)
		(size 0.45)
		(drill 0.1)
		(layers "F.Cu" "B.Cu")
		(remove_unused_layers yes)
		(keep_end_layers yes)
		(zone_layer_connections "In3.Cu")
		(teardrops
			(best_length_ratio 0.4)
			(max_length 1)
			(best_width_ratio 0.9)
			(max_width 2)
			(curved_edges yes)
			(filter_ratio 0.9)
			(enabled yes)
			(allow_two_segments yes)
			(prefer_zone_connections yes)
		)
		(net 74)
	)
	(via
		(at 149.45 137.86)
		(size 0.45)
		(drill 0.1)
		(layers "F.Cu" "B.Cu")
		(remove_unused_layers yes)
		(keep_end_layers yes)
		(zone_layer_connections "In3.Cu")
		(teardrops
			(best_length_ratio 0.4)
			(max_length 1)
			(best_width_ratio 0.9)
			(max_width 2)
			(curved_edges yes)
			(filter_ratio 0.9)
			(enabled yes)
			(allow_two_segments yes)
			(prefer_zone_connections yes)
		)
		(net 74)
	)
	(segment
		(start 154.5 132.86)
		(end 153.45 132.86)
		(width 0.5)
		(layer "B.Cu")
		(net 74)
	)
	(segment
		(start 136.365 132.85)
		(end 135.31 132.85)
		(width 0.5)
		(layer "B.Cu")
		(net 74)
	)
	(segment
		(start 202.65861 72.802163)
		(end 204.016447 74.16)
		(width 0.2)
		(layer "In5.Cu")
		(net 74)
	)
	(segment
		(start 305.65 95.06)
		(end 297.59 87)
		(width 0.2)
		(layer "In5.Cu")
		(net 74)
	)
	(segment
		(start 256.810001 88.449999)
		(end 252.184999 88.449999)
		(width 0.2)
		(layer "In5.Cu")
		(net 74)
	)
	(segment
		(start 258.86 86.4)
		(end 256.810001 88.449999)
		(width 0.2)
		(layer "In5.Cu")
		(net 74)
	)
	(segment
		(start 222.55 74.16)
		(end 230.25 81.86)
		(width 0.2)
		(layer "In5.Cu")
		(net 74)
	)
	(segment
		(start 245.595 81.86)
		(end 252.184999 88.449999)
		(width 0.2)
		(layer "In5.Cu")
		(net 74)
	)
	(segment
		(start 204.016447 74.16)
		(end 222.55 74.16)
		(width 0.2)
		(layer "In5.Cu")
		(net 74)
	)
	(segment
		(start 261.7 87)
		(end 261.1 86.4)
		(width 0.2)
		(layer "In5.Cu")
		(net 74)
	)
	(segment
		(start 302.04 115.44)
		(end 305.65 111.83)
		(width 0.2)
		(layer "In5.Cu")
		(net 74)
	)
	(segment
		(start 297.59 87)
		(end 261.7 87)
		(width 0.2)
		(layer "In5.Cu")
		(net 74)
	)
	(segment
		(start 305.65 111.83)
		(end 305.65 95.06)
		(width 0.2)
		(layer "In5.Cu")
		(net 74)
	)
	(segment
		(start 230.25 81.86)
		(end 245.595 81.86)
		(width 0.2)
		(layer "In5.Cu")
		(net 74)
	)
	(segment
		(start 261.1 86.4)
		(end 258.86 86.4)
		(width 0.2)
		(layer "In5.Cu")
		(net 74)
	)
	(segment
		(start 305.1 94.76)
		(end 304.5 95.36)
		(width 0.125)
		(layer "F.Cu")
		(net 75)
	)
	(segment
		(start 307.274 96.74)
		(end 307.98 96.74)
		(width 0.125)
		(layer "F.Cu")
		(net 75)
	)
	(segment
		(start 304.3 92.16)
		(end 304.65 92.16)
		(width 0.125)
		(layer "F.Cu")
		(net 75)
	)
	(segment
		(start 305.1 92.61)
		(end 305.1 94.76)
		(width 0.125)
		(layer "F.Cu")
		(net 75)
	)
	(segment
		(start 304.63 96.74)
		(end 305.35 96.74)
		(width 0.125)
		(layer "F.Cu")
		(net 75)
	)
	(segment
		(start 309.73 98.49)
		(end 313.65 98.49)
		(width 0.125)
		(layer "F.Cu")
		(net 75)
	)
	(segment
		(start 304.65 92.16)
		(end 305.1 92.61)
		(width 0.125)
		(layer "F.Cu")
		(net 75)
	)
	(segment
		(start 307.98 96.74)
		(end 309.73 98.49)
		(width 0.125)
		(layer "F.Cu")
		(net 75)
	)
	(segment
		(start 304.5 96.61)
		(end 304.63 96.74)
		(width 0.125)
		(layer "F.Cu")
		(net 75)
	)
	(segment
		(start 304.5 95.36)
		(end 304.5 96.61)
		(width 0.125)
		(layer "F.Cu")
		(net 75)
	)
	(segment
		(start 313.765499 98.374501)
		(end 313.765499 97.9165)
		(width 0.125)
		(layer "F.Cu")
		(net 75)
	)
	(segment
		(start 304.125 91.985)
		(end 304.3 92.16)
		(width 0.125)
		(layer "F.Cu")
		(net 75)
	)
	(segment
		(start 313.65 98.49)
		(end 313.765499 98.374501)
		(width 0.125)
		(layer "F.Cu")
		(net 75)
	)
	(segment
		(start 304.125 91.259)
		(end 304.125 91.985)
		(width 0.125)
		(layer "F.Cu")
		(net 75)
	)
	(segment
		(start 312.825499 137.56)
		(end 309.7 137.56)
		(width 0.125)
		(layer "F.Cu")
		(net 76)
	)
	(segment
		(start 307.9535 135.8135)
		(end 307.298999 135.8135)
		(width 0.125)
		(layer "F.Cu")
		(net 76)
	)
	(segment
		(start 313.075499 137.31)
		(end 312.825499 137.56)
		(width 0.125)
		(layer "F.Cu")
		(net 76)
	)
	(segment
		(start 313.075499 136.94)
		(end 313.075499 137.31)
		(width 0.125)
		(layer "F.Cu")
		(net 76)
	)
	(segment
		(start 309.7 137.56)
		(end 307.9535 135.8135)
		(width 0.125)
		(layer "F.Cu")
		(net 76)
	)
	(segment
		(start 304.65 92.71)
		(end 304.55 92.61)
		(width 0.125)
		(layer "F.Cu")
		(net 77)
	)
	(segment
		(start 218.525 163.135)
		(end 218.525 161.825)
		(width 0.3)
		(layer "F.Cu")
		(net 77)
	)
	(segment
		(start 303.477 92.037)
		(end 303.477 91.259)
		(width 0.125)
		(layer "F.Cu")
		(net 77)
	)
	(segment
		(start 303.15 96.74)
		(end 303.87 96.74)
		(width 0.125)
		(layer "F.Cu")
		(net 77)
	)
	(segment
		(start 218.525 161.825)
		(end 218.5 161.8)
		(width 0.3)
		(layer "F.Cu")
		(net 77)
	)
	(segment
		(start 218.1 161.8)
		(end 218.5 161.8)
		(width 0.3)
		(layer "F.Cu")
		(net 77)
	)
	(segment
		(start 218.025 163.135)
		(end 218.025 161.875)
		(width 0.3)
		(layer "F.Cu")
		(net 77)
	)
	(segment
		(start 218.025 161.875)
		(end 218.1 161.8)
		(width 0.3)
		(layer "F.Cu")
		(net 77)
	)
	(segment
		(start 217.6 161.8)
		(end 218.5 161.8)
		(width 0.3)
		(layer "F.Cu")
		(net 77)
	)
	(segment
		(start 304.55 92.61)
		(end 304.05 92.61)
		(width 0.125)
		(layer "F.Cu")
		(net 77)
	)
	(segment
		(start 304.05 92.61)
		(end 303.477 92.037)
		(width 0.125)
		(layer "F.Cu")
		(net 77)
	)
	(segment
		(start 217.525 163.135)
		(end 217.525 161.875)
		(width 0.3)
		(layer "F.Cu")
		(net 77)
	)
	(segment
		(start 217.525 161.875)
		(end 217.6 161.8)
		(width 0.3)
		(layer "F.Cu")
		(net 77)
	)
	(segment
		(start 219 163.11)
		(end 219.025 163.135)
		(width 0.3)
		(layer "F.Cu")
		(net 77)
	)
	(segment
		(start 303.87 96.74)
		(end 304 96.61)
		(width 0.125)
		(layer "F.Cu")
		(net 77)
	)
	(segment
		(start 304 96.61)
		(end 304 95.21)
		(width 0.125)
		(layer "F.Cu")
		(net 77)
	)
	(segment
		(start 188.70861 74.102163)
		(end 188.708611 72.802163)
		(width 0.2)
		(layer "F.Cu")
		(net 77)
	)
	(segment
		(start 304 95.21)
		(end 304.65 94.56)
		(width 0.125)
		(layer "F.Cu")
		(net 77)
	)
	(segment
		(start 304.65 94.56)
		(end 304.65 92.71)
		(width 0.125)
		(layer "F.Cu")
		(net 77)
	)
	(segment
		(start 218.5 161.8)
		(end 219 161.8)
		(width 0.3)
		(layer "F.Cu")
		(net 77)
	)
	(segment
		(start 219 161.8)
		(end 219 163.11)
		(width 0.3)
		(layer "F.Cu")
		(net 77)
	)
	(via
		(at 217 160.2)
		(size 0.45)
		(drill 0.1)
		(layers "F.Cu" "B.Cu")
		(free yes)
		(teardrops
			(best_length_ratio 0.4)
			(max_length 1)
			(best_width_ratio 0.9)
			(max_width 2)
			(curved_edges yes)
			(filter_ratio 0.9)
			(enabled yes)
			(allow_two_segments yes)
			(prefer_zone_connections yes)
		)
		(net 77)
	)
	(via
		(at 302.05 97.81)
		(size 0.45)
		(drill 0.1)
		(layers "F.Cu" "B.Cu")
		(remove_unused_layers yes)
		(keep_end_layers yes)
		(free yes)
		(zone_layer_connections "In3.Cu")
		(teardrops
			(best_length_ratio 0.4)
			(max_length 1)
			(best_width_ratio 0.9)
			(max_width 2)
			(curved_edges yes)
			(filter_ratio 0.9)
			(enabled yes)
			(allow_two_segments yes)
			(prefer_zone_connections yes)
		)
		(net 77)
	)
	(via
		(at 103.21 73.565)
		(size 0.45)
		(drill 0.1)
		(layers "F.Cu" "B.Cu")
		(remove_unused_layers yes)
		(keep_end_layers yes)
		(zone_layer_connections "In5.Cu")
		(teardrops
			(best_length_ratio 0.4)
			(max_length 1)
			(best_width_ratio 0.9)
			(max_width 2)
			(curved_edges yes)
			(filter_ratio 0.9)
			(enabled yes)
			(allow_two_segments yes)
			(prefer_zone_connections yes)
		)
		(net 77)
	)
	(via
		(at 301.049999 96.81)
		(size 0.45)
		(drill 0.1)
		(layers "F.Cu" "B.Cu")
		(remove_unused_layers yes)
		(keep_end_layers yes)
		(free yes)
		(zone_layer_connections "In3.Cu")
		(teardrops
			(best_length_ratio 0.4)
			(max_length 1)
			(best_width_ratio 0.9)
			(max_width 2)
			(curved_edges yes)
			(filter_ratio 0.9)
			(enabled yes)
			(allow_two_segments yes)
			(prefer_zone_connections yes)
		)
		(net 77)
	)
	(via
		(at 302.05 95.81)
		(size 0.45)
		(drill 0.1)
		(layers "F.Cu" "B.Cu")
		(remove_unused_layers yes)
		(keep_end_layers yes)
		(free yes)
		(zone_layer_connections "In3.Cu")
		(teardrops
			(best_length_ratio 0.4)
			(max_length 1)
			(best_width_ratio 0.9)
			(max_width 2)
			(curved_edges yes)
			(filter_ratio 0.9)
			(enabled yes)
			(allow_two_segments yes)
			(prefer_zone_connections yes)
		)
		(net 77)
	)
	(via
		(at 300.05 95.81)
		(size 0.45)
		(drill 0.1)
		(layers "F.Cu" "B.Cu")
		(remove_unused_layers yes)
		(keep_end_layers yes)
		(free yes)
		(zone_layer_connections "In3.Cu" "In5.Cu")
		(teardrops
			(best_length_ratio 0.4)
			(max_length 1)
			(best_width_ratio 0.9)
			(max_width 2)
			(curved_edges yes)
			(filter_ratio 0.9)
			(enabled yes)
			(allow_two_segments yes)
			(prefer_zone_connections yes)
		)
		(net 77)
	)
	(via
		(at 217.6 160.3)
		(size 0.45)
		(drill 0.1)
		(layers "F.Cu" "B.Cu")
		(free yes)
		(teardrops
			(best_length_ratio 0.4)
			(max_length 1)
			(best_width_ratio 0.9)
			(max_width 2)
			(curved_edges yes)
			(filter_ratio 0.9)
			(enabled yes)
			(allow_two_segments yes)
			(prefer_zone_connections yes)
		)
		(net 77)
	)
	(via
		(at 217 159.6)
		(size 0.45)
		(drill 0.1)
		(layers "F.Cu" "B.Cu")
		(free yes)
		(teardrops
			(best_length_ratio 0.4)
			(max_length 1)
			(best_width_ratio 0.9)
			(max_width 2)
			(curved_edges yes)
			(filter_ratio 0.9)
			(enabled yes)
			(allow_two_segments yes)
			(prefer_zone_connections yes)
		)
		(net 77)
	)
	(via
		(at 301.05 97.81)
		(size 0.45)
		(drill 0.1)
		(layers "F.Cu" "B.Cu")
		(remove_unused_layers yes)
		(keep_end_layers yes)
		(free yes)
		(zone_layer_connections "In3.Cu")
		(teardrops
			(best_length_ratio 0.4)
			(max_length 1)
			(best_width_ratio 0.9)
			(max_width 2)
			(curved_edges yes)
			(filter_ratio 0.9)
			(enabled yes)
			(allow_two_segments yes)
			(prefer_zone_connections yes)
		)
		(net 77)
	)
	(via
		(at 188.70861 74.102163)
		(size 0.45)
		(drill 0.1)
		(layers "F.Cu" "B.Cu")
		(remove_unused_layers yes)
		(keep_end_layers yes)
		(zone_layer_connections "In5.Cu")
		(teardrops
			(best_length_ratio 0.4)
			(max_length 1)
			(best_width_ratio 0.9)
			(max_width 2)
			(curved_edges yes)
			(filter_ratio 0.9)
			(enabled yes)
			(allow_two_segments yes)
			(prefer_zone_connections yes)
		)
		(net 77)
	)
	(via
		(at 300.050001 96.81)
		(size 0.45)
		(drill 0.1)
		(layers "F.Cu" "B.Cu")
		(remove_unused_layers yes)
		(keep_end_layers yes)
		(free yes)
		(zone_layer_connections "In3.Cu")
		(teardrops
			(best_length_ratio 0.4)
			(max_length 1)
			(best_width_ratio 0.9)
			(max_width 2)
			(curved_edges yes)
			(filter_ratio 0.9)
			(enabled yes)
			(allow_two_segments yes)
			(prefer_zone_connections yes)
		)
		(net 77)
	)
	(via
		(at 300.05 97.81)
		(size 0.45)
		(drill 0.1)
		(layers "F.Cu" "B.Cu")
		(remove_unused_layers yes)
		(keep_end_layers yes)
		(free yes)
		(zone_layer_connections "In3.Cu")
		(teardrops
			(best_length_ratio 0.4)
			(max_length 1)
			(best_width_ratio 0.9)
			(max_width 2)
			(curved_edges yes)
			(filter_ratio 0.9)
			(enabled yes)
			(allow_two_segments yes)
			(prefer_zone_connections yes)
		)
		(net 77)
	)
	(via
		(at 217.6 159.7)
		(size 0.45)
		(drill 0.1)
		(layers "F.Cu" "B.Cu")
		(free yes)
		(teardrops
			(best_length_ratio 0.4)
			(max_length 1)
			(best_width_ratio 0.9)
			(max_width 2)
			(curved_edges yes)
			(filter_ratio 0.9)
			(enabled yes)
			(allow_two_segments yes)
			(prefer_zone_connections yes)
		)
		(net 77)
	)
	(via
		(at 301.05 95.81)
		(size 0.45)
		(drill 0.1)
		(layers "F.Cu" "B.Cu")
		(remove_unused_layers yes)
		(keep_end_layers yes)
		(free yes)
		(zone_layer_connections "In3.Cu")
		(teardrops
			(best_length_ratio 0.4)
			(max_length 1)
			(best_width_ratio 0.9)
			(max_width 2)
			(curved_edges yes)
			(filter_ratio 0.9)
			(enabled yes)
			(allow_two_segments yes)
			(prefer_zone_connections yes)
		)
		(net 77)
	)
	(via
		(at 217 160.8)
		(size 0.45)
		(drill 0.1)
		(layers "F.Cu" "B.Cu")
		(free yes)
		(teardrops
			(best_length_ratio 0.4)
			(max_length 1)
			(best_width_ratio 0.9)
			(max_width 2)
			(curved_edges yes)
			(filter_ratio 0.9)
			(enabled yes)
			(allow_two_segments yes)
			(prefer_zone_connections yes)
		)
		(net 77)
	)
	(via
		(at 217.6 160.9)
		(size 0.45)
		(drill 0.1)
		(layers "F.Cu" "B.Cu")
		(free yes)
		(teardrops
			(best_length_ratio 0.4)
			(max_length 1)
			(best_width_ratio 0.9)
			(max_width 2)
			(curved_edges yes)
			(filter_ratio 0.9)
			(enabled yes)
			(allow_two_segments yes)
			(prefer_zone_connections yes)
		)
		(net 77)
	)
	(via
		(at 302.05 96.81)
		(size 0.45)
		(drill 0.1)
		(layers "F.Cu" "B.Cu")
		(remove_unused_layers yes)
		(keep_end_layers yes)
		(free yes)
		(zone_layer_connections "In3.Cu")
		(teardrops
			(best_length_ratio 0.4)
			(max_length 1)
			(best_width_ratio 0.9)
			(max_width 2)
			(curved_edges yes)
			(filter_ratio 0.9)
			(enabled yes)
			(allow_two_segments yes)
			(prefer_zone_connections yes)
		)
		(net 77)
	)
	(segment
		(start 161.305 69.355)
		(end 166.81 74.86)
		(width 0.2)
		(layer "In5.Cu")
		(net 77)
	)
	(segment
		(start 256.782513 89.96)
		(end 234.9 89.96)
		(width 0.2)
		(layer "In5.Cu")
		(net 77)
	)
	(segment
		(start 191.094975 72.96)
		(end 189.850773 72.96)
		(width 0.2)
		(layer "In5.Cu")
		(net 77)
	)
	(segment
		(start 223.95 79.01)
		(end 205.140447 79.01)
		(width 0.2)
		(layer "In5.Cu")
		(net 77)
	)
	(segment
		(start 104.008058 68.56)
		(end 156.5 68.56)
		(width 0.2)
		(layer "In5.Cu")
		(net 77)
	)
	(segment
		(start 205.140447 79.01)
		(end 199.38261 73.252163)
		(width 0.2)
		(layer "In5.Cu")
		(net 77)
	)
	(segment
		(start 193.087138 74.952163)
		(end 191.094975 72.96)
		(width 0.2)
		(layer "In5.Cu")
		(net 77)
	)
	(segment
		(start 299.7 96.16)
		(end 262.982513 96.16)
		(width 0.2)
		(layer "In5.Cu")
		(net 77)
	)
	(segment
		(start 103.21 73.565)
		(end 102.205 73.565)
		(width 0.2)
		(layer "In5.Cu")
		(net 77)
	)
	(segment
		(start 101.55 71.018058)
		(end 104.008058 68.56)
		(width 0.2)
		(layer "In5.Cu")
		(net 77)
	)
	(segment
		(start 197.43261 73.252163)
		(end 195.73261 74.952163)
		(width 0.2)
		(layer "In5.Cu")
		(net 77)
	)
	(segment
		(start 102.205 73.565)
		(end 101.55 72.91)
		(width 0.2)
		(layer "In5.Cu")
		(net 77)
	)
	(segment
		(start 189.850773 72.96)
		(end 188.70861 74.102163)
		(width 0.2)
		(layer "In5.Cu")
		(net 77)
	)
	(segment
		(start 199.38261 73.252163)
		(end 197.43261 73.252163)
		(width 0.2)
		(layer "In5.Cu")
		(net 77)
	)
	(segment
		(start 262.982513 96.16)
		(end 256.782513 89.96)
		(width 0.2)
		(layer "In5.Cu")
		(net 77)
	)
	(segment
		(start 195.73261 74.952163)
		(end 193.087138 74.952163)
		(width 0.2)
		(layer "In5.Cu")
		(net 77)
	)
	(segment
		(start 234.9 89.96)
		(end 223.95 79.01)
		(width 0.2)
		(layer "In5.Cu")
		(net 77)
	)
	(segment
		(start 166.81 74.86)
		(end 187.950773 74.86)
		(width 0.2)
		(layer "In5.Cu")
		(net 77)
	)
	(segment
		(start 157.295 69.355)
		(end 161.305 69.355)
		(width 0.2)
		(layer "In5.Cu")
		(net 77)
	)
	(segment
		(start 300.05 95.81)
		(end 299.7 96.16)
		(width 0.2)
		(layer "In5.Cu")
		(net 77)
	)
	(segment
		(start 187.950773 74.86)
		(end 188.70861 74.102163)
		(width 0.2)
		(layer "In5.Cu")
		(net 77)
	)
	(segment
		(start 156.5 68.56)
		(end 157.295 69.355)
		(width 0.2)
		(layer "In5.Cu")
		(net 77)
	)
	(segment
		(start 101.55 72.91)
		(end 101.55 71.018058)
		(width 0.2)
		(layer "In5.Cu")
		(net 77)
	)
	(segment
		(start 124.382 148.618)
		(end 124.22 148.78)
		(width 0.3)
		(layer "F.Cu")
		(net 78)
	)
	(segment
		(start 142.539 147.11)
		(end 142.539 148.616)
		(width 0.3)
		(layer "F.Cu")
		(net 78)
	)
	(segment
		(start 123.7825 149.9815)
		(end 123.7825 149.2175)
		(width 0.125)
		(layer "F.Cu")
		(net 78)
	)
	(segment
		(start 204.45 83.85)
		(end 203.4 84.9)
		(width 0.2)
		(layer "F.Cu")
		(net 78)
	)
	(segment
		(start 123.7825 149.2175)
		(end 124.22 148.78)
		(width 0.125)
		(layer "F.Cu")
		(net 78)
	)
	(segment
		(start 142.539 150.579)
		(end 141.9395 149.9795)
		(width 0.125)
		(layer "F.Cu")
		(net 78)
	)
	(segment
		(start 204.45 76.643553)
		(end 204.45 83.85)
		(width 0.2)
		(layer "F.Cu")
		(net 78)
	)
	(segment
		(start 142.539 148.616)
		(end 142.377 148.778)
		(width 0.3)
		(layer "F.Cu")
		(net 78)
	)
	(segment
		(start 203.4 84.9)
		(end 199.55 84.9)
		(width 0.2)
		(layer "F.Cu")
		(net 78)
	)
	(segment
		(start 124.382 147.112)
		(end 124.382 148.618)
		(width 0.3)
		(layer "F.Cu")
		(net 78)
	)
	(segment
		(start 124.382 151.411)
		(end 124.382 150.581)
		(width 0.125)
		(layer "F.Cu")
		(net 78)
	)
	(segment
		(start 203.60861 75.802163)
		(end 204.45 76.643553)
		(width 0.2)
		(layer "F.Cu")
		(net 78)
	)
	(segment
		(start 142.539 151.409)
		(end 142.539 150.579)
		(width 0.125)
		(layer "F.Cu")
		(net 78)
	)
	(segment
		(start 124.382 150.581)
		(end 123.7825 149.9815)
		(width 0.125)
		(layer "F.Cu")
		(net 78)
	)
	(segment
		(start 199.55 84.9)
		(end 199.01 84.36)
		(width 0.2)
		(layer "F.Cu")
		(net 78)
	)
	(segment
		(start 141.9395 149.2155)
		(end 142.377 148.778)
		(width 0.125)
		(layer "F.Cu")
		(net 78)
	)
	(segment
		(start 200.60861 72.802163)
		(end 199.70861 72.802163)
		(width 0.2)
		(layer "F.Cu")
		(net 78)
	)
	(segment
		(start 199.01 84.36)
		(end 199.01 83.38)
		(width 0.2)
		(layer "F.Cu")
		(net 78)
	)
	(segment
		(start 141.9395 149.9795)
		(end 141.9395 149.2155)
		(width 0.125)
		(layer "F.Cu")
		(net 78)
	)
	(via
		(at 147.45 133.86)
		(size 0.45)
		(drill 0.1)
		(layers "F.Cu" "B.Cu")
		(remove_unused_layers yes)
		(keep_end_layers yes)
		(zone_layer_connections "In3.Cu")
		(teardrops
			(best_length_ratio 0.4)
			(max_length 1)
			(best_width_ratio 0.9)
			(max_width 2)
			(curved_edges yes)
			(filter_ratio 0.9)
			(enabled yes)
			(allow_two_segments yes)
			(prefer_zone_connections yes)
		)
		(net 78)
	)
	(via
		(at 301.038 134.879)
		(size 0.45)
		(drill 0.1)
		(layers "F.Cu" "B.Cu")
		(remove_unused_layers yes)
		(keep_end_layers yes)
		(free yes)
		(zone_layer_connections "In3.Cu")
		(teardrops
			(best_length_ratio 0.4)
			(max_length 1)
			(best_width_ratio 0.9)
			(max_width 2)
			(curved_edges yes)
			(filter_ratio 0.9)
			(enabled yes)
			(allow_two_segments yes)
			(prefer_zone_connections yes)
		)
		(net 78)
	)
	(via
		(at 301.038 136.879)
		(size 0.45)
		(drill 0.1)
		(layers "F.Cu" "B.Cu")
		(remove_unused_layers yes)
		(keep_end_layers yes)
		(free yes)
		(zone_layer_connections "In3.Cu")
		(teardrops
			(best_length_ratio 0.4)
			(max_length 1)
			(best_width_ratio 0.9)
			(max_width 2)
			(curved_edges yes)
			(filter_ratio 0.9)
			(enabled yes)
			(allow_two_segments yes)
			(prefer_zone_connections yes)
		)
		(net 78)
	)
	(via
		(at 200.60861 72.802163)
		(size 0.45)
		(drill 0.1)
		(layers "F.Cu" "B.Cu")
		(remove_unused_layers yes)
		(keep_end_layers yes)
		(zone_layer_connections "In5.Cu")
		(teardrops
			(best_length_ratio 0.4)
			(max_length 1)
			(best_width_ratio 0.9)
			(max_width 2)
			(curved_edges yes)
			(filter_ratio 0.9)
			(enabled yes)
			(allow_two_segments yes)
			(prefer_zone_connections yes)
		)
		(net 78)
	)
	(via
		(at 124.36 134.88)
		(size 0.45)
		(drill 0.1)
		(layers "F.Cu" "B.Cu")
		(remove_unused_layers yes)
		(keep_end_layers yes)
		(zone_layer_connections "In3.Cu")
		(teardrops
			(best_length_ratio 0.4)
			(max_length 1)
			(best_width_ratio 0.9)
			(max_width 2)
			(curved_edges yes)
			(filter_ratio 0.9)
			(enabled yes)
			(allow_two_segments yes)
			(prefer_zone_connections yes)
		)
		(net 78)
	)
	(via
		(at 154.45 133.86)
		(size 0.45)
		(drill 0.1)
		(layers "F.Cu" "B.Cu")
		(remove_unused_layers yes)
		(keep_end_layers yes)
		(zone_layer_connections "In3.Cu")
		(teardrops
			(best_length_ratio 0.4)
			(max_length 1)
			(best_width_ratio 0.9)
			(max_width 2)
			(curved_edges yes)
			(filter_ratio 0.9)
			(enabled yes)
			(allow_two_segments yes)
			(prefer_zone_connections yes)
		)
		(net 78)
	)
	(via
		(at 203.60861 75.802163)
		(size 0.45)
		(drill 0.1)
		(layers "F.Cu" "B.Cu")
		(remove_unused_layers yes)
		(keep_end_layers yes)
		(zone_layer_connections "In5.Cu")
		(teardrops
			(best_length_ratio 0.4)
			(max_length 1)
			(best_width_ratio 0.9)
			(max_width 2)
			(curved_edges yes)
			(filter_ratio 0.9)
			(enabled yes)
			(allow_two_segments yes)
			(prefer_zone_connections yes)
		)
		(net 78)
	)
	(via
		(at 300.038001 135.879)
		(size 0.45)
		(drill 0.1)
		(layers "F.Cu" "B.Cu")
		(remove_unused_layers yes)
		(keep_end_layers yes)
		(free yes)
		(zone_layer_connections "In3.Cu")
		(teardrops
			(best_length_ratio 0.4)
			(max_length 1)
			(best_width_ratio 0.9)
			(max_width 2)
			(curved_edges yes)
			(filter_ratio 0.9)
			(enabled yes)
			(allow_two_segments yes)
			(prefer_zone_connections yes)
		)
		(net 78)
	)
	(via
		(at 130.29 141.86)
		(size 0.45)
		(drill 0.1)
		(layers "F.Cu" "B.Cu")
		(remove_unused_layers yes)
		(keep_end_layers yes)
		(zone_layer_connections "In3.Cu")
		(teardrops
			(best_length_ratio 0.4)
			(max_length 1)
			(best_width_ratio 0.9)
			(max_width 2)
			(curved_edges yes)
			(filter_ratio 0.9)
			(enabled yes)
			(allow_two_segments yes)
			(prefer_zone_connections yes)
		)
		(net 78)
	)
	(via
		(at 134.29 141.86)
		(size 0.45)
		(drill 0.1)
		(layers "F.Cu" "B.Cu")
		(remove_unused_layers yes)
		(keep_end_layers yes)
		(zone_layer_connections "In3.Cu")
		(teardrops
			(best_length_ratio 0.4)
			(max_length 1)
			(best_width_ratio 0.9)
			(max_width 2)
			(curved_edges yes)
			(filter_ratio 0.9)
			(enabled yes)
			(allow_two_segments yes)
			(prefer_zone_connections yes)
		)
		(net 78)
	)
	(via
		(at 158.38 140.36)
		(size 0.45)
		(drill 0.1)
		(layers "F.Cu" "B.Cu")
		(remove_unused_layers yes)
		(keep_end_layers yes)
		(zone_layer_connections "In3.Cu")
		(teardrops
			(best_length_ratio 0.4)
			(max_length 1)
			(best_width_ratio 0.9)
			(max_width 2)
			(curved_edges yes)
			(filter_ratio 0.9)
			(enabled yes)
			(allow_two_segments yes)
			(prefer_zone_connections yes)
		)
		(net 78)
	)
	(via
		(at 152.45 141.86)
		(size 0.45)
		(drill 0.1)
		(layers "F.Cu" "B.Cu")
		(remove_unused_layers yes)
		(keep_end_layers yes)
		(zone_layer_connections "In3.Cu")
		(teardrops
			(best_length_ratio 0.4)
			(max_length 1)
			(best_width_ratio 0.9)
			(max_width 2)
			(curved_edges yes)
			(filter_ratio 0.9)
			(enabled yes)
			(allow_two_segments yes)
			(prefer_zone_connections yes)
		)
		(net 78)
	)
	(via
		(at 148.45 141.86)
		(size 0.45)
		(drill 0.1)
		(layers "F.Cu" "B.Cu")
		(remove_unused_layers yes)
		(keep_end_layers yes)
		(zone_layer_connections "In3.Cu")
		(teardrops
			(best_length_ratio 0.4)
			(max_length 1)
			(best_width_ratio 0.9)
			(max_width 2)
			(curved_edges yes)
			(filter_ratio 0.9)
			(enabled yes)
			(allow_two_segments yes)
			(prefer_zone_connections yes)
		)
		(net 78)
	)
	(via
		(at 136.29 133.86)
		(size 0.45)
		(drill 0.1)
		(layers "F.Cu" "B.Cu")
		(remove_unused_layers yes)
		(keep_end_layers yes)
		(zone_layer_connections "In3.Cu")
		(teardrops
			(best_length_ratio 0.4)
			(max_length 1)
			(best_width_ratio 0.9)
			(max_width 2)
			(curved_edges yes)
			(filter_ratio 0.9)
			(enabled yes)
			(allow_two_segments yes)
			(prefer_zone_connections yes)
		)
		(net 78)
	)
	(via
		(at 301.037999 135.879)
		(size 0.45)
		(drill 0.1)
		(layers "F.Cu" "B.Cu")
		(remove_unused_layers yes)
		(keep_end_layers yes)
		(free yes)
		(zone_layer_connections "In3.Cu")
		(teardrops
			(best_length_ratio 0.4)
			(max_length 1)
			(best_width_ratio 0.9)
			(max_width 2)
			(curved_edges yes)
			(filter_ratio 0.9)
			(enabled yes)
			(allow_two_segments yes)
			(prefer_zone_connections yes)
		)
		(net 78)
	)
	(via
		(at 129.29 133.86)
		(size 0.45)
		(drill 0.1)
		(layers "F.Cu" "B.Cu")
		(remove_unused_layers yes)
		(keep_end_layers yes)
		(zone_layer_connections "In3.Cu")
		(teardrops
			(best_length_ratio 0.4)
			(max_length 1)
			(best_width_ratio 0.9)
			(max_width 2)
			(curved_edges yes)
			(filter_ratio 0.9)
			(enabled yes)
			(allow_two_segments yes)
			(prefer_zone_connections yes)
		)
		(net 78)
	)
	(via
		(at 302.038001 136.879)
		(size 0.45)
		(drill 0.1)
		(layers "F.Cu" "B.Cu")
		(remove_unused_layers yes)
		(keep_end_layers yes)
		(free yes)
		(zone_layer_connections "In3.Cu")
		(teardrops
			(best_length_ratio 0.4)
			(max_length 1)
			(best_width_ratio 0.9)
			(max_width 2)
			(curved_edges yes)
			(filter_ratio 0.9)
			(enabled yes)
			(allow_two_segments yes)
			(prefer_zone_connections yes)
		)
		(net 78)
	)
	(via
		(at 142.52 134.88)
		(size 0.45)
		(drill 0.1)
		(layers "F.Cu" "B.Cu")
		(remove_unused_layers yes)
		(keep_end_layers yes)
		(zone_layer_connections "In3.Cu")
		(teardrops
			(best_length_ratio 0.4)
			(max_length 1)
			(best_width_ratio 0.9)
			(max_width 2)
			(curved_edges yes)
			(filter_ratio 0.9)
			(enabled yes)
			(allow_two_segments yes)
			(prefer_zone_connections yes)
		)
		(net 78)
	)
	(via
		(at 142.377 148.778)
		(size 0.45)
		(drill 0.1)
		(layers "F.Cu" "B.Cu")
		(remove_unused_layers yes)
		(keep_end_layers yes)
		(zone_layer_connections "In3.Cu")
		(teardrops
			(best_length_ratio 0.4)
			(max_length 1)
			(best_width_ratio 0.9)
			(max_width 2)
			(curved_edges yes)
			(filter_ratio 0.9)
			(enabled yes)
			(allow_two_segments yes)
			(prefer_zone_connections yes)
		)
		(net 78)
	)
	(via
		(at 124.22 148.78)
		(size 0.45)
		(drill 0.1)
		(layers "F.Cu" "B.Cu")
		(remove_unused_layers yes)
		(keep_end_layers yes)
		(zone_layer_connections "In3.Cu")
		(teardrops
			(best_length_ratio 0.4)
			(max_length 1)
			(best_width_ratio 0.9)
			(max_width 2)
			(curved_edges yes)
			(filter_ratio 0.9)
			(enabled yes)
			(allow_two_segments yes)
			(prefer_zone_connections yes)
		)
		(net 78)
	)
	(via
		(at 300.038002 136.879)
		(size 0.45)
		(drill 0.1)
		(layers "F.Cu" "B.Cu")
		(remove_unused_layers yes)
		(keep_end_layers yes)
		(free yes)
		(zone_layer_connections "In3.Cu")
		(teardrops
			(best_length_ratio 0.4)
			(max_length 1)
			(best_width_ratio 0.9)
			(max_width 2)
			(curved_edges yes)
			(filter_ratio 0.9)
			(enabled yes)
			(allow_two_segments yes)
			(prefer_zone_connections yes)
		)
		(net 78)
	)
	(via
		(at 252.189852 89.355693)
		(size 0.45)
		(drill 0.1)
		(layers "F.Cu" "B.Cu")
		(remove_unused_layers yes)
		(keep_end_layers yes)
		(zone_layer_connections "In5.Cu")
		(teardrops
			(best_length_ratio 0.4)
			(max_length 1)
			(best_width_ratio 0.9)
			(max_width 2)
			(curved_edges yes)
			(filter_ratio 0.9)
			(enabled yes)
			(allow_two_segments yes)
			(prefer_zone_connections yes)
		)
		(net 78)
	)
	(via
		(at 140.22 140.36)
		(size 0.45)
		(drill 0.1)
		(layers "F.Cu" "B.Cu")
		(remove_unused_layers yes)
		(keep_end_layers yes)
		(zone_layer_connections "In3.Cu")
		(teardrops
			(best_length_ratio 0.4)
			(max_length 1)
			(best_width_ratio 0.9)
			(max_width 2)
			(curved_edges yes)
			(filter_ratio 0.9)
			(enabled yes)
			(allow_two_segments yes)
			(prefer_zone_connections yes)
		)
		(net 78)
	)
	(via
		(at 300.038 134.879)
		(size 0.45)
		(drill 0.1)
		(layers "F.Cu" "B.Cu")
		(remove_unused_layers yes)
		(keep_end_layers yes)
		(free yes)
		(zone_layer_connections "In3.Cu")
		(teardrops
			(best_length_ratio 0.4)
			(max_length 1)
			(best_width_ratio 0.9)
			(max_width 2)
			(curved_edges yes)
			(filter_ratio 0.9)
			(enabled yes)
			(allow_two_segments yes)
			(prefer_zone_connections yes)
		)
		(net 78)
	)
	(via
		(at 302.038 135.879)
		(size 0.45)
		(drill 0.1)
		(layers "F.Cu" "B.Cu")
		(remove_unused_layers yes)
		(keep_end_layers yes)
		(free yes)
		(zone_layer_connections "In3.Cu")
		(teardrops
			(best_length_ratio 0.4)
			(max_length 1)
			(best_width_ratio 0.9)
			(max_width 2)
			(curved_edges yes)
			(filter_ratio 0.9)
			(enabled yes)
			(allow_two_segments yes)
			(prefer_zone_connections yes)
		)
		(net 78)
	)
	(via
		(at 302.038 134.879)
		(size 0.45)
		(drill 0.1)
		(layers "F.Cu" "B.Cu")
		(remove_unused_layers yes)
		(keep_end_layers yes)
		(free yes)
		(zone_layer_connections "In3.Cu" "In5.Cu")
		(teardrops
			(best_length_ratio 0.4)
			(max_length 1)
			(best_width_ratio 0.9)
			(max_width 2)
			(curved_edges yes)
			(filter_ratio 0.9)
			(enabled yes)
			(allow_two_segments yes)
			(prefer_zone_connections yes)
		)
		(net 78)
	)
	(segment
		(start 158.38 139.36)
		(end 158.38 140.36)
		(width 0.125)
		(layer "B.Cu")
		(net 78)
	)
	(segment
		(start 129.29 132.898)
		(end 129.29 133.86)
		(width 0.5)
		(layer "B.Cu")
		(net 78)
	)
	(segment
		(start 143.77 137.06)
		(end 143.77 136.06)
		(width 0.125)
		(layer "B.Cu")
		(net 78)
	)
	(segment
		(start 140.22 141.36)
		(end 140.22 140.36)
		(width 0.125)
		(layer "B.Cu")
		(net 78)
	)
	(segment
		(start 143.77 136.06)
		(end 143.77 135.64)
		(width 0.125)
		(layer "B.Cu")
		(net 78)
	)
	(segment
		(start 125.61 137.06)
		(end 125.61 136.06)
		(width 0.125)
		(layer "B.Cu")
		(net 78)
	)
	(segment
		(start 148.38 133.87)
		(end 147.46 133.87)
		(width 0.125)
		(layer "B.Cu")
		(net 78)
	)
	(segment
		(start 147.43 132.908)
		(end 147.43 133.87)
		(width 0.5)
		(layer "B.Cu")
		(net 78)
	)
	(segment
		(start 158.38 140.36)
		(end 158.38 141.36)
		(width 0.125)
		(layer "B.Cu")
		(net 78)
	)
	(segment
		(start 143.01 134.88)
		(end 142.52 134.88)
		(width 0.125)
		(layer "B.Cu")
		(net 78)
	)
	(segment
		(start 143.77 135.64)
		(end 143.01 134.88)
		(width 0.125)
		(layer "B.Cu")
		(net 78)
	)
	(segment
		(start 307.464999 122.44)
		(end 307.464999 127.595001)
		(width 0.2)
		(layer "B.Cu")
		(net 78)
	)
	(segment
		(start 125.61 136.06)
		(end 125.61 135.64)
		(width 0.125)
		(layer "B.Cu")
		(net 78)
	)
	(segment
		(start 125.61 135.64)
		(end 124.85 134.88)
		(width 0.125)
		(layer "B.Cu")
		(net 78)
	)
	(segment
		(start 124.85 134.88)
		(end 124.36 134.88)
		(width 0.125)
		(layer "B.Cu")
		(net 78)
	)
	(segment
		(start 130.22 133.87)
		(end 129.27 133.87)
		(width 0.125)
		(layer "B.Cu")
		(net 78)
	)
	(segment
		(start 140.22 140.36)
		(end 140.22 139.36)
		(width 0.125)
		(layer "B.Cu")
		(net 78)
	)
	(segment
		(start 307.464999 127.595001)
		(end 302.038 133.022)
		(width 0.2)
		(layer "B.Cu")
		(net 78)
	)
	(segment
		(start 302.038 133.022)
		(end 302.038 134.879)
		(width 0.2)
		(layer "B.Cu")
		(net 78)
	)
	(segment
		(start 296.99 87.5)
		(end 304.95 95.46)
		(width 0.2)
		(layer "In5.Cu")
		(net 78)
	)
	(segment
		(start 252.189852 89.355693)
		(end 256.754307 89.355693)
		(width 0.2)
		(layer "In5.Cu")
		(net 78)
	)
	(segment
		(start 304.95 95.46)
		(end 304.95 111.46)
		(width 0.2)
		(layer "In5.Cu")
		(net 78)
	)
	(segment
		(start 301.55 114.86)
		(end 301.55 134.391)
		(width 0.2)
		(layer "In5.Cu")
		(net 78)
	)
	(segment
		(start 222.242163 75.802163)
		(end 203.60861 75.802163)
		(width 0.2)
		(layer "In5.Cu")
		(net 78)
	)
	(segment
		(start 304.95 111.46)
		(end 301.55 114.86)
		(width 0.2)
		(layer "In5.Cu")
		(net 78)
	)
	(segment
		(start 256.754307 89.355693)
		(end 258.61 87.5)
		(width 0.2)
		(layer "In5.Cu")
		(net 78)
	)
	(segment
		(start 237.345693 89.355693)
		(end 230.6 82.61)
		(width 0.2)
		(layer "In5.Cu")
		(net 78)
	)
	(segment
		(start 252.189852 89.355693)
		(end 237.345693 89.355693)
		(width 0.2)
		(layer "In5.Cu")
		(net 78)
	)
	(segment
		(start 258.61 87.5)
		(end 296.99 87.5)
		(width 0.2)
		(layer "In5.Cu")
		(net 78)
	)
	(segment
		(start 301.55 134.391)
		(end 302.038 134.879)
		(width 0.2)
		(layer "In5.Cu")
		(net 78)
	)
	(segment
		(start 229.05 82.61)
		(end 222.242163 75.802163)
		(width 0.2)
		(layer "In5.Cu")
		(net 78)
	)
	(segment
		(start 230.6 82.61)
		(end 229.05 82.61)
		(width 0.2)
		(layer "In5.Cu")
		(net 78)
	)
	(segment
		(start 203.60861 75.802163)
		(end 200.60861 72.802163)
		(width 0.2)
		(layer "In5.Cu")
		(net 78)
	)
	(segment
		(start 261.54 87.469999)
		(end 261.959999 87.469999)
		(width 0.3)
		(layer "F.Cu")
		(net 80)
	)
	(segment
		(start 259.98 87.639999)
		(end 261.37 87.639999)
		(width 0.3)
		(layer "F.Cu")
		(net 80)
	)
	(segment
		(start 262.778 91.485)
		(end 263.25 91.957001)
		(width 0.3)
		(layer "F.Cu")
		(net 80)
	)
	(segment
		(start 262.3 87.81)
		(end 262.3 89.86)
		(width 0.3)
		(layer "F.Cu")
		(net 80)
	)
	(segment
		(start 261.959999 87.469999)
		(end 262.3 87.81)
		(width 0.3)
		(layer "F.Cu")
		(net 80)
	)
	(segment
		(start 262.3 89.86)
		(end 261.35 90.81)
		(width 0.3)
		(layer "F.Cu")
		(net 80)
	)
	(segment
		(start 261.37 87.639999)
		(end 261.54 87.469999)
		(width 0.3)
		(layer "F.Cu")
		(net 80)
	)
	(segment
		(start 261.35 90.81)
		(end 261.35 91.485)
		(width 0.3)
		(layer "F.Cu")
		(net 80)
	)
	(segment
		(start 261.35 91.485)
		(end 262.778 91.485)
		(width 0.3)
		(layer "F.Cu")
		(net 80)
	)
	(via
		(at 296.75 143.76)
		(size 0.45)
		(drill 0.1)
		(layers "F.Cu" "B.Cu")
		(remove_unused_layers yes)
		(keep_end_layers yes)
		(free yes)
		(zone_layer_connections "In2.Cu")
		(teardrops
			(best_length_ratio 0.4)
			(max_length 1)
			(best_width_ratio 0.9)
			(max_width 2)
			(curved_edges yes)
			(filter_ratio 0.9)
			(enabled yes)
			(allow_two_segments yes)
			(prefer_zone_connections yes)
		)
		(net 81)
	)
	(via
		(at 296.750001 142.76)
		(size 0.45)
		(drill 0.1)
		(layers "F.Cu" "B.Cu")
		(remove_unused_layers yes)
		(keep_end_layers yes)
		(free yes)
		(zone_layer_connections "In2.Cu")
		(teardrops
			(best_length_ratio 0.4)
			(max_length 1)
			(best_width_ratio 0.9)
			(max_width 2)
			(curved_edges yes)
			(filter_ratio 0.9)
			(enabled yes)
			(allow_two_segments yes)
			(prefer_zone_connections yes)
		)
		(net 81)
	)
	(via
		(at 296.75 141.76)
		(size 0.45)
		(drill 0.1)
		(layers "F.Cu" "B.Cu")
		(remove_unused_layers yes)
		(keep_end_layers yes)
		(free yes)
		(zone_layer_connections "In2.Cu")
		(teardrops
			(best_length_ratio 0.4)
			(max_length 1)
			(best_width_ratio 0.9)
			(max_width 2)
			(curved_edges yes)
			(filter_ratio 0.9)
			(enabled yes)
			(allow_two_segments yes)
			(prefer_zone_connections yes)
		)
		(net 81)
	)
	(via
		(at 297.75 140.76)
		(size 0.45)
		(drill 0.1)
		(layers "F.Cu" "B.Cu")
		(remove_unused_layers yes)
		(keep_end_layers yes)
		(free yes)
		(zone_layer_connections "In2.Cu")
		(teardrops
			(best_length_ratio 0.4)
			(max_length 1)
			(best_width_ratio 0.9)
			(max_width 2)
			(curved_edges yes)
			(filter_ratio 0.9)
			(enabled yes)
			(allow_two_segments yes)
			(prefer_zone_connections yes)
		)
		(net 81)
	)
	(via
		(at 297.75 143.76)
		(size 0.45)
		(drill 0.1)
		(layers "F.Cu" "B.Cu")
		(remove_unused_layers yes)
		(keep_end_layers yes)
		(free yes)
		(zone_layer_connections "In2.Cu")
		(teardrops
			(best_length_ratio 0.4)
			(max_length 1)
			(best_width_ratio 0.9)
			(max_width 2)
			(curved_edges yes)
			(filter_ratio 0.9)
			(enabled yes)
			(allow_two_segments yes)
			(prefer_zone_connections yes)
		)
		(net 81)
	)
	(via
		(at 297.749999 142.76)
		(size 0.45)
		(drill 0.1)
		(layers "F.Cu" "B.Cu")
		(remove_unused_layers yes)
		(keep_end_layers yes)
		(free yes)
		(zone_layer_connections "In2.Cu")
		(teardrops
			(best_length_ratio 0.4)
			(max_length 1)
			(best_width_ratio 0.9)
			(max_width 2)
			(curved_edges yes)
			(filter_ratio 0.9)
			(enabled yes)
			(allow_two_segments yes)
			(prefer_zone_connections yes)
		)
		(net 81)
	)
	(via
		(at 296.75 140.76)
		(size 0.45)
		(drill 0.1)
		(layers "F.Cu" "B.Cu")
		(remove_unused_layers yes)
		(keep_end_layers yes)
		(free yes)
		(zone_layer_connections "In2.Cu")
		(teardrops
			(best_length_ratio 0.4)
			(max_length 1)
			(best_width_ratio 0.9)
			(max_width 2)
			(curved_edges yes)
			(filter_ratio 0.9)
			(enabled yes)
			(allow_two_segments yes)
			(prefer_zone_connections yes)
		)
		(net 81)
	)
	(via
		(at 297.75 141.76)
		(size 0.45)
		(drill 0.1)
		(layers "F.Cu" "B.Cu")
		(remove_unused_layers yes)
		(keep_end_layers yes)
		(free yes)
		(zone_layer_connections "In2.Cu")
		(teardrops
			(best_length_ratio 0.4)
			(max_length 1)
			(best_width_ratio 0.9)
			(max_width 2)
			(curved_edges yes)
			(filter_ratio 0.9)
			(enabled yes)
			(allow_two_segments yes)
			(prefer_zone_connections yes)
		)
		(net 81)
	)
	(segment
		(start 236.240707 73.504999)
		(end 236.240707 71.86)
		(width 0.5)
		(layer "B.Cu")
		(net 81)
	)
	(segment
		(start 263.700708 73.504999)
		(end 263.700708 71.86)
		(width 0.5)
		(layer "B.Cu")
		(net 81)
	)
	(segment
		(start 249.970709 73.504999)
		(end 249.970709 71.86)
		(width 0.5)
		(layer "B.Cu")
		(net 81)
	)
	(segment
		(start 236.795708 74.06)
		(end 236.240707 73.504999)
		(width 0.5)
		(layer "B.Cu")
		(net 81)
	)
	(segment
		(start 264.255709 74.06)
		(end 263.700708 73.504999)
		(width 0.5)
		(layer "B.Cu")
		(net 81)
	)
	(segment
		(start 250.52571 74.06)
		(end 249.970709 73.504999)
		(width 0.5)
		(layer "B.Cu")
		(net 81)
	)
	(segment
		(start 258.325 126.221748)
		(end 257.187748 126.221748)
		(width 0.125)
		(layer "F.Cu")
		(net 82)
	)
	(segment
		(start 207.18 112.53)
		(end 207.75 113.1)
		(width 0.125)
		(layer "F.Cu")
		(net 83)
	)
	(segment
		(start 207.75 113.1)
		(end 224.28 113.1)
		(width 0.125)
		(layer "F.Cu")
		(net 83)
	)
	(segment
		(start 207.18 99.98)
		(end 207.18 112.53)
		(width 0.125)
		(layer "F.Cu")
		(net 83)
	)
	(segment
		(start 224.28 113.1)
		(end 235.5 124.32)
		(width 0.125)
		(layer "F.Cu")
		(net 83)
	)
	(segment
		(start 180.709 70.61)
		(end 180.709 73.509)
		(width 0.125)
		(layer "F.Cu")
		(net 83)
	)
	(segment
		(start 235.5 124.32)
		(end 246.09 124.32)
		(width 0.125)
		(layer "F.Cu")
		(net 83)
	)
	(segment
		(start 180.709 73.509)
		(end 207.18 99.98)
		(width 0.125)
		(layer "F.Cu")
		(net 83)
	)
	(segment
		(start 246.09 124.32)
		(end 248.9305 127.1605)
		(width 0.125)
		(layer "F.Cu")
		(net 83)
	)
	(segment
		(start 248.9305 127.1605)
		(end 249.8 127.1605)
		(width 0.125)
		(layer "F.Cu")
		(net 83)
	)
	(segment
		(start 223.15 124.91)
		(end 225.9 124.91)
		(width 0.125)
		(layer "F.Cu")
		(net 84)
	)
	(segment
		(start 245.68 129.46)
		(end 246.35 128.79)
		(width 0.125)
		(layer "F.Cu")
		(net 84)
	)
	(segment
		(start 248.374 128.789999)
		(end 247.374 128.79)
		(width 0.125)
		(layer "F.Cu")
		(net 84)
	)
	(segment
		(start 237.47 129.46)
		(end 239.26 129.46)
		(width 0.125)
		(layer "F.Cu")
		(net 84)
	)
	(segment
		(start 230.45 129.46)
		(end 237.47 129.46)
		(width 0.125)
		(layer "F.Cu")
		(net 84)
	)
	(segment
		(start 239.37 129.46)
		(end 239.359 129.449)
		(width 0.125)
		(layer "F.Cu")
		(net 84)
	)
	(segment
		(start 247.350001 128.790001)
		(end 246.35 128.79)
		(width 0.125)
		(layer "F.Cu")
		(net 84)
	)
	(segment
		(start 239.359 129.449)
		(end 239.359 128.59)
		(width 0.125)
		(layer "F.Cu")
		(net 84)
	)
	(segment
		(start 237.459 129.449)
		(end 237.459 128.59)
		(width 0.125)
		(layer "F.Cu")
		(net 84)
	)
	(segment
		(start 239.26 129.46)
		(end 239.37 129.46)
		(width 0.125)
		(layer "F.Cu")
		(net 84)
	)
	(segment
		(start 225.9 124.91)
		(end 230.45 129.46)
		(width 0.125)
		(layer "F.Cu")
		(net 84)
	)
	(segment
		(start 244.377 129.46)
		(end 244.377 127.959)
		(width 0.125)
		(layer "F.Cu")
		(net 84)
	)
	(segment
		(start 239.26 129.46)
		(end 245.68 129.46)
		(width 0.125)
		(layer "F.Cu")
		(net 84)
	)
	(segment
		(start 237.47 129.46)
		(end 237.459 129.449)
		(width 0.125)
		(layer "F.Cu")
		(net 84)
	)
	(via
		(at 181.75 84.9)
		(size 0.45)
		(drill 0.1)
		(layers "F.Cu" "B.Cu")
		(teardrops
			(best_length_ratio 0.4)
			(max_length 1)
			(best_width_ratio 0.9)
			(max_width 2)
			(curved_edges yes)
			(filter_ratio 0.9)
			(enabled yes)
			(allow_two_segments yes)
			(prefer_zone_connections yes)
		)
		(net 84)
	)
	(via
		(at 223.15 124.91)
		(size 0.45)
		(drill 0.1)
		(layers "F.Cu" "B.Cu")
		(remove_unused_layers yes)
		(keep_end_layers yes)
		(zone_layer_connections "In5.Cu")
		(teardrops
			(best_length_ratio 0.4)
			(max_length 1)
			(best_width_ratio 0.9)
			(max_width 2)
			(curved_edges yes)
			(filter_ratio 0.9)
			(enabled yes)
			(allow_two_segments yes)
			(prefer_zone_connections yes)
		)
		(net 84)
	)
	(segment
		(start 118.325 115.275)
		(end 130.625 115.275)
		(width 0.125)
		(layer "B.Cu")
		(net 84)
	)
	(segment
		(start 174.6 84.9)
		(end 181.75 84.9)
		(width 0.125)
		(layer "B.Cu")
		(net 84)
	)
	(segment
		(start 130.625 115.275)
		(end 133.5 112.4)
		(width 0.125)
		(layer "B.Cu")
		(net 84)
	)
	(segment
		(start 104.9 117.41)
		(end 116.19 117.41)
		(width 0.125)
		(layer "B.Cu")
		(net 84)
	)
	(segment
		(start 159.85 99.65)
		(end 174.6 84.9)
		(width 0.125)
		(layer "B.Cu")
		(net 84)
	)
	(segment
		(start 98.398 120.658)
		(end 98.398 119.71)
		(width 0.3)
		(layer "B.Cu")
		(net 84)
	)
	(segment
		(start 135.65 99.65)
		(end 159.85 99.65)
		(width 0.125)
		(layer "B.Cu")
		(net 84)
	)
	(segment
		(start 133.5 101.8)
		(end 135.65 99.65)
		(width 0.125)
		(layer "B.Cu")
		(net 84)
	)
	(segment
		(start 99.699 121.31)
		(end 99.05 121.31)
		(width 0.3)
		(layer "B.Cu")
		(net 84)
	)
	(segment
		(start 99.699 121.31)
		(end 101 121.31)
		(width 0.125)
		(layer "B.Cu")
		(net 84)
	)
	(segment
		(start 99.05 121.31)
		(end 98.398 120.658)
		(width 0.3)
		(layer "B.Cu")
		(net 84)
	)
	(segment
		(start 116.19 117.41)
		(end 118.325 115.275)
		(width 0.125)
		(layer "B.Cu")
		(net 84)
	)
	(segment
		(start 133.5 112.4)
		(end 133.5 101.8)
		(width 0.125)
		(layer "B.Cu")
		(net 84)
	)
	(segment
		(start 101 121.31)
		(end 104.9 117.41)
		(width 0.125)
		(layer "B.Cu")
		(net 84)
	)
	(segment
		(start 200.55 123.4)
		(end 198.5 121.35)
		(width 0.125)
		(layer "In5.Cu")
		(net 84)
	)
	(segment
		(start 202.25 123.4)
		(end 200.55 123.4)
		(width 0.125)
		(layer "In5.Cu")
		(net 84)
	)
	(segment
		(start 206.75 118.9)
		(end 202.25 123.4)
		(width 0.125)
		(layer "In5.Cu")
		(net 84)
	)
	(segment
		(start 219.75 123.55)
		(end 219.75 122.1)
		(width 0.125)
		(layer "In5.Cu")
		(net 84)
	)
	(segment
		(start 219.75 122.1)
		(end 216.55 118.9)
		(width 0.125)
		(layer "In5.Cu")
		(net 84)
	)
	(segment
		(start 216.55 118.9)
		(end 206.75 118.9)
		(width 0.125)
		(layer "In5.Cu")
		(net 84)
	)
	(segment
		(start 183.45 84.9)
		(end 181.75 84.9)
		(width 0.125)
		(layer "In5.Cu")
		(net 84)
	)
	(segment
		(start 223.15 124.91)
		(end 221.11 124.91)
		(width 0.125)
		(layer "In5.Cu")
		(net 84)
	)
	(segment
		(start 198.5 121.35)
		(end 198.5 99.95)
		(width 0.125)
		(layer "In5.Cu")
		(net 84)
	)
	(segment
		(start 198.5 99.95)
		(end 183.45 84.9)
		(width 0.125)
		(layer "In5.Cu")
		(net 84)
	)
	(segment
		(start 221.11 124.91)
		(end 219.75 123.55)
		(width 0.125)
		(layer "In5.Cu")
		(net 84)
	)
	(segment
		(start 252.44 165.53)
		(end 252.44 165.54)
		(width 0.3)
		(layer "F.Cu")
		(net 85)
	)
	(segment
		(start 259.1405 161.5805)
		(end 259.12 161.56)
		(width 0.3)
		(layer "F.Cu")
		(net 85)
	)
	(segment
		(start 260.32 161.5805)
		(end 259.1405 161.5805)
		(width 0.3)
		(layer "F.Cu")
		(net 85)
	)
	(segment
		(start 250.745 163.834999)
		(end 249.322145 163.835)
		(width 0.3)
		(layer "F.Cu")
		(net 85)
	)
	(segment
		(start 252.44 165.54)
		(end 253.2 166.3)
		(width 0.3)
		(layer "F.Cu")
		(net 85)
	)
	(segment
		(start 258.4 165)
		(end 259.12 164.28)
		(width 0.3)
		(layer "F.Cu")
		(net 85)
	)
	(segment
		(start 252.44 165.529999)
		(end 250.745 163.834999)
		(width 0.3)
		(layer "F.Cu")
		(net 85)
	)
	(segment
		(start 254.3 166.3)
		(end 255.6 165)
		(width 0.3)
		(layer "F.Cu")
		(net 85)
	)
	(segment
		(start 259.12 164.28)
		(end 259.12 161.56)
		(width 0.3)
		(layer "F.Cu")
		(net 85)
	)
	(segment
		(start 253.2 166.3)
		(end 254.3 166.3)
		(width 0.3)
		(layer "F.Cu")
		(net 85)
	)
	(segment
		(start 255.6 165)
		(end 258.4 165)
		(width 0.3)
		(layer "F.Cu")
		(net 85)
	)
	(segment
		(start 258.12 161.56)
		(end 259.12 161.56)
		(width 0.3)
		(layer "F.Cu")
		(net 85)
	)
	(segment
		(start 211.525 163.135)
		(end 211.525 164.447501)
		(width 0.202)
		(layer "F.Cu")
		(net 86)
	)
	(segment
		(start 211.4695 164.626)
		(end 211.5935 164.75)
		(width 0.202)
		(layer "F.Cu")
		(net 86)
	)
	(segment
		(start 296.699 74.66)
		(end 296.643 74.716)
		(width 0.202)
		(layer "F.Cu")
		(net 86)
	)
	(segment
		(start 211.525 164.447501)
		(end 211.4695 164.503001)
		(width 0.202)
		(layer "F.Cu")
		(net 86)
	)
	(segment
		(start 296.643 75.263348)
		(end 296.767 75.387348)
		(width 0.202)
		(layer "F.Cu")
		(net 86)
	)
	(segment
		(start 211.4695 164.503001)
		(end 211.4695 164.626)
		(width 0.202)
		(layer "F.Cu")
		(net 86)
	)
	(segment
		(start 296.643 74.716)
		(end 296.643 75.263348)
		(width 0.202)
		(layer "F.Cu")
		(net 86)
	)
	(via
		(at 296.767 75.387348)
		(size 0.45)
		(drill 0.1)
		(layers "F.Cu" "B.Cu")
		(remove_unused_layers yes)
		(keep_end_layers yes)
		(zone_layer_connections)
		(teardrops
			(best_length_ratio 0.4)
			(max_length 1)
			(best_width_ratio 0.9)
			(max_width 2)
			(curved_edges yes)
			(filter_ratio 0.9)
			(enabled yes)
			(allow_two_segments yes)
			(prefer_zone_connections yes)
		)
		(net 86)
	)
	(via
		(at 211.5935 164.75)
		(size 0.45)
		(drill 0.1)
		(layers "F.Cu" "B.Cu")
		(teardrops
			(best_length_ratio 0.4)
			(max_length 1)
			(best_width_ratio 0.9)
			(max_width 2)
			(curved_edges yes)
			(filter_ratio 0.9)
			(enabled yes)
			(allow_two_segments yes)
			(prefer_zone_connections yes)
		)
		(net 86)
	)
	(segment
		(start 293.130566 69.9055)
		(end 276.669434 69.9055)
		(width 0.202)
		(layer "B.Cu")
		(net 86)
	)
	(segment
		(start 212.5055 150.769434)
		(end 212.5055 158.669434)
		(width 0.202)
		(layer "B.Cu")
		(net 86)
	)
	(segment
		(start 213.0055 164.130566)
		(end 213.0055 164.869434)
		(width 0.202)
		(layer "B.Cu")
		(net 86)
	)
	(segment
		(start 211.4695 164.874)
		(end 211.5935 164.75)
		(width 0.202)
		(layer "B.Cu")
		(net 86)
	)
	(segment
		(start 211.1055 162.230566)
		(end 213.0055 164.130566)
		(width 0.202)
		(layer "B.Cu")
		(net 86)
	)
	(segment
		(start 276.669434 69.9055)
		(end 269.7155 76.859434)
		(width 0.202)
		(layer "B.Cu")
		(net 86)
	)
	(segment
		(start 262.419434 141.5555)
		(end 245.130566 141.5555)
		(width 0.202)
		(layer "B.Cu")
		(net 86)
	)
	(segment
		(start 212.569434 165.3055)
		(end 211.880566 165.3055)
		(width 0.202)
		(layer "B.Cu")
		(net 86)
	)
	(segment
		(start 239.130566 135.5555)
		(end 224.069434 135.5555)
		(width 0.202)
		(layer "B.Cu")
		(net 86)
	)
	(segment
		(start 224.069434 135.5555)
		(end 218.6055 141.019434)
		(width 0.202)
		(layer "B.Cu")
		(net 86)
	)
	(segment
		(start 211.880566 165.3055)
		(end 211.4695 164.894434)
		(width 0.202)
		(layer "B.Cu")
		(net 86)
	)
	(segment
		(start 218.6055 141.019434)
		(end 218.6055 144.669434)
		(width 0.202)
		(layer "B.Cu")
		(net 86)
	)
	(segment
		(start 213.0055 164.869434)
		(end 212.569434 165.3055)
		(width 0.202)
		(layer "B.Cu")
		(net 86)
	)
	(segment
		(start 263.1055 134.219434)
		(end 263.1055 140.869434)
		(width 0.202)
		(layer "B.Cu")
		(net 86)
	)
	(segment
		(start 296.643 75.263348)
		(end 296.643 73.417934)
		(width 0.202)
		(layer "B.Cu")
		(net 86)
	)
	(segment
		(start 296.643 73.417934)
		(end 293.130566 69.9055)
		(width 0.202)
		(layer "B.Cu")
		(net 86)
	)
	(segment
		(start 211.1055 160.069434)
		(end 211.1055 162.230566)
		(width 0.202)
		(layer "B.Cu")
		(net 86)
	)
	(segment
		(start 245.130566 141.5555)
		(end 239.130566 135.5555)
		(width 0.202)
		(layer "B.Cu")
		(net 86)
	)
	(segment
		(start 269.7155 76.859434)
		(end 269.7155 127.609434)
		(width 0.202)
		(layer "B.Cu")
		(net 86)
	)
	(segment
		(start 269.7155 127.609434)
		(end 263.1055 134.219434)
		(width 0.202)
		(layer "B.Cu")
		(net 86)
	)
	(segment
		(start 211.4695 164.894434)
		(end 211.4695 164.874)
		(width 0.202)
		(layer "B.Cu")
		(net 86)
	)
	(segment
		(start 212.5055 158.669434)
		(end 211.1055 160.069434)
		(width 0.202)
		(layer "B.Cu")
		(net 86)
	)
	(segment
		(start 263.1055 140.869434)
		(end 262.419434 141.5555)
		(width 0.202)
		(layer "B.Cu")
		(net 86)
	)
	(segment
		(start 296.767 75.387348)
		(end 296.643 75.263348)
		(width 0.202)
		(layer "B.Cu")
		(net 86)
	)
	(segment
		(start 218.6055 144.669434)
		(end 212.5055 150.769434)
		(width 0.202)
		(layer "B.Cu")
		(net 86)
	)
	(segment
		(start 213.025 163.135)
		(end 213.025 162.41)
		(width 0.202)
		(layer "F.Cu")
		(net 87)
	)
	(segment
		(start 212.625214 160.550149)
		(end 212.625214 160.374786)
		(width 0.202)
		(layer "F.Cu")
		(net 87)
	)
	(segment
		(start 212.9695 162.3545)
		(end 212.9695 160.894435)
		(width 0.202)
		(layer "F.Cu")
		(net 87)
	)
	(segment
		(start 293.644 74.716)
		(end 293.644 75.263348)
		(width 0.202)
		(layer "F.Cu")
		(net 87)
	)
	(segment
		(start 212.9695 160.894435)
		(end 212.625214 160.550149)
		(width 0.202)
		(layer "F.Cu")
		(net 87)
	)
	(segment
		(start 213.025 162.41)
		(end 212.9695 162.3545)
		(width 0.202)
		(layer "F.Cu")
		(net 87)
	)
	(segment
		(start 293.644 75.263348)
		(end 293.768 75.387348)
		(width 0.202)
		(layer "F.Cu")
		(net 87)
	)
	(segment
		(start 293.7 74.66)
		(end 293.644 74.716)
		(width 0.202)
		(layer "F.Cu")
		(net 87)
	)
	(via
		(at 212.625214 160.374786)
		(size 0.45)
		(drill 0.1)
		(layers "F.Cu" "B.Cu")
		(teardrops
			(best_length_ratio 0.4)
			(max_length 1)
			(best_width_ratio 0.9)
			(max_width 2)
			(curved_edges yes)
			(filter_ratio 0.9)
			(enabled yes)
			(allow_two_segments yes)
			(prefer_zone_connections yes)
		)
		(net 87)
	)
	(via
		(at 293.768 75.387348)
		(size 0.45)
		(drill 0.1)
		(layers "F.Cu" "B.Cu")
		(remove_unused_layers yes)
		(keep_end_layers yes)
		(zone_layer_connections)
		(teardrops
			(best_length_ratio 0.4)
			(max_length 1)
			(best_width_ratio 0.9)
			(max_width 2)
			(curved_edges yes)
			(filter_ratio 0.9)
			(enabled yes)
			(allow_two_segments yes)
			(prefer_zone_connections yes)
		)
		(net 87)
	)
	(segment
		(start 214.5555 159.569434)
		(end 213.419434 160.7055)
		(width 0.202)
		(layer "B.Cu")
		(net 87)
	)
	(segment
		(start 263.719434 143.6555)
		(end 244.380566 143.6555)
		(width 0.202)
		(layer "B.Cu")
		(net 87)
	)
	(segment
		(start 293.644 72.943934)
		(end 291.780566 71.0805)
		(width 0.202)
		(layer "B.Cu")
		(net 87)
	)
	(segment
		(start 277.344434 71.0805)
		(end 271.2155 77.209434)
		(width 0.202)
		(layer "B.Cu")
		(net 87)
	)
	(segment
		(start 220.5555 141.719434)
		(end 220.5555 145.569434)
		(width 0.202)
		(layer "B.Cu")
		(net 87)
	)
	(segment
		(start 214.5555 151.569434)
		(end 214.5555 159.569434)
		(width 0.202)
		(layer "B.Cu")
		(net 87)
	)
	(segment
		(start 293.644 75.263348)
		(end 293.644 72.943934)
		(width 0.202)
		(layer "B.Cu")
		(net 87)
	)
	(segment
		(start 244.380566 143.6555)
		(end 238.380566 137.6555)
		(width 0.202)
		(layer "B.Cu")
		(net 87)
	)
	(segment
		(start 271.2155 77.209434)
		(end 271.2155 128.709434)
		(width 0.202)
		(layer "B.Cu")
		(net 87)
	)
	(segment
		(start 238.380566 137.6555)
		(end 224.619434 137.6555)
		(width 0.202)
		(layer "B.Cu")
		(net 87)
	)
	(segment
		(start 293.768 75.387348)
		(end 293.644 75.263348)
		(width 0.202)
		(layer "B.Cu")
		(net 87)
	)
	(segment
		(start 213.419434 160.7055)
		(end 212.780565 160.7055)
		(width 0.202)
		(layer "B.Cu")
		(net 87)
	)
	(segment
		(start 271.2155 128.709434)
		(end 264.6555 135.269434)
		(width 0.202)
		(layer "B.Cu")
		(net 87)
	)
	(segment
		(start 264.6555 142.719434)
		(end 263.719434 143.6555)
		(width 0.202)
		(layer "B.Cu")
		(net 87)
	)
	(segment
		(start 220.5555 145.569434)
		(end 214.5555 151.569434)
		(width 0.202)
		(layer "B.Cu")
		(net 87)
	)
	(segment
		(start 212.780565 160.7055)
		(end 212.625214 160.550149)
		(width 0.202)
		(layer "B.Cu")
		(net 87)
	)
	(segment
		(start 224.619434 137.6555)
		(end 220.5555 141.719434)
		(width 0.202)
		(layer "B.Cu")
		(net 87)
	)
	(segment
		(start 291.780566 71.0805)
		(end 277.344434 71.0805)
		(width 0.202)
		(layer "B.Cu")
		(net 87)
	)
	(segment
		(start 212.625214 160.550149)
		(end 212.625214 160.374786)
		(width 0.202)
		(layer "B.Cu")
		(net 87)
	)
	(segment
		(start 264.6555 135.269434)
		(end 264.6555 142.719434)
		(width 0.202)
		(layer "B.Cu")
		(net 87)
	)
	(segment
		(start 214.525 163.135)
		(end 214.525 162.41)
		(width 0.202)
		(layer "F.Cu")
		(net 88)
	)
	(segment
		(start 214.4695 161.624)
		(end 214.5935 161.5)
		(width 0.202)
		(layer "F.Cu")
		(net 88)
	)
	(segment
		(start 290.643 74.716)
		(end 290.643 75.263348)
		(width 0.202)
		(layer "F.Cu")
		(net 88)
	)
	(segment
		(start 214.4695 162.3545)
		(end 214.4695 161.624)
		(width 0.202)
		(layer "F.Cu")
		(net 88)
	)
	(segment
		(start 214.525 162.41)
		(end 214.4695 162.3545)
		(width 0.202)
		(layer "F.Cu")
		(net 88)
	)
	(segment
		(start 290.643 75.263348)
		(end 290.767 75.387348)
		(width 0.202)
		(layer "F.Cu")
		(net 88)
	)
	(segment
		(start 290.699 74.66)
		(end 290.643 74.716)
		(width 0.202)
		(layer "F.Cu")
		(net 88)
	)
	(via
		(at 214.5935 161.5)
		(size 0.45)
		(drill 0.1)
		(layers "F.Cu" "B.Cu")
		(teardrops
			(best_length_ratio 0.4)
			(max_length 1)
			(best_width_ratio 0.9)
			(max_width 2)
			(curved_edges yes)
			(filter_ratio 0.9)
			(enabled yes)
			(allow_two_segments yes)
			(prefer_zone_connections yes)
		)
		(net 88)
	)
	(via
		(at 290.767 75.387348)
		(size 0.45)
		(drill 0.1)
		(layers "F.Cu" "B.Cu")
		(remove_unused_layers yes)
		(keep_end_layers yes)
		(zone_layer_connections)
		(teardrops
			(best_length_ratio 0.4)
			(max_length 1)
			(best_width_ratio 0.9)
			(max_width 2)
			(curved_edges yes)
			(filter_ratio 0.9)
			(enabled yes)
			(allow_two_segments yes)
			(prefer_zone_connections yes)
		)
		(net 88)
	)
	(segment
		(start 278.369434 72.2805)
		(end 272.7155 77.934434)
		(width 0.202)
		(layer "B.Cu")
		(net 88)
	)
	(segment
		(start 214.4695 162.644434)
		(end 214.4695 161.624)
		(width 0.202)
		(layer "B.Cu")
		(net 88)
	)
	(segment
		(start 272.7155 129.609434)
		(end 266.1055 136.219434)
		(width 0.202)
		(layer "B.Cu")
		(net 88)
	)
	(segment
		(start 215.719434 163.0055)
		(end 214.830566 163.0055)
		(width 0.202)
		(layer "B.Cu")
		(net 88)
	)
	(segment
		(start 290.767 75.387348)
		(end 290.643 75.263348)
		(width 0.202)
		(layer "B.Cu")
		(net 88)
	)
	(segment
		(start 290.643 75.263348)
		(end 290.643 73.267934)
		(width 0.202)
		(layer "B.Cu")
		(net 88)
	)
	(segment
		(start 290.643 73.267934)
		(end 289.655566 72.2805)
		(width 0.202)
		(layer "B.Cu")
		(net 88)
	)
	(segment
		(start 216.6055 152.769434)
		(end 216.6055 158.619434)
		(width 0.202)
		(layer "B.Cu")
		(net 88)
	)
	(segment
		(start 289.655566 72.2805)
		(end 278.369434 72.2805)
		(width 0.202)
		(layer "B.Cu")
		(net 88)
	)
	(segment
		(start 214.830566 163.0055)
		(end 214.4695 162.644434)
		(width 0.202)
		(layer "B.Cu")
		(net 88)
	)
	(segment
		(start 272.7155 77.934434)
		(end 272.7155 129.609434)
		(width 0.202)
		(layer "B.Cu")
		(net 88)
	)
	(segment
		(start 215.9555 159.269434)
		(end 215.9555 162.769434)
		(width 0.202)
		(layer "B.Cu")
		(net 88)
	)
	(segment
		(start 243.530566 145.8055)
		(end 237.280566 139.5555)
		(width 0.202)
		(layer "B.Cu")
		(net 88)
	)
	(segment
		(start 222.5055 142.719434)
		(end 222.5055 146.869434)
		(width 0.202)
		(layer "B.Cu")
		(net 88)
	)
	(segment
		(start 222.5055 146.869434)
		(end 216.6055 152.769434)
		(width 0.202)
		(layer "B.Cu")
		(net 88)
	)
	(segment
		(start 266.1055 136.219434)
		(end 266.1055 144.469434)
		(width 0.202)
		(layer "B.Cu")
		(net 88)
	)
	(segment
		(start 225.669434 139.5555)
		(end 222.5055 142.719434)
		(width 0.202)
		(layer "B.Cu")
		(net 88)
	)
	(segment
		(start 264.769434 145.8055)
		(end 243.530566 145.8055)
		(width 0.202)
		(layer "B.Cu")
		(net 88)
	)
	(segment
		(start 216.6055 158.619434)
		(end 215.9555 159.269434)
		(width 0.202)
		(layer "B.Cu")
		(net 88)
	)
	(segment
		(start 237.280566 139.5555)
		(end 225.669434 139.5555)
		(width 0.202)
		(layer "B.Cu")
		(net 88)
	)
	(segment
		(start 266.1055 144.469434)
		(end 264.769434 145.8055)
		(width 0.202)
		(layer "B.Cu")
		(net 88)
	)
	(segment
		(start 214.4695 161.624)
		(end 214.5935 161.5)
		(width 0.202)
		(layer "B.Cu")
		(net 88)
	)
	(segment
		(start 215.9555 162.769434)
		(end 215.719434 163.0055)
		(width 0.202)
		(layer "B.Cu")
		(net 88)
	)
	(segment
		(start 287.642 74.716)
		(end 287.642 75.263348)
		(width 0.202)
		(layer "F.Cu")
		(net 89)
	)
	(segment
		(start 216.525 163.135)
		(end 216.525 163.86)
		(width 0.202)
		(layer "F.Cu")
		(net 89)
	)
	(segment
		(start 216.4695 163.9155)
		(end 216.4695 164.576)
		(width 0.202)
		(layer "F.Cu")
		(net 89)
	)
	(segment
		(start 216.525 163.86)
		(end 216.4695 163.9155)
		(width 0.202)
		(layer "F.Cu")
		(net 89)
	)
	(segment
		(start 287.698 74.66)
		(end 287.642 74.716)
		(width 0.202)
		(layer "F.Cu")
		(net 89)
	)
	(segment
		(start 216.4695 164.576)
		(end 216.5935 164.7)
		(width 0.202)
		(layer "F.Cu")
		(net 89)
	)
	(segment
		(start 287.642 75.263348)
		(end 287.766 75.387348)
		(width 0.202)
		(layer "F.Cu")
		(net 89)
	)
	(via
		(at 216.5935 164.7)
		(size 0.45)
		(drill 0.1)
		(layers "F.Cu" "B.Cu")
		(teardrops
			(best_length_ratio 0.4)
			(max_length 1)
			(best_width_ratio 0.9)
			(max_width 2)
			(curved_edges yes)
			(filter_ratio 0.9)
			(enabled yes)
			(allow_two_segments yes)
			(prefer_zone_connections yes)
		)
		(net 89)
	)
	(via
		(at 287.766 75.387348)
		(size 0.45)
		(drill 0.1)
		(layers "F.Cu" "B.Cu")
		(remove_unused_layers yes)
		(keep_end_layers yes)
		(zone_layer_connections)
		(teardrops
			(best_length_ratio 0.4)
			(max_length 1)
			(best_width_ratio 0.9)
			(max_width 2)
			(curved_edges yes)
			(filter_ratio 0.9)
			(enabled yes)
			(allow_two_segments yes)
			(prefer_zone_connections yes)
		)
		(net 89)
	)
	(segment
		(start 223.9055 148.069434)
		(end 218.1055 153.869434)
		(width 0.202)
		(layer "B.Cu")
		(net 89)
	)
	(segment
		(start 242.530566 148.0055)
		(end 236.180566 141.6555)
		(width 0.202)
		(layer "B.Cu")
		(net 89)
	)
	(segment
		(start 265.319434 148.0055)
		(end 242.530566 148.0055)
		(width 0.202)
		(layer "B.Cu")
		(net 89)
	)
	(segment
		(start 236.180566 141.6555)
		(end 226.419434 141.6555)
		(width 0.202)
		(layer "B.Cu")
		(net 89)
	)
	(segment
		(start 217.719434 165.2055)
		(end 216.730566 165.2055)
		(width 0.202)
		(layer "B.Cu")
		(net 89)
	)
	(segment
		(start 287.642 75.263348)
		(end 287.642 74.466934)
		(width 0.202)
		(layer "B.Cu")
		(net 89)
	)
	(segment
		(start 287.080566 73.9055)
		(end 278.994434 73.9055)
		(width 0.202)
		(layer "B.Cu")
		(net 89)
	)
	(segment
		(start 278.994434 73.9055)
		(end 274.2155 78.684434)
		(width 0.202)
		(layer "B.Cu")
		(net 89)
	)
	(segment
		(start 267.4055 137.319434)
		(end 267.4055 145.919434)
		(width 0.202)
		(layer "B.Cu")
		(net 89)
	)
	(segment
		(start 274.2155 130.509434)
		(end 267.4055 137.319434)
		(width 0.202)
		(layer "B.Cu")
		(net 89)
	)
	(segment
		(start 274.2155 78.684434)
		(end 274.2155 130.509434)
		(width 0.202)
		(layer "B.Cu")
		(net 89)
	)
	(segment
		(start 216.4695 164.944434)
		(end 216.4695 164.824)
		(width 0.202)
		(layer "B.Cu")
		(net 89)
	)
	(segment
		(start 226.419434 141.6555)
		(end 223.9055 144.169434)
		(width 0.202)
		(layer "B.Cu")
		(net 89)
	)
	(segment
		(start 287.766 75.387348)
		(end 287.642 75.263348)
		(width 0.202)
		(layer "B.Cu")
		(net 89)
	)
	(segment
		(start 223.9055 144.169434)
		(end 223.9055 148.069434)
		(width 0.202)
		(layer "B.Cu")
		(net 89)
	)
	(segment
		(start 267.4055 145.919434)
		(end 265.319434 148.0055)
		(width 0.202)
		(layer "B.Cu")
		(net 89)
	)
	(segment
		(start 216.730566 165.2055)
		(end 216.4695 164.944434)
		(width 0.202)
		(layer "B.Cu")
		(net 89)
	)
	(segment
		(start 218.1055 164.819434)
		(end 217.719434 165.2055)
		(width 0.202)
		(layer "B.Cu")
		(net 89)
	)
	(segment
		(start 287.642 74.466934)
		(end 287.080566 73.9055)
		(width 0.202)
		(layer "B.Cu")
		(net 89)
	)
	(segment
		(start 216.4695 164.824)
		(end 216.5935 164.7)
		(width 0.202)
		(layer "B.Cu")
		(net 89)
	)
	(segment
		(start 218.1055 153.869434)
		(end 218.1055 164.819434)
		(width 0.202)
		(layer "B.Cu")
		(net 89)
	)
	(segment
		(start 211.0805 164.626)
		(end 210.9565 164.75)
		(width 0.202)
		(layer "F.Cu")
		(net 90)
	)
	(segment
		(start 296.254 75.263348)
		(end 296.13 75.387348)
		(width 0.202)
		(layer "F.Cu")
		(net 90)
	)
	(segment
		(start 296.254 74.716)
		(end 296.254 75.263348)
		(width 0.202)
		(layer "F.Cu")
		(net 90)
	)
	(segment
		(start 211.025 163.135)
		(end 211.025 164.447501)
		(width 0.202)
		(layer "F.Cu")
		(net 90)
	)
	(segment
		(start 211.0805 164.503001)
		(end 211.0805 164.626)
		(width 0.202)
		(layer "F.Cu")
		(net 90)
	)
	(segment
		(start 296.198 74.66)
		(end 296.254 74.716)
		(width 0.202)
		(layer "F.Cu")
		(net 90)
	)
	(segment
		(start 211.025 164.447501)
		(end 211.0805 164.503001)
		(width 0.202)
		(layer "F.Cu")
		(net 90)
	)
	(via
		(at 296.13 75.387348)
		(size 0.45)
		(drill 0.1)
		(layers "F.Cu" "B.Cu")
		(remove_unused_layers yes)
		(keep_end_layers yes)
		(zone_layer_connections)
		(teardrops
			(best_length_ratio 0.4)
			(max_length 1)
			(best_width_ratio 0.9)
			(max_width 2)
			(curved_edges yes)
			(filter_ratio 0.9)
			(enabled yes)
			(allow_two_segments yes)
			(prefer_zone_connections yes)
		)
		(net 90)
	)
	(via
		(at 210.9565 164.75)
		(size 0.45)
		(drill 0.1)
		(layers "F.Cu" "B.Cu")
		(teardrops
			(best_length_ratio 0.4)
			(max_length 1)
			(best_width_ratio 0.9)
			(max_width 2)
			(curved_edges yes)
			(filter_ratio 0.9)
			(enabled yes)
			(allow_two_segments yes)
			(prefer_zone_connections yes)
		)
		(net 90)
	)
	(segment
		(start 276.830566 70.2945)
		(end 270.1045 77.020566)
		(width 0.202)
		(layer "B.Cu")
		(net 90)
	)
	(segment
		(start 238.969434 135.9445)
		(end 224.230566 135.9445)
		(width 0.202)
		(layer "B.Cu")
		(net 90)
	)
	(segment
		(start 244.969434 141.9445)
		(end 238.969434 135.9445)
		(width 0.202)
		(layer "B.Cu")
		(net 90)
	)
	(segment
		(start 262.580566 141.9445)
		(end 244.969434 141.9445)
		(width 0.202)
		(layer "B.Cu")
		(net 90)
	)
	(segment
		(start 211.4945 162.069434)
		(end 213.3945 163.969434)
		(width 0.202)
		(layer "B.Cu")
		(net 90)
	)
	(segment
		(start 212.730566 165.6945)
		(end 211.719434 165.6945)
		(width 0.202)
		(layer "B.Cu")
		(net 90)
	)
	(segment
		(start 211.0805 165.055566)
		(end 211.0805 164.874)
		(width 0.202)
		(layer "B.Cu")
		(net 90)
	)
	(segment
		(start 270.1045 127.770566)
		(end 263.4945 134.380566)
		(width 0.202)
		(layer "B.Cu")
		(net 90)
	)
	(segment
		(start 213.3945 165.030566)
		(end 212.730566 165.6945)
		(width 0.202)
		(layer "B.Cu")
		(net 90)
	)
	(segment
		(start 212.8945 158.830566)
		(end 211.4945 160.230566)
		(width 0.202)
		(layer "B.Cu")
		(net 90)
	)
	(segment
		(start 270.1045 77.020566)
		(end 270.1045 127.770566)
		(width 0.202)
		(layer "B.Cu")
		(net 90)
	)
	(segment
		(start 296.254 75.263348)
		(end 296.254 73.579066)
		(width 0.202)
		(layer "B.Cu")
		(net 90)
	)
	(segment
		(start 292.969434 70.2945)
		(end 276.830566 70.2945)
		(width 0.202)
		(layer "B.Cu")
		(net 90)
	)
	(segment
		(start 224.230566 135.9445)
		(end 218.9945 141.180566)
		(width 0.202)
		(layer "B.Cu")
		(net 90)
	)
	(segment
		(start 211.0805 164.874)
		(end 210.9565 164.75)
		(width 0.202)
		(layer "B.Cu")
		(net 90)
	)
	(segment
		(start 263.4945 134.380566)
		(end 263.4945 141.030566)
		(width 0.202)
		(layer "B.Cu")
		(net 90)
	)
	(segment
		(start 213.3945 163.969434)
		(end 213.3945 165.030566)
		(width 0.202)
		(layer "B.Cu")
		(net 90)
	)
	(segment
		(start 211.719434 165.6945)
		(end 211.0805 165.055566)
		(width 0.202)
		(layer "B.Cu")
		(net 90)
	)
	(segment
		(start 296.13 75.387348)
		(end 296.254 75.263348)
		(width 0.202)
		(layer "B.Cu")
		(net 90)
	)
	(segment
		(start 218.9945 141.180566)
		(end 218.9945 144.830566)
		(width 0.202)
		(layer "B.Cu")
		(net 90)
	)
	(segment
		(start 296.254 73.579066)
		(end 292.969434 70.2945)
		(width 0.202)
		(layer "B.Cu")
		(net 90)
	)
	(segment
		(start 211.4945 160.230566)
		(end 211.4945 162.069434)
		(width 0.202)
		(layer "B.Cu")
		(net 90)
	)
	(segment
		(start 218.9945 144.830566)
		(end 212.8945 150.930566)
		(width 0.202)
		(layer "B.Cu")
		(net 90)
	)
	(segment
		(start 212.8945 150.930566)
		(end 212.8945 158.830566)
		(width 0.202)
		(layer "B.Cu")
		(net 90)
	)
	(segment
		(start 263.4945 141.030566)
		(end 262.580566 141.9445)
		(width 0.202)
		(layer "B.Cu")
		(net 90)
	)
	(segment
		(start 293.255 74.716)
		(end 293.255 75.263348)
		(width 0.202)
		(layer "F.Cu")
		(net 91)
	)
	(segment
		(start 212.5805 161.055565)
		(end 212.350149 160.825214)
		(width 0.202)
		(layer "F.Cu")
		(net 91)
	)
	(segment
		(start 212.350149 160.825214)
		(end 212.174786 160.825214)
		(width 0.202)
		(layer "F.Cu")
		(net 91)
	)
	(segment
		(start 212.5805 162.3545)
		(end 212.5805 161.055565)
		(width 0.202)
		(layer "F.Cu")
		(net 91)
	)
	(segment
		(start 293.255 75.263348)
		(end 293.131 75.387348)
		(width 0.202)
		(layer "F.Cu")
		(net 91)
	)
	(segment
		(start 293.199 74.66)
		(end 293.255 74.716)
		(width 0.202)
		(layer "F.Cu")
		(net 91)
	)
	(segment
		(start 212.525 162.41)
		(end 212.5805 162.3545)
		(width 0.202)
		(layer "F.Cu")
		(net 91)
	)
	(segment
		(start 212.525 163.135)
		(end 212.525 162.41)
		(width 0.202)
		(layer "F.Cu")
		(net 91)
	)
	(via
		(at 293.131 75.387348)
		(size 0.45)
		(drill 0.1)
		(layers "F.Cu" "B.Cu")
		(remove_unused_layers yes)
		(keep_end_layers yes)
		(zone_layer_connections)
		(teardrops
			(best_length_ratio 0.4)
			(max_length 1)
			(best_width_ratio 0.9)
			(max_width 2)
			(curved_edges yes)
			(filter_ratio 0.9)
			(enabled yes)
			(allow_two_segments yes)
			(prefer_zone_connections yes)
		)
		(net 91)
	)
	(via
		(at 212.174786 160.825214)
		(size 0.45)
		(drill 0.1)
		(layers "F.Cu" "B.Cu")
		(teardrops
			(best_length_ratio 0.4)
			(max_length 1)
			(best_width_ratio 0.9)
			(max_width 2)
			(curved_edges yes)
			(filter_ratio 0.9)
			(enabled yes)
			(allow_two_segments yes)
			(prefer_zone_connections yes)
		)
		(net 91)
	)
	(segment
		(start 214.9445 151.730566)
		(end 220.9445 145.730566)
		(width 0.202)
		(layer "B.Cu")
		(net 91)
	)
	(segment
		(start 271.6045 128.870566)
		(end 271.6045 77.370566)
		(width 0.202)
		(layer "B.Cu")
		(net 91)
	)
	(segment
		(start 213.580566 161.0945)
		(end 213.905117 160.769949)
		(width 0.202)
		(layer "B.Cu")
		(net 91)
	)
	(segment
		(start 265.0445 142.880566)
		(end 265.0445 135.430566)
		(width 0.202)
		(layer "B.Cu")
		(net 91)
	)
	(segment
		(start 212.174786 160.825214)
		(end 212.350149 160.825214)
		(width 0.202)
		(layer "B.Cu")
		(net 91)
	)
	(segment
		(start 214.655441 160.43133)
		(end 214.60515 160.381039)
		(width 0.202)
		(layer "B.Cu")
		(net 91)
	)
	(segment
		(start 293.255 75.263348)
		(end 293.131 75.387348)
		(width 0.202)
		(layer "B.Cu")
		(net 91)
	)
	(segment
		(start 214.60515 160.069912)
		(end 214.682934 159.992131)
		(width 0.202)
		(layer "B.Cu")
		(net 91)
	)
	(segment
		(start 293.255 73.105066)
		(end 293.255 75.263348)
		(width 0.202)
		(layer "B.Cu")
		(net 91)
	)
	(segment
		(start 214.9445 159.730566)
		(end 214.9445 151.730566)
		(width 0.202)
		(layer "B.Cu")
		(net 91)
	)
	(segment
		(start 277.505566 71.4695)
		(end 291.619434 71.4695)
		(width 0.202)
		(layer "B.Cu")
		(net 91)
	)
	(segment
		(start 244.219434 144.0445)
		(end 263.880566 144.0445)
		(width 0.202)
		(layer "B.Cu")
		(net 91)
	)
	(segment
		(start 214.57766 160.820239)
		(end 214.655441 160.742457)
		(width 0.202)
		(layer "B.Cu")
		(net 91)
	)
	(segment
		(start 214.216243 160.769949)
		(end 214.266533 160.820239)
		(width 0.202)
		(layer "B.Cu")
		(net 91)
	)
	(segment
		(start 220.9445 141.880566)
		(end 224.780566 138.0445)
		(width 0.202)
		(layer "B.Cu")
		(net 91)
	)
	(segment
		(start 224.780566 138.0445)
		(end 238.219434 138.0445)
		(width 0.202)
		(layer "B.Cu")
		(net 91)
	)
	(segment
		(start 265.0445 135.430566)
		(end 271.6045 128.870566)
		(width 0.202)
		(layer "B.Cu")
		(net 91)
	)
	(segment
		(start 212.350149 160.825214)
		(end 212.619435 161.0945)
		(width 0.202)
		(layer "B.Cu")
		(net 91)
	)
	(segment
		(start 212.619435 161.0945)
		(end 213.580566 161.0945)
		(width 0.202)
		(layer "B.Cu")
		(net 91)
	)
	(segment
		(start 238.219434 138.0445)
		(end 244.219434 144.0445)
		(width 0.202)
		(layer "B.Cu")
		(net 91)
	)
	(segment
		(start 291.619434 71.4695)
		(end 293.255 73.105066)
		(width 0.202)
		(layer "B.Cu")
		(net 91)
	)
	(segment
		(start 214.682934 159.992131)
		(end 214.9445 159.730566)
		(width 0.202)
		(layer "B.Cu")
		(net 91)
	)
	(segment
		(start 271.6045 77.370566)
		(end 277.505566 71.4695)
		(width 0.202)
		(layer "B.Cu")
		(net 91)
	)
	(segment
		(start 263.880566 144.0445)
		(end 265.0445 142.880566)
		(width 0.202)
		(layer "B.Cu")
		(net 91)
	)
	(segment
		(start 220.9445 145.730566)
		(end 220.9445 141.880566)
		(width 0.202)
		(layer "B.Cu")
		(net 91)
	)
	(arc
		(start 213.905117 160.769949)
		(mid 214.06068 160.705513)
		(end 214.216243 160.769949)
		(width 0.202)
		(layer "B.Cu")
		(net 91)
	)
	(arc
		(start 214.655441 160.742457)
		(mid 214.719878 160.586893)
		(end 214.655441 160.43133)
		(width 0.202)
		(layer "B.Cu")
		(net 91)
	)
	(arc
		(start 214.60515 160.381039)
		(mid 214.540713 160.225476)
		(end 214.60515 160.069912)
		(width 0.202)
		(layer "B.Cu")
		(net 91)
	)
	(arc
		(start 214.266533 160.820239)
		(mid 214.422097 160.884675)
		(end 214.57766 160.820239)
		(width 0.202)
		(layer "B.Cu")
		(net 91)
	)
	(segment
		(start 290.198 74.66)
		(end 290.254 74.716)
		(width 0.202)
		(layer "F.Cu")
		(net 92)
	)
	(segment
		(start 290.254 75.263348)
		(end 290.13 75.387348)
		(width 0.202)
		(layer "F.Cu")
		(net 92)
	)
	(segment
		(start 214.0805 161.624)
		(end 213.9565 161.5)
		(width 0.202)
		(layer "F.Cu")
		(net 92)
	)
	(segment
		(start 214.025 163.135)
		(end 214.025 162.41)
		(width 0.202)
		(layer "F.Cu")
		(net 92)
	)
	(segment
		(start 290.254 74.716)
		(end 290.254 75.263348)
		(width 0.202)
		(layer "F.Cu")
		(net 92)
	)
	(segment
		(start 214.025 162.41)
		(end 214.0805 162.3545)
		(width 0.202)
		(layer "F.Cu")
		(net 92)
	)
	(segment
		(start 214.0805 162.3545)
		(end 214.0805 161.624)
		(width 0.202)
		(layer "F.Cu")
		(net 92)
	)
	(via
		(at 213.9565 161.5)
		(size 0.45)
		(drill 0.1)
		(layers "F.Cu" "B.Cu")
		(teardrops
			(best_length_ratio 0.4)
			(max_length 1)
			(best_width_ratio 0.9)
			(max_width 2)
			(curved_edges yes)
			(filter_ratio 0.9)
			(enabled yes)
			(allow_two_segments yes)
			(prefer_zone_connections yes)
		)
		(net 92)
	)
	(via
		(at 290.13 75.387348)
		(size 0.45)
		(drill 0.1)
		(layers "F.Cu" "B.Cu")
		(remove_unused_layers yes)
		(keep_end_layers yes)
		(zone_layer_connections)
		(teardrops
			(best_length_ratio 0.4)
			(max_length 1)
			(best_width_ratio 0.9)
			(max_width 2)
			(curved_edges yes)
			(filter_ratio 0.9)
			(enabled yes)
			(allow_two_segments yes)
			(prefer_zone_connections yes)
		)
		(net 92)
	)
	(segment
		(start 237.119434 139.9445)
		(end 225.830566 139.9445)
		(width 0.202)
		(layer "B.Cu")
		(net 92)
	)
	(segment
		(start 216.3445 159.430566)
		(end 216.3445 162.930566)
		(width 0.202)
		(layer "B.Cu")
		(net 92)
	)
	(segment
		(start 266.4945 144.630566)
		(end 264.930566 146.1945)
		(width 0.202)
		(layer "B.Cu")
		(net 92)
	)
	(segment
		(start 214.669434 163.3945)
		(end 214.0805 162.805566)
		(width 0.202)
		(layer "B.Cu")
		(net 92)
	)
	(segment
		(start 266.4945 136.380566)
		(end 266.4945 144.630566)
		(width 0.202)
		(layer "B.Cu")
		(net 92)
	)
	(segment
		(start 222.8945 142.880566)
		(end 222.8945 147.030566)
		(width 0.202)
		(layer "B.Cu")
		(net 92)
	)
	(segment
		(start 273.1045 78.095566)
		(end 273.1045 129.770566)
		(width 0.202)
		(layer "B.Cu")
		(net 92)
	)
	(segment
		(start 216.9945 158.780566)
		(end 216.3445 159.430566)
		(width 0.202)
		(layer "B.Cu")
		(net 92)
	)
	(segment
		(start 214.0805 162.805566)
		(end 214.0805 161.624)
		(width 0.202)
		(layer "B.Cu")
		(net 92)
	)
	(segment
		(start 264.930566 146.1945)
		(end 243.369434 146.1945)
		(width 0.202)
		(layer "B.Cu")
		(net 92)
	)
	(segment
		(start 273.1045 129.770566)
		(end 266.4945 136.380566)
		(width 0.202)
		(layer "B.Cu")
		(net 92)
	)
	(segment
		(start 215.880566 163.3945)
		(end 214.669434 163.3945)
		(width 0.202)
		(layer "B.Cu")
		(net 92)
	)
	(segment
		(start 216.9945 152.930566)
		(end 216.9945 158.780566)
		(width 0.202)
		(layer "B.Cu")
		(net 92)
	)
	(segment
		(start 289.494434 72.6695)
		(end 278.530566 72.6695)
		(width 0.202)
		(layer "B.Cu")
		(net 92)
	)
	(segment
		(start 214.0805 161.624)
		(end 213.9565 161.5)
		(width 0.202)
		(layer "B.Cu")
		(net 92)
	)
	(segment
		(start 290.13 75.387348)
		(end 290.254 75.263348)
		(width 0.202)
		(layer "B.Cu")
		(net 92)
	)
	(segment
		(start 216.3445 162.930566)
		(end 215.880566 163.3945)
		(width 0.202)
		(layer "B.Cu")
		(net 92)
	)
	(segment
		(start 290.254 73.429066)
		(end 289.494434 72.6695)
		(width 0.202)
		(layer "B.Cu")
		(net 92)
	)
	(segment
		(start 278.530566 72.6695)
		(end 273.1045 78.095566)
		(width 0.202)
		(layer "B.Cu")
		(net 92)
	)
	(segment
		(start 225.830566 139.9445)
		(end 222.8945 142.880566)
		(width 0.202)
		(layer "B.Cu")
		(net 92)
	)
	(segment
		(start 243.369434 146.1945)
		(end 237.119434 139.9445)
		(width 0.202)
		(layer "B.Cu")
		(net 92)
	)
	(segment
		(start 290.254 75.263348)
		(end 290.254 73.429066)
		(width 0.202)
		(layer "B.Cu")
		(net 92)
	)
	(segment
		(start 222.8945 147.030566)
		(end 216.9945 152.930566)
		(width 0.202)
		(layer "B.Cu")
		(net 92)
	)
	(segment
		(start 287.253 75.263348)
		(end 287.129 75.387348)
		(width 0.202)
		(layer "F.Cu")
		(net 93)
	)
	(segment
		(start 216.025 163.135)
		(end 216.025 163.86)
		(width 0.202)
		(layer "F.Cu")
		(net 93)
	)
	(segment
		(start 287.253 74.716)
		(end 287.253 75.263348)
		(width 0.202)
		(layer "F.Cu")
		(net 93)
	)
	(segment
		(start 216.0805 164.576)
		(end 215.9565 164.7)
		(width 0.202)
		(layer "F.Cu")
		(net 93)
	)
	(segment
		(start 287.197 74.66)
		(end 287.253 74.716)
		(width 0.202)
		(layer "F.Cu")
		(net 93)
	)
	(segment
		(start 216.025 163.86)
		(end 216.0805 163.9155)
		(width 0.202)
		(layer "F.Cu")
		(net 93)
	)
	(segment
		(start 216.0805 163.9155)
		(end 216.0805 164.576)
		(width 0.202)
		(layer "F.Cu")
		(net 93)
	)
	(via
		(at 215.9565 164.7)
		(size 0.45)
		(drill 0.1)
		(layers "F.Cu" "B.Cu")
		(teardrops
			(best_length_ratio 0.4)
			(max_length 1)
			(best_width_ratio 0.9)
			(max_width 2)
			(curved_edges yes)
			(filter_ratio 0.9)
			(enabled yes)
			(allow_two_segments yes)
			(prefer_zone_connections yes)
		)
		(net 93)
	)
	(via
		(at 287.129 75.387348)
		(size 0.45)
		(drill 0.1)
		(layers "F.Cu" "B.Cu")
		(remove_unused_layers yes)
		(keep_end_layers yes)
		(zone_layer_connections)
		(teardrops
			(best_length_ratio 0.4)
			(max_length 1)
			(best_width_ratio 0.9)
			(max_width 2)
			(curved_edges yes)
			(filter_ratio 0.9)
			(enabled yes)
			(allow_two_segments yes)
			(prefer_zone_connections yes)
		)
		(net 93)
	)
	(segment
		(start 216.0805 164.824)
		(end 215.9565 164.7)
		(width 0.202)
		(layer "B.Cu")
		(net 93)
	)
	(segment
		(start 279.155566 74.2945)
		(end 274.6045 78.845566)
		(width 0.202)
		(layer "B.Cu")
		(net 93)
	)
	(segment
		(start 218.4945 154.030566)
		(end 218.4945 164.980566)
		(width 0.202)
		(layer "B.Cu")
		(net 93)
	)
	(segment
		(start 274.6045 130.670566)
		(end 267.7945 137.480566)
		(width 0.202)
		(layer "B.Cu")
		(net 93)
	)
	(segment
		(start 286.919434 74.2945)
		(end 279.155566 74.2945)
		(width 0.202)
		(layer "B.Cu")
		(net 93)
	)
	(segment
		(start 224.2945 148.230566)
		(end 218.4945 154.030566)
		(width 0.202)
		(layer "B.Cu")
		(net 93)
	)
	(segment
		(start 267.7945 137.480566)
		(end 267.7945 146.080566)
		(width 0.202)
		(layer "B.Cu")
		(net 93)
	)
	(segment
		(start 242.369434 148.3945)
		(end 236.019434 142.0445)
		(width 0.202)
		(layer "B.Cu")
		(net 93)
	)
	(segment
		(start 287.253 75.263348)
		(end 287.253 74.628066)
		(width 0.202)
		(layer "B.Cu")
		(net 93)
	)
	(segment
		(start 287.253 74.628066)
		(end 286.919434 74.2945)
		(width 0.202)
		(layer "B.Cu")
		(net 93)
	)
	(segment
		(start 216.0805 165.105566)
		(end 216.0805 164.824)
		(width 0.202)
		(layer "B.Cu")
		(net 93)
	)
	(segment
		(start 267.7945 146.080566)
		(end 265.480566 148.3945)
		(width 0.202)
		(layer "B.Cu")
		(net 93)
	)
	(segment
		(start 265.480566 148.3945)
		(end 242.369434 148.3945)
		(width 0.202)
		(layer "B.Cu")
		(net 93)
	)
	(segment
		(start 224.2945 144.330566)
		(end 224.2945 148.230566)
		(width 0.202)
		(layer "B.Cu")
		(net 93)
	)
	(segment
		(start 274.6045 78.845566)
		(end 274.6045 130.670566)
		(width 0.202)
		(layer "B.Cu")
		(net 93)
	)
	(segment
		(start 287.129 75.387348)
		(end 287.253 75.263348)
		(width 0.202)
		(layer "B.Cu")
		(net 93)
	)
	(segment
		(start 216.569434 165.5945)
		(end 216.0805 165.105566)
		(width 0.202)
		(layer "B.Cu")
		(net 93)
	)
	(segment
		(start 217.880566 165.5945)
		(end 216.569434 165.5945)
		(width 0.202)
		(layer "B.Cu")
		(net 93)
	)
	(segment
		(start 218.4945 164.980566)
		(end 217.880566 165.5945)
		(width 0.202)
		(layer "B.Cu")
		(net 93)
	)
	(segment
		(start 226.580566 142.0445)
		(end 224.2945 144.330566)
		(width 0.202)
		(layer "B.Cu")
		(net 93)
	)
	(segment
		(start 236.019434 142.0445)
		(end 226.580566 142.0445)
		(width 0.202)
		(layer "B.Cu")
		(net 93)
	)
	(segment
		(start 108.667786 159.060785)
		(end 108.373 159.355571)
		(width 0.202)
		(layer "B.Cu")
		(net 94)
	)
	(segment
		(start 112.258713 157.946353)
		(end 111.730067 158.474999)
		(width 0.202)
		(layer "B.Cu")
		(net 94)
	)
	(segment
		(start 115.3455 149.416)
		(end 115.3455 150.381139)
		(width 0.202)
		(layer "B.Cu")
		(net 94)
	)
	(segment
		(start 114.759713 151.795353)
		(end 113.322111 153.232955)
		(width 0.202)
		(layer "B.Cu")
		(net 94)
	)
	(segment
		(start 110.315854 159.060785)
		(end 108.667786 159.060785)
		(width 0.202)
		(layer "B.Cu")
		(net 94)
	)
	(segment
		(start 115.401 149.3605)
		(end 115.3455 149.416)
		(width 0.202)
		(layer "B.Cu")
		(net 94)
	)
	(segment
		(start 112.8445 154.38601)
		(end 112.8445 156.532139)
		(width 0.202)
		(layer "B.Cu")
		(net 94)
	)
	(arc
		(start 110.315854 159.060785)
		(mid 111.081221 158.908544)
		(end 111.730067 158.474999)
		(width 0.202)
		(layer "B.Cu")
		(net 94)
	)
	(arc
		(start 113.322111 153.232955)
		(mid 112.968627 153.761981)
		(end 112.8445 154.38601)
		(width 0.202)
		(layer "B.Cu")
		(net 94)
	)
	(arc
		(start 112.8445 156.532139)
		(mid 112.692259 157.297506)
		(end 112.258713 157.946353)
		(width 0.202)
		(layer "B.Cu")
		(net 94)
	)
	(arc
		(start 115.3455 150.381139)
		(mid 115.193259 151.146506)
		(end 114.759713 151.795353)
		(width 0.202)
		(layer "B.Cu")
		(net 94)
	)
	(segment
		(start 102.5255 166.1655)
		(end 102.465 166.105)
		(width 0.202)
		(layer "B.Cu")
		(net 95)
	)
	(segment
		(start 105.623001 166.1655)
		(end 105.567501 166.11)
		(width 0.202)
		(layer "B.Cu")
		(net 95)
	)
	(segment
		(start 103.914999 166.1655)
		(end 102.5255 166.1655)
		(width 0.202)
		(layer "B.Cu")
		(net 95)
	)
	(segment
		(start 109.331 165.869)
		(end 109.0345 166.1655)
		(width 0.202)
		(layer "B.Cu")
		(net 95)
	)
	(segment
		(start 105.155 166.11)
		(end 104.383 166.11)
		(width 0.202)
		(layer "B.Cu")
		(net 95)
	)
	(segment
		(start 109.0345 166.1655)
		(end 105.623001 166.1655)
		(width 0.202)
		(layer "B.Cu")
		(net 95)
	)
	(segment
		(start 104.383 166.11)
		(end 103.970499 166.11)
		(width 0.202)
		(layer "B.Cu")
		(net 95)
	)
	(segment
		(start 103.970499 166.11)
		(end 103.914999 166.1655)
		(width 0.202)
		(layer "B.Cu")
		(net 95)
	)
	(segment
		(start 105.567501 166.11)
		(end 105.155 166.11)
		(width 0.202)
		(layer "B.Cu")
		(net 95)
	)
	(segment
		(start 105.567501 164.612)
		(end 105.155 164.612)
		(width 0.202)
		(layer "B.Cu")
		(net 96)
	)
	(segment
		(start 103.914999 164.6675)
		(end 102.5275 164.6675)
		(width 0.202)
		(layer "B.Cu")
		(net 96)
	)
	(segment
		(start 107.413 164.377)
		(end 107.1225 164.6675)
		(width 0.202)
		(layer "B.Cu")
		(net 96)
	)
	(segment
		(start 105.623001 164.6675)
		(end 105.567501 164.612)
		(width 0.202)
		(layer "B.Cu")
		(net 96)
	)
	(segment
		(start 105.155 164.612)
		(end 104.383 164.612)
		(width 0.202)
		(layer "B.Cu")
		(net 96)
	)
	(segment
		(start 102.5275 164.6675)
		(end 102.465 164.605)
		(width 0.202)
		(layer "B.Cu")
		(net 96)
	)
	(segment
		(start 103.970499 164.612)
		(end 103.914999 164.6675)
		(width 0.202)
		(layer "B.Cu")
		(net 96)
	)
	(segment
		(start 107.1225 164.6675)
		(end 105.623001 164.6675)
		(width 0.202)
		(layer "B.Cu")
		(net 96)
	)
	(segment
		(start 104.383 164.612)
		(end 103.970499 164.612)
		(width 0.202)
		(layer "B.Cu")
		(net 96)
	)
	(segment
		(start 102.5255 160.1655)
		(end 102.465 160.105)
		(width 0.202)
		(layer "B.Cu")
		(net 97)
	)
	(segment
		(start 105.567501 160.11)
		(end 105.155 160.11)
		(width 0.202)
		(layer "B.Cu")
		(net 97)
	)
	(segment
		(start 104.383 160.11)
		(end 103.970499 160.11)
		(width 0.202)
		(layer "B.Cu")
		(net 97)
	)
	(segment
		(start 105.623001 160.1655)
		(end 105.567501 160.11)
		(width 0.202)
		(layer "B.Cu")
		(net 97)
	)
	(segment
		(start 105.155 160.11)
		(end 104.383 160.11)
		(width 0.202)
		(layer "B.Cu")
		(net 97)
	)
	(segment
		(start 109.0345 160.1655)
		(end 105.623001 160.1655)
		(width 0.202)
		(layer "B.Cu")
		(net 97)
	)
	(segment
		(start 103.970499 160.11)
		(end 103.914999 160.1655)
		(width 0.202)
		(layer "B.Cu")
		(net 97)
	)
	(segment
		(start 103.914999 160.1655)
		(end 102.5255 160.1655)
		(width 0.202)
		(layer "B.Cu")
		(net 97)
	)
	(segment
		(start 109.331 159.869)
		(end 109.0345 160.1655)
		(width 0.202)
		(layer "B.Cu")
		(net 97)
	)
	(segment
		(start 107.1225 158.6675)
		(end 105.623001 158.6675)
		(width 0.202)
		(layer "B.Cu")
		(net 98)
	)
	(segment
		(start 107.413 158.377)
		(end 107.1225 158.6675)
		(width 0.202)
		(layer "B.Cu")
		(net 98)
	)
	(segment
		(start 105.155 158.612)
		(end 104.383 158.612)
		(width 0.202)
		(layer "B.Cu")
		(net 98)
	)
	(segment
		(start 104.383 158.612)
		(end 103.970499 158.612)
		(width 0.202)
		(layer "B.Cu")
		(net 98)
	)
	(segment
		(start 103.914999 158.6675)
		(end 102.5275 158.6675)
		(width 0.202)
		(layer "B.Cu")
		(net 98)
	)
	(segment
		(start 105.623001 158.6675)
		(end 105.567501 158.612)
		(width 0.202)
		(layer "B.Cu")
		(net 98)
	)
	(segment
		(start 105.567501 158.612)
		(end 105.155 158.612)
		(width 0.202)
		(layer "B.Cu")
		(net 98)
	)
	(segment
		(start 102.5275 158.6675)
		(end 102.465 158.605)
		(width 0.202)
		(layer "B.Cu")
		(net 98)
	)
	(segment
		(start 103.970499 158.612)
		(end 103.914999 158.6675)
		(width 0.202)
		(layer "B.Cu")
		(net 98)
	)
	(segment
		(start 108.667786 158.671786)
		(end 108.8 158.671786)
		(width 0.202)
		(layer "B.Cu")
		(net 99)
	)
	(segment
		(start 109.93955 158.671786)
		(end 110.200927 158.671786)
		(width 0.202)
		(layer "B.Cu")
		(net 99)
	)
	(segment
		(start 114.9565 149.416)
		(end 114.901 149.3605)
		(width 0.202)
		(layer "B.Cu")
		(net 99)
	)
	(segment
		(start 110.200927 158.671786)
		(end 110.295553 158.671786)
		(width 0.202)
		(layer "B.Cu")
		(net 99)
	)
	(segment
		(start 109.33955 158.132235)
		(end 109.4 158.132235)
		(width 0.202)
		(layer "B.Cu")
		(net 99)
	)
	(segment
		(start 108.373 158.377)
		(end 108.667786 158.671786)
		(width 0.202)
		(layer "B.Cu")
		(net 99)
	)
	(segment
		(start 111.469351 158.185583)
		(end 111.970336 157.684598)
		(width 0.202)
		(layer "B.Cu")
		(net 99)
	)
	(segment
		(start 109.069775 158.402011)
		(end 109.069775 158.40201)
		(width 0.202)
		(layer "B.Cu")
		(net 99)
	)
	(segment
		(start 112.4555 156.513309)
		(end 112.4555 154.377861)
		(width 0.202)
		(layer "B.Cu")
		(net 99)
	)
	(segment
		(start 114.9565 150.358615)
		(end 114.9565 149.416)
		(width 0.202)
		(layer "B.Cu")
		(net 99)
	)
	(segment
		(start 109.669775 158.40201)
		(end 109.669775 158.402011)
		(width 0.202)
		(layer "B.Cu")
		(net 99)
	)
	(segment
		(start 113.041286 152.963648)
		(end 114.468725 151.536209)
		(width 0.202)
		(layer "B.Cu")
		(net 99)
	)
	(arc
		(start 109.4 158.132235)
		(mid 109.59076 158.21125)
		(end 109.669775 158.40201)
		(width 0.202)
		(layer "B.Cu")
		(net 99)
	)
	(arc
		(start 110.295553 158.671786)
		(mid 110.930808 158.545426)
		(end 111.469351 158.185583)
		(width 0.202)
		(layer "B.Cu")
		(net 99)
	)
	(arc
		(start 111.970336 157.684598)
		(mid 112.32941 157.147206)
		(end 112.4555 156.513309)
		(width 0.202)
		(layer "B.Cu")
		(net 99)
	)
	(arc
		(start 112.4555 154.377861)
		(mid 112.607741 153.612494)
		(end 113.041286 152.963648)
		(width 0.202)
		(layer "B.Cu")
		(net 99)
	)
	(arc
		(start 109.069775 158.40201)
		(mid 109.14879 158.21125)
		(end 109.33955 158.132235)
		(width 0.202)
		(layer "B.Cu")
		(net 99)
	)
	(arc
		(start 109.669775 158.402011)
		(mid 109.74879 158.592771)
		(end 109.93955 158.671786)
		(width 0.202)
		(layer "B.Cu")
		(net 99)
	)
	(arc
		(start 108.8 158.671786)
		(mid 108.99076 158.592771)
		(end 109.069775 158.402011)
		(width 0.202)
		(layer "B.Cu")
		(net 99)
	)
	(arc
		(start 114.468725 151.536209)
		(mid 114.829731 150.995924)
		(end 114.9565 150.358615)
		(width 0.202)
		(layer "B.Cu")
		(net 99)
	)
	(segment
		(start 109.037929 166.5545)
		(end 105.623001 166.5545)
		(width 0.202)
		(layer "B.Cu")
		(net 100)
	)
	(segment
		(start 105.155 166.61)
		(end 104.383 166.61)
		(width 0.202)
		(layer "B.Cu")
		(net 100)
	)
	(segment
		(start 103.970499 166.61)
		(end 103.914999 166.5545)
		(width 0.202)
		(layer "B.Cu")
		(net 100)
	)
	(segment
		(start 105.567501 166.61)
		(end 105.155 166.61)
		(width 0.202)
		(layer "B.Cu")
		(net 100)
	)
	(segment
		(start 104.383 166.61)
		(end 103.970499 166.61)
		(width 0.202)
		(layer "B.Cu")
		(net 100)
	)
	(segment
		(start 109.331 166.847571)
		(end 109.037929 166.5545)
		(width 0.202)
		(layer "B.Cu")
		(net 100)
	)
	(segment
		(start 103.914999 166.5545)
		(end 102.5155 166.5545)
		(width 0.202)
		(layer "B.Cu")
		(net 100)
	)
	(segment
		(start 102.5155 166.5545)
		(end 102.465 166.605)
		(width 0.202)
		(layer "B.Cu")
		(net 100)
	)
	(segment
		(start 105.623001 166.5545)
		(end 105.567501 166.61)
		(width 0.202)
		(layer "B.Cu")
		(net 100)
	)
	(segment
		(start 197.771563 136.666349)
		(end 198.203607 136.666349)
		(width 0.202)
		(layer "B.Cu")
		(net 101)
	)
	(segment
		(start 197.284015 136.178799)
		(end 197.284015 136.1788)
		(width 0.202)
		(layer "B.Cu")
		(net 101)
	)
	(segment
		(start 197.284015 136.1788)
		(end 197.771563 136.666349)
		(width 0.202)
		(layer "B.Cu")
		(net 101)
	)
	(segment
		(start 198.203607 136.666349)
		(end 198.221285 136.684026)
		(width 0.202)
		(layer "B.Cu")
		(net 101)
	)
	(segment
		(start 197.016552 135.832847)
		(end 197.016552 135.911336)
		(width 0.202)
		(layer "B.Cu")
		(net 101)
	)
	(segment
		(start 196.552513 135.368808)
		(end 197.016552 135.832847)
		(width 0.202)
		(layer "B.Cu")
		(net 101)
	)
	(segment
		(start 197.016552 135.911336)
		(end 197.284015 136.178799)
		(width 0.202)
		(layer "B.Cu")
		(net 101)
	)
	(segment
		(start 102.5135 165.0565)
		(end 102.465 165.105)
		(width 0.202)
		(layer "B.Cu")
		(net 102)
	)
	(segment
		(start 105.155 165.112)
		(end 104.383 165.112)
		(width 0.202)
		(layer "B.Cu")
		(net 102)
	)
	(segment
		(start 103.970499 165.112)
		(end 103.914999 165.0565)
		(width 0.202)
		(layer "B.Cu")
		(net 102)
	)
	(segment
		(start 104.383 165.112)
		(end 103.970499 165.112)
		(width 0.202)
		(layer "B.Cu")
		(net 102)
	)
	(segment
		(start 107.413 165.355571)
		(end 107.113929 165.0565)
		(width 0.202)
		(layer "B.Cu")
		(net 102)
	)
	(segment
		(start 105.567501 165.112)
		(end 105.155 165.112)
		(width 0.202)
		(layer "B.Cu")
		(net 102)
	)
	(segment
		(start 103.914999 165.0565)
		(end 102.5135 165.0565)
		(width 0.202)
		(layer "B.Cu")
		(net 102)
	)
	(segment
		(start 105.623001 165.0565)
		(end 105.567501 165.112)
		(width 0.202)
		(layer "B.Cu")
		(net 102)
	)
	(segment
		(start 107.113929 165.0565)
		(end 105.623001 165.0565)
		(width 0.202)
		(layer "B.Cu")
		(net 102)
	)
	(segment
		(start 195.955892 136.893507)
		(end 195.955892 136.971996)
		(width 0.202)
		(layer "B.Cu")
		(net 103)
	)
	(segment
		(start 197.778989 138.795094)
		(end 197.778989 138.795095)
		(width 0.202)
		(layer "B.Cu")
		(net 103)
	)
	(segment
		(start 198.047336 139.063441)
		(end 198.479378 139.063441)
		(width 0.202)
		(layer "B.Cu")
		(net 103)
	)
	(segment
		(start 198.479378 139.063441)
		(end 198.497056 139.081119)
		(width 0.202)
		(layer "B.Cu")
		(net 103)
	)
	(segment
		(start 195.955892 136.971996)
		(end 197.778989 138.795094)
		(width 0.202)
		(layer "B.Cu")
		(net 103)
	)
	(segment
		(start 195.491852 136.429468)
		(end 195.955892 136.893507)
		(width 0.202)
		(layer "B.Cu")
		(net 103)
	)
	(segment
		(start 197.778989 138.795095)
		(end 198.047336 139.063441)
		(width 0.202)
		(layer "B.Cu")
		(net 103)
	)
	(segment
		(start 109.331 160.847571)
		(end 109.037929 160.5545)
		(width 0.202)
		(layer "B.Cu")
		(net 104)
	)
	(segment
		(start 105.623001 160.5545)
		(end 105.567501 160.61)
		(width 0.202)
		(layer "B.Cu")
		(net 104)
	)
	(segment
		(start 103.970499 160.61)
		(end 103.914999 160.5545)
		(width 0.202)
		(layer "B.Cu")
		(net 104)
	)
	(segment
		(start 102.5155 160.5545)
		(end 102.465 160.605)
		(width 0.202)
		(layer "B.Cu")
		(net 104)
	)
	(segment
		(start 104.383 160.61)
		(end 103.970499 160.61)
		(width 0.202)
		(layer "B.Cu")
		(net 104)
	)
	(segment
		(start 103.914999 160.5545)
		(end 102.5155 160.5545)
		(width 0.202)
		(layer "B.Cu")
		(net 104)
	)
	(segment
		(start 109.037929 160.5545)
		(end 105.623001 160.5545)
		(width 0.202)
		(layer "B.Cu")
		(net 104)
	)
	(segment
		(start 105.567501 160.61)
		(end 105.155 160.61)
		(width 0.202)
		(layer "B.Cu")
		(net 104)
	)
	(segment
		(start 105.155 160.61)
		(end 104.383 160.61)
		(width 0.202)
		(layer "B.Cu")
		(net 104)
	)
	(segment
		(start 194.895232 137.954168)
		(end 194.895232 138.032656)
		(width 0.202)
		(layer "B.Cu")
		(net 105)
	)
	(segment
		(start 194.431192 137.490128)
		(end 194.895232 137.954168)
		(width 0.202)
		(layer "B.Cu")
		(net 105)
	)
	(segment
		(start 194.895232 138.032656)
		(end 195.550799 138.688224)
		(width 0.202)
		(layer "B.Cu")
		(net 105)
	)
	(segment
		(start 196.068144 138.773528)
		(end 196.085821 138.791205)
		(width 0.202)
		(layer "B.Cu")
		(net 105)
	)
	(segment
		(start 195.62903 138.773528)
		(end 196.068144 138.773528)
		(width 0.202)
		(layer "B.Cu")
		(net 105)
	)
	(segment
		(start 195.550799 138.695296)
		(end 195.62903 138.773528)
		(width 0.202)
		(layer "B.Cu")
		(net 105)
	)
	(segment
		(start 195.550799 138.688224)
		(end 195.550799 138.695296)
		(width 0.202)
		(layer "B.Cu")
		(net 105)
	)
	(segment
		(start 103.914999 159.0565)
		(end 102.5135 159.0565)
		(width 0.202)
		(layer "B.Cu")
		(net 106)
	)
	(segment
		(start 104.383 159.112)
		(end 103.970499 159.112)
		(width 0.202)
		(layer "B.Cu")
		(net 106)
	)
	(segment
		(start 102.5135 159.0565)
		(end 102.465 159.105)
		(width 0.202)
		(layer "B.Cu")
		(net 106)
	)
	(segment
		(start 105.155 159.112)
		(end 104.383 159.112)
		(width 0.202)
		(layer "B.Cu")
		(net 106)
	)
	(segment
		(start 107.113929 159.0565)
		(end 105.623001 159.0565)
		(width 0.202)
		(layer "B.Cu")
		(net 106)
	)
	(segment
		(start 105.623001 159.0565)
		(end 105.567501 159.112)
		(width 0.202)
		(layer "B.Cu")
		(net 106)
	)
	(segment
		(start 107.413 159.355571)
		(end 107.113929 159.0565)
		(width 0.202)
		(layer "B.Cu")
		(net 106)
	)
	(segment
		(start 103.970499 159.112)
		(end 103.914999 159.0565)
		(width 0.202)
		(layer "B.Cu")
		(net 106)
	)
	(segment
		(start 105.567501 159.112)
		(end 105.155 159.112)
		(width 0.202)
		(layer "B.Cu")
		(net 106)
	)
	(segment
		(start 141.065 139.455)
		(end 141.065 140.993702)
		(width 0.16)
		(layer "F.Cu")
		(net 107)
	)
	(segment
		(start 141.621298 141.55)
		(end 142.185 141.55)
		(width 0.16)
		(layer "F.Cu")
		(net 107)
	)
	(segment
		(start 140.61 139)
		(end 141.065 139.455)
		(width 0.16)
		(layer "F.Cu")
		(net 107)
	)
	(segment
		(start 142.185 141.55)
		(end 142.495 141.86)
		(width 0.16)
		(layer "F.Cu")
		(net 107)
	)
	(segment
		(start 141.065 140.993702)
		(end 141.621298 141.55)
		(width 0.16)
		(layer "F.Cu")
		(net 107)
	)
	(segment
		(start 143.505 140.86)
		(end 143.815 141.17)
		(width 0.16)
		(layer "F.Cu")
		(net 108)
	)
	(segment
		(start 145.14 141.17)
		(end 145.45 140.86)
		(width 0.16)
		(layer "F.Cu")
		(net 108)
	)
	(segment
		(start 143.815 141.17)
		(end 145.14 141.17)
		(width 0.16)
		(layer "F.Cu")
		(net 108)
	)
	(segment
		(start 142.185 141.17)
		(end 142.495 140.86)
		(width 0.16)
		(layer "F.Cu")
		(net 109)
	)
	(segment
		(start 141.74 140.425)
		(end 141.7 140.425)
		(width 0.16)
		(layer "F.Cu")
		(net 109)
	)
	(segment
		(start 141.445 140.836298)
		(end 141.778702 141.17)
		(width 0.16)
		(layer "F.Cu")
		(net 109)
	)
	(segment
		(start 141.445 139.455)
		(end 141.445 139.66)
		(width 0.16)
		(layer "F.Cu")
		(net 109)
	)
	(segment
		(start 141.9 139)
		(end 141.445 139.455)
		(width 0.16)
		(layer "F.Cu")
		(net 109)
	)
	(segment
		(start 141.7 139.915)
		(end 141.74 139.915)
		(width 0.16)
		(layer "F.Cu")
		(net 109)
	)
	(segment
		(start 141.778702 141.17)
		(end 142.185 141.17)
		(width 0.16)
		(layer "F.Cu")
		(net 109)
	)
	(segment
		(start 141.445 140.68)
		(end 141.445 140.836298)
		(width 0.16)
		(layer "F.Cu")
		(net 109)
	)
	(arc
		(start 141.7 140.425)
		(mid 141.519688 140.499688)
		(end 141.445 140.68)
		(width 0.16)
		(layer "F.Cu")
		(net 109)
	)
	(arc
		(start 141.995 140.17)
		(mid 141.920312 140.350312)
		(end 141.74 140.425)
		(width 0.16)
		(layer "F.Cu")
		(net 109)
	)
	(arc
		(start 141.74 139.915)
		(mid 141.920312 139.989688)
		(end 141.995 140.17)
		(width 0.16)
		(layer "F.Cu")
		(net 109)
	)
	(arc
		(start 141.445 139.66)
		(mid 141.519688 139.840312)
		(end 141.7 139.915)
		(width 0.16)
		(layer "F.Cu")
		(net 109)
	)
	(segment
		(start 143.815 141.55)
		(end 145.14 141.55)
		(width 0.16)
		(layer "F.Cu")
		(net 110)
	)
	(segment
		(start 145.14 141.55)
		(end 145.45 141.86)
		(width 0.16)
		(layer "F.Cu")
		(net 110)
	)
	(segment
		(start 143.505 141.86)
		(end 143.815 141.55)
		(width 0.16)
		(layer "F.Cu")
		(net 110)
	)
	(segment
		(start 198.052965 154.009)
		(end 199.297034 154.009)
		(width 0.16)
		(layer "F.Cu")
		(net 111)
	)
	(segment
		(start 200.025 151.859)
		(end 200.025 151.134)
		(width 0.16)
		(layer "F.Cu")
		(net 111)
	)
	(segment
		(start 197.611881 153.487119)
		(end 197.611881 153.69218)
		(width 0.16)
		(layer "F.Cu")
		(net 111)
	)
	(segment
		(start 199.509166 153.921132)
		(end 199.997132 153.433166)
		(width 0.16)
		(layer "F.Cu")
		(net 111)
	)
	(segment
		(start 197.611881 153.69218)
		(end 197.840833 153.921132)
		(width 0.16)
		(layer "F.Cu")
		(net 111)
	)
	(segment
		(start 200.085 151.919)
		(end 200.025 151.859)
		(width 0.16)
		(layer "F.Cu")
		(net 111)
	)
	(segment
		(start 200.085 153.221034)
		(end 200.085 151.919)
		(width 0.16)
		(layer "F.Cu")
		(net 111)
	)
	(via
		(at 155.615 147.63)
		(size 0.45)
		(drill 0.1)
		(layers "F.Cu" "B.Cu")
		(remove_unused_layers yes)
		(keep_end_layers yes)
		(zone_layer_connections)
		(teardrops
			(best_length_ratio 0.4)
			(max_length 1)
			(best_width_ratio 0.9)
			(max_width 2)
			(curved_edges yes)
			(filter_ratio 0.9)
			(enabled yes)
			(allow_two_segments yes)
			(prefer_zone_connections yes)
		)
		(net 111)
	)
	(via
		(at 197.611881 153.487119)
		(size 0.45)
		(drill 0.1)
		(layers "F.Cu" "B.Cu")
		(teardrops
			(best_length_ratio 0.4)
			(max_length 1)
			(best_width_ratio 0.9)
			(max_width 2)
			(curved_edges yes)
			(filter_ratio 0.9)
			(enabled yes)
			(allow_two_segments yes)
			(prefer_zone_connections yes)
		)
		(net 111)
	)
	(arc
		(start 197.840833 153.921132)
		(mid 197.93816 153.986164)
		(end 198.052965 154.009)
		(width 0.16)
		(layer "F.Cu")
		(net 111)
	)
	(arc
		(start 199.997132 153.433166)
		(mid 200.062164 153.335839)
		(end 200.085 153.221034)
		(width 0.16)
		(layer "F.Cu")
		(net 111)
	)
	(arc
		(start 199.297034 154.009)
		(mid 199.411839 153.986164)
		(end 199.509166 153.921132)
		(width 0.16)
		(layer "F.Cu")
		(net 111)
	)
	(segment
		(start 156.000813 148.969515)
		(end 156.391895 149.360597)
		(width 0.16)
		(layer "B.Cu")
		(net 111)
	)
	(segment
		(start 175.957951 152.025653)
		(end 176.092302 151.891302)
		(width 0.16)
		(layer "B.Cu")
		(net 111)
	)
	(segment
		(start 197.89 154.370595)
		(end 197.89 154.177406)
		(width 0.16)
		(layer "B.Cu")
		(net 111)
	)
	(segment
		(start 171.067745 147.135447)
		(end 171.711684 147.779386)
		(width 0.16)
		(layer "B.Cu")
		(net 111)
	)
	(segment
		(start 197.077868 155.389834)
		(end 197.743554 154.724148)
		(width 0.16)
		(layer "B.Cu")
		(net 111)
	)
	(segment
		(start 158.79 149.59)
		(end 160.23705 149.59)
		(width 0.16)
		(layer "B.Cu")
		(net 111)
	)
	(segment
		(start 191.509166 155.376868)
		(end 193.174852 157.042554)
		(width 0.16)
		(layer "B.Cu")
		(net 111)
	)
	(segment
		(start 177.441458 153.738261)
		(end 177.083661 154.096058)
		(width 0.16)
		(layer "B.Cu")
		(net 111)
	)
	(segment
		(start 179.554949 155.289)
		(end 191.297034 155.289)
		(width 0.16)
		(layer "B.Cu")
		(net 111)
	)
	(segment
		(start 175.066997 151.134699)
		(end 174.594649 151.607046)
		(width 0.16)
		(layer "B.Cu")
		(net 111)
	)
	(segment
		(start 174.847795 150.646795)
		(end 174.982147 150.512446)
		(width 0.16)
		(layer "B.Cu")
		(net 111)
	)
	(segment
		(start 172.577987 148.645689)
		(end 172.105639 149.118036)
		(width 0.16)
		(layer "B.Cu")
		(net 111)
	)
	(segment
		(start 178.685966 154.753668)
		(end 178.705149 154.772851)
		(width 0.16)
		(layer "B.Cu")
		(net 111)
	)
	(segment
		(start 173.319037 147.90464)
		(end 172.961239 148.262435)
		(width 0.16)
		(layer "B.Cu")
		(net 111)
	)
	(segment
		(start 173.603292 149.402292)
		(end 173.603291 149.402291)
		(width 0.16)
		(layer "B.Cu")
		(net 111)
	)
	(segment
		(start 173.468941 149.536643)
		(end 173.603292 149.402292)
		(width 0.16)
		(layer "B.Cu")
		(net 111)
	)
	(segment
		(start 197.743553 153.823852)
		(end 197.699749 153.780048)
		(width 0.16)
		(layer "B.Cu")
		(net 111)
	)
	(segment
		(start 174.563542 149.149145)
		(end 174.091193 149.621491)
		(width 0.16)
		(layer "B.Cu")
		(net 111)
	)
	(segment
		(start 174.241098 151.253495)
		(end 174.713445 150.781147)
		(width 0.16)
		(layer "B.Cu")
		(net 111)
	)
	(segment
		(start 174.847796 150.646796)
		(end 174.847795 150.646795)
		(width 0.16)
		(layer "B.Cu")
		(net 111)
	)
	(segment
		(start 178.297059 152.882662)
		(end 177.939261 153.240457)
		(width 0.16)
		(layer "B.Cu")
		(net 111)
	)
	(segment
		(start 176.092301 151.891301)
		(end 176.206853 151.776752)
		(width 0.16)
		(layer "B.Cu")
		(net 111)
	)
	(segment
		(start 175.485604 152.498001)
		(end 175.957951 152.025653)
		(width 0.16)
		(layer "B.Cu")
		(net 111)
	)
	(segment
		(start 176.206853 151.776752)
		(end 176.341204 151.642401)
		(width 0.16)
		(layer "B.Cu")
		(net 111)
	)
	(segment
		(start 155.615 147.63)
		(end 155.76 147.775)
		(width 0.16)
		(layer "B.Cu")
		(net 111)
	)
	(segment
		(start 177.690359 153.489359)
		(end 177.69036 153.48936)
		(width 0.16)
		(layer "B.Cu")
		(net 111)
	)
	(segment
		(start 176.928101 151.284603)
		(end 177.052551 151.409053)
		(width 0.16)
		(layer "B.Cu")
		(net 111)
	)
	(segment
		(start 193.528405 157.189)
		(end 195.671595 157.189)
		(width 0.16)
		(layer "B.Cu")
		(net 111)
	)
	(segment
		(start 174.091193 149.621491)
		(end 173.822491 149.890193)
		(width 0.16)
		(layer "B.Cu")
		(net 111)
	)
	(segment
		(start 175.201348 151.000348)
		(end 175.066997 151.134699)
		(width 0.16)
		(layer "B.Cu")
		(net 111)
	)
	(segment
		(start 174.713445 150.781147)
		(end 174.847796 150.646796)
		(width 0.16)
		(layer "B.Cu")
		(net 111)
	)
	(segment
		(start 173.194586 147.551088)
		(end 173.319036 147.675538)
		(width 0.16)
		(layer "B.Cu")
		(net 111)
	)
	(segment
		(start 163.585809 146.989)
		(end 170.714191 146.989)
		(width 0.16)
		(layer "B.Cu")
		(net 111)
	)
	(segment
		(start 161.031326 149.336376)
		(end 163.232256 147.135446)
		(width 0.16)
		(layer "B.Cu")
		(net 111)
	)
	(segment
		(start 172.961239 148.262435)
		(end 172.712337 148.511337)
		(width 0.16)
		(layer "B.Cu")
		(net 111)
	)
	(segment
		(start 174.594649 152.373551)
		(end 174.719099 152.498001)
		(width 0.16)
		(layer "B.Cu")
		(net 111)
	)
	(segment
		(start 177.974616 154.987013)
		(end 178.332412 154.629216)
		(width 0.16)
		(layer "B.Cu")
		(net 111)
	)
	(segment
		(start 196.99 155.870595)
		(end 196.99 155.601966)
		(width 0.16)
		(layer "B.Cu")
		(net 111)
	)
	(segment
		(start 160.23705 149.59)
		(end 160.23805 149.589)
		(width 0.16)
		(layer "B.Cu")
		(net 111)
	)
	(segment
		(start 178.172608 152.52911)
		(end 178.297058 152.65356)
		(width 0.16)
		(layer "B.Cu")
		(net 111)
	)
	(segment
		(start 172.996594 150.008991)
		(end 173.468941 149.536643)
		(width 0.16)
		(layer "B.Cu")
		(net 111)
	)
	(segment
		(start 177.585711 152.886907)
		(end 177.943508 152.529111)
		(width 0.16)
		(layer "B.Cu")
		(net 111)
	)
	(segment
		(start 177.575809 153.60391)
		(end 177.441458 153.738261)
		(width 0.16)
		(layer "B.Cu")
		(net 111)
	)
	(segment
		(start 175.434693 150.767001)
		(end 175.335699 150.865996)
		(width 0.16)
		(layer "B.Cu")
		(net 111)
	)
	(segment
		(start 172.712337 148.511337)
		(end 172.712338 148.511338)
		(width 0.16)
		(layer "B.Cu")
		(net 111)
	)
	(segment
		(start 197.611881 153.567916)
		(end 197.611881 153.487119)
		(width 0.16)
		(layer "B.Cu")
		(net 111)
	)
	(segment
		(start 178.561513 154.629216)
		(end 178.685966 154.753668)
		(width 0.16)
		(layer "B.Cu")
		(net 111)
	)
	(segment
		(start 155.76 147.775)
		(end 155.76 148.38814)
		(width 0.16)
		(layer "B.Cu")
		(net 111)
	)
	(segment
		(start 177.69036 153.48936)
		(end 177.575809 153.60391)
		(width 0.16)
		(layer "B.Cu")
		(net 111)
	)
	(segment
		(start 175.201348 151.000347)
		(end 175.201348 151.000348)
		(width 0.16)
		(layer "B.Cu")
		(net 111)
	)
	(segment
		(start 160.23805 149.589)
		(end 160.421438 149.589)
		(width 0.16)
		(layer "B.Cu")
		(net 111)
	)
	(segment
		(start 156.945724 149.59)
		(end 158.79 149.59)
		(width 0.16)
		(layer "B.Cu")
		(net 111)
	)
	(segment
		(start 176.819206 152.886908)
		(end 176.819205 152.886906)
		(width 0.16)
		(layer "B.Cu")
		(net 111)
	)
	(segment
		(start 173.350143 151.129045)
		(end 173.474593 151.253495)
		(width 0.16)
		(layer "B.Cu")
		(net 111)
	)
	(segment
		(start 171.711684 147.779386)
		(end 171.841184 147.908886)
		(width 0.16)
		(layer "B.Cu")
		(net 111)
	)
	(segment
		(start 178.705149 154.772851)
		(end 178.985371 155.053073)
		(width 0.16)
		(layer "B.Cu")
		(net 111)
	)
	(segment
		(start 177.083661 154.862563)
		(end 177.208111 154.987013)
		(width 0.16)
		(layer "B.Cu")
		(net 111)
	)
	(segment
		(start 171.841184 147.908886)
		(end 171.841183 147.908884)
		(width 0.16)
		(layer "B.Cu")
		(net 111)
	)
	(segment
		(start 196.025149 157.042553)
		(end 196.843554 156.224148)
		(width 0.16)
		(layer "B.Cu")
		(net 111)
	)
	(segment
		(start 174.982147 150.512446)
		(end 175.081142 150.413451)
		(width 0.16)
		(layer "B.Cu")
		(net 111)
	)
	(segment
		(start 172.712338 148.511338)
		(end 172.577987 148.645689)
		(width 0.16)
		(layer "B.Cu")
		(net 111)
	)
	(segment
		(start 177.052552 151.638155)
		(end 176.694754 151.99595)
		(width 0.16)
		(layer "B.Cu")
		(net 111)
	)
	(segment
		(start 172.607689 147.908885)
		(end 172.965486 147.551089)
		(width 0.16)
		(layer "B.Cu")
		(net 111)
	)
	(segment
		(start 175.27913 150.41345)
		(end 175.434693 150.569013)
		(width 0.16)
		(layer "B.Cu")
		(net 111)
	)
	(segment
		(start 176.694755 152.762456)
		(end 176.819206 152.886908)
		(width 0.16)
		(layer "B.Cu")
		(net 111)
	)
	(segment
		(start 175.335699 150.865996)
		(end 175.201348 151.000347)
		(width 0.16)
		(layer "B.Cu")
		(net 111)
	)
	(segment
		(start 176.092302 151.891302)
		(end 176.092301 151.891301)
		(width 0.16)
		(layer "B.Cu")
		(net 111)
	)
	(segment
		(start 174.439091 148.795593)
		(end 174.563541 148.920043)
		(width 0.16)
		(layer "B.Cu")
		(net 111)
	)
	(segment
		(start 173.822491 149.890193)
		(end 173.350143 150.36254)
		(width 0.16)
		(layer "B.Cu")
		(net 111)
	)
	(segment
		(start 177.939261 153.240457)
		(end 177.690359 153.489359)
		(width 0.16)
		(layer "B.Cu")
		(net 111)
	)
	(segment
		(start 173.603291 149.402291)
		(end 173.737643 149.267942)
		(width 0.16)
		(layer "B.Cu")
		(net 111)
	)
	(segment
		(start 176.341204 151.642401)
		(end 176.699001 151.284604)
		(width 0.16)
		(layer "B.Cu")
		(net 111)
	)
	(segment
		(start 172.105639 149.884541)
		(end 172.230089 150.008991)
		(width 0.16)
		(layer "B.Cu")
		(net 111)
	)
	(segment
		(start 173.737643 149.267942)
		(end 174.209991 148.795594)
		(width 0.16)
		(layer "B.Cu")
		(net 111)
	)
	(arc
		(start 170.714191 146.989)
		(mid 170.905533 147.02706)
		(end 171.067745 147.135447)
		(width 0.16)
		(layer "B.Cu")
		(net 111)
	)
	(arc
		(start 160.421438 149.589)
		(mid 160.751507 149.523345)
		(end 161.031326 149.336376)
		(width 0.16)
		(layer "B.Cu")
		(net 111)
	)
	(arc
		(start 177.052551 151.409053)
		(mid 177.1 151.523605)
		(end 177.052552 151.638155)
		(width 0.16)
		(layer "B.Cu")
		(net 111)
	)
	(arc
		(start 177.208111 154.987013)
		(mid 177.591364 155.145761)
		(end 177.974616 154.987013)
		(width 0.16)
		(layer "B.Cu")
		(net 111)
	)
	(arc
		(start 156.391895 149.360597)
		(mid 156.645994 149.53038)
		(end 156.945724 149.59)
		(width 0.16)
		(layer "B.Cu")
		(net 111)
	)
	(arc
		(start 171.841183 147.908884)
		(mid 172.224437 148.067633)
		(end 172.607689 147.908885)
		(width 0.16)
		(layer "B.Cu")
		(net 111)
	)
	(arc
		(start 196.99 155.601966)
		(mid 197.012836 155.487161)
		(end 197.077868 155.389834)
		(width 0.16)
		(layer "B.Cu")
		(net 111)
	)
	(arc
		(start 176.694754 151.99595)
		(mid 176.536006 152.379202)
		(end 176.694755 152.762456)
		(width 0.16)
		(layer "B.Cu")
		(net 111)
	)
	(arc
		(start 191.297034 155.289)
		(mid 191.411839 155.311836)
		(end 191.509166 155.376868)
		(width 0.16)
		(layer "B.Cu")
		(net 111)
	)
	(arc
		(start 173.350143 150.36254)
		(mid 173.191395 150.745792)
		(end 173.350143 151.129045)
		(width 0.16)
		(layer "B.Cu")
		(net 111)
	)
	(arc
		(start 174.563541 148.920043)
		(mid 174.61099 149.034595)
		(end 174.563542 149.149145)
		(width 0.16)
		(layer "B.Cu")
		(net 111)
	)
	(arc
		(start 197.743554 154.724148)
		(mid 197.85194 154.561936)
		(end 197.89 154.370595)
		(width 0.16)
		(layer "B.Cu")
		(net 111)
	)
	(arc
		(start 178.985371 155.053073)
		(mid 179.246696 155.227685)
		(end 179.554949 155.289)
		(width 0.16)
		(layer "B.Cu")
		(net 111)
	)
	(arc
		(start 174.719099 152.498001)
		(mid 175.102352 152.656749)
		(end 175.485604 152.498001)
		(width 0.16)
		(layer "B.Cu")
		(net 111)
	)
	(arc
		(start 172.230089 150.008991)
		(mid 172.613342 150.167739)
		(end 172.996594 150.008991)
		(width 0.16)
		(layer "B.Cu")
		(net 111)
	)
	(arc
		(start 173.319036 147.675538)
		(mid 173.366485 147.79009)
		(end 173.319037 147.90464)
		(width 0.16)
		(layer "B.Cu")
		(net 111)
	)
	(arc
		(start 177.943508 152.529111)
		(mid 178.058058 152.481663)
		(end 178.172608 152.52911)
		(width 0.16)
		(layer "B.Cu")
		(net 111)
	)
	(arc
		(start 163.232256 147.135446)
		(mid 163.394468 147.02706)
		(end 163.585809 146.989)
		(width 0.16)
		(layer "B.Cu")
		(net 111)
	)
	(arc
		(start 155.76 148.38814)
		(mid 155.822585 148.702778)
		(end 156.000813 148.969515)
		(width 0.16)
		(layer "B.Cu")
		(net 111)
	)
	(arc
		(start 172.965486 147.551089)
		(mid 173.080036 147.503641)
		(end 173.194586 147.551088)
		(width 0.16)
		(layer "B.Cu")
		(net 111)
	)
	(arc
		(start 176.819205 152.886906)
		(mid 177.202459 153.045655)
		(end 177.585711 152.886907)
		(width 0.16)
		(layer "B.Cu")
		(net 111)
	)
	(arc
		(start 174.209991 148.795594)
		(mid 174.324541 148.748146)
		(end 174.439091 148.795593)
		(width 0.16)
		(layer "B.Cu")
		(net 111)
	)
	(arc
		(start 175.434693 150.569013)
		(mid 175.475699 150.668008)
		(end 175.434693 150.767001)
		(width 0.16)
		(layer "B.Cu")
		(net 111)
	)
	(arc
		(start 197.89 154.177406)
		(mid 197.85194 153.986064)
		(end 197.743553 153.823852)
		(width 0.16)
		(layer "B.Cu")
		(net 111)
	)
	(arc
		(start 177.083661 154.096058)
		(mid 176.924913 154.47931)
		(end 177.083661 154.862563)
		(width 0.16)
		(layer "B.Cu")
		(net 111)
	)
	(arc
		(start 175.081142 150.413451)
		(mid 175.180135 150.372445)
		(end 175.27913 150.41345)
		(width 0.16)
		(layer "B.Cu")
		(net 111)
	)
	(arc
		(start 178.332412 154.629216)
		(mid 178.446962 154.581768)
		(end 178.561513 154.629216)
		(width 0.16)
		(layer "B.Cu")
		(net 111)
	)
	(arc
		(start 197.699749 153.780048)
		(mid 197.634717 153.682721)
		(end 197.611881 153.567916)
		(width 0.16)
		(layer "B.Cu")
		(net 111)
	)
	(arc
		(start 195.671595 157.189)
		(mid 195.862937 157.15094)
		(end 196.025149 157.042553)
		(width 0.16)
		(layer "B.Cu")
		(net 111)
	)
	(arc
		(start 176.699001 151.284604)
		(mid 176.813551 151.237156)
		(end 176.928101 151.284603)
		(width 0.16)
		(layer "B.Cu")
		(net 111)
	)
	(arc
		(start 172.105639 149.118036)
		(mid 171.946891 149.501288)
		(end 172.105639 149.884541)
		(width 0.16)
		(layer "B.Cu")
		(net 111)
	)
	(arc
		(start 178.297058 152.65356)
		(mid 178.344507 152.768112)
		(end 178.297059 152.882662)
		(width 0.16)
		(layer "B.Cu")
		(net 111)
	)
	(arc
		(start 193.174852 157.042554)
		(mid 193.337064 157.15094)
		(end 193.528405 157.189)
		(width 0.16)
		(layer "B.Cu")
		(net 111)
	)
	(arc
		(start 196.843554 156.224148)
		(mid 196.95194 156.061936)
		(end 196.99 155.870595)
		(width 0.16)
		(layer "B.Cu")
		(net 111)
	)
	(arc
		(start 173.474593 151.253495)
		(mid 173.857846 151.412243)
		(end 174.241098 151.253495)
		(width 0.16)
		(layer "B.Cu")
		(net 111)
	)
	(arc
		(start 174.594649 151.607046)
		(mid 174.435901 151.990298)
		(end 174.594649 152.373551)
		(width 0.16)
		(layer "B.Cu")
		(net 111)
	)
	(segment
		(start 155.57 146.96)
		(end 155.76 146.77)
		(width 0.16)
		(layer "F.Cu")
		(net 112)
	)
	(segment
		(start 155.76 143.17)
		(end 155.45 142.86)
		(width 0.16)
		(layer "F.Cu")
		(net 112)
	)
	(segment
		(start 155.76 146.77)
		(end 155.76 143.17)
		(width 0.16)
		(layer "F.Cu")
		(net 112)
	)
	(segment
		(start 200.525 151.859)
		(end 200.465 151.919)
		(width 0.16)
		(layer "F.Cu")
		(net 113)
	)
	(segment
		(start 200.318553 153.649149)
		(end 199.725148 154.242554)
		(width 0.16)
		(layer "F.Cu")
		(net 113)
	)
	(segment
		(start 197.34318 153.960881)
		(end 197.138119 153.960881)
		(width 0.16)
		(layer "F.Cu")
		(net 113)
	)
	(segment
		(start 200.525 151.134)
		(end 200.525 151.859)
		(width 0.16)
		(layer "F.Cu")
		(net 113)
	)
	(segment
		(start 199.371595 154.389)
		(end 197.978406 154.389)
		(width 0.16)
		(layer "F.Cu")
		(net 113)
	)
	(segment
		(start 197.624852 154.242553)
		(end 197.34318 153.960881)
		(width 0.16)
		(layer "F.Cu")
		(net 113)
	)
	(segment
		(start 200.465 151.919)
		(end 200.465 153.295595)
		(width 0.16)
		(layer "F.Cu")
		(net 113)
	)
	(via
		(at 156.285 147.63)
		(size 0.45)
		(drill 0.1)
		(layers "F.Cu" "B.Cu")
		(remove_unused_layers yes)
		(keep_end_layers yes)
		(zone_layer_connections)
		(teardrops
			(best_length_ratio 0.4)
			(max_length 1)
			(best_width_ratio 0.9)
			(max_width 2)
			(curved_edges yes)
			(filter_ratio 0.9)
			(enabled yes)
			(allow_two_segments yes)
			(prefer_zone_connections yes)
		)
		(net 113)
	)
	(via
		(at 197.138119 153.960881)
		(size 0.45)
		(drill 0.1)
		(layers "F.Cu" "B.Cu")
		(teardrops
			(best_length_ratio 0.4)
			(max_length 1)
			(best_width_ratio 0.9)
			(max_width 2)
			(curved_edges yes)
			(filter_ratio 0.9)
			(enabled yes)
			(allow_two_segments yes)
			(prefer_zone_connections yes)
		)
		(net 113)
	)
	(arc
		(start 199.725148 154.242554)
		(mid 199.562936 154.35094)
		(end 199.371595 154.389)
		(width 0.16)
		(layer "F.Cu")
		(net 113)
	)
	(arc
		(start 200.318553 153.649149)
		(mid 200.42694 153.486937)
		(end 200.465 153.295595)
		(width 0.16)
		(layer "F.Cu")
		(net 113)
	)
	(arc
		(start 197.624852 154.242553)
		(mid 197.787064 154.35094)
		(end 197.978406 154.389)
		(width 0.16)
		(layer "F.Cu")
		(net 113)
	)
	(segment
		(start 175.547832 150.144748)
		(end 175.703395 150.300311)
		(width 0.16)
		(layer "B.Cu")
		(net 113)
	)
	(segment
		(start 177.705914 154.718311)
		(end 178.06371 154.360514)
		(width 0.16)
		(layer "B.Cu")
		(net 113)
	)
	(segment
		(start 173.200239 149.267941)
		(end 173.468941 148.999239)
		(width 0.16)
		(layer "B.Cu")
		(net 113)
	)
	(segment
		(start 178.973851 154.504149)
		(end 179.232255 154.762553)
		(width 0.16)
		(layer "B.Cu")
		(net 113)
	)
	(segment
		(start 172.374341 149.615839)
		(end 172.498791 149.740289)
		(width 0.16)
		(layer "B.Cu")
		(net 113)
	)
	(segment
		(start 176.0725 151.373697)
		(end 176.430297 151.0159)
		(width 0.16)
		(layer "B.Cu")
		(net 113)
	)
	(segment
		(start 172.338988 147.640185)
		(end 172.696783 147.282387)
		(width 0.16)
		(layer "B.Cu")
		(net 113)
	)
	(segment
		(start 196.61 155.796034)
		(end 196.61 155.527405)
		(width 0.16)
		(layer "B.Cu")
		(net 113)
	)
	(segment
		(start 173.618845 150.860343)
		(end 173.743295 150.984793)
		(width 0.16)
		(layer "B.Cu")
		(net 113)
	)
	(segment
		(start 173.468941 148.999239)
		(end 173.941287 148.52689)
		(width 0.16)
		(layer "B.Cu")
		(net 113)
	)
	(segment
		(start 160.092632 149.209)
		(end 160.414191 149.209)
		(width 0.16)
		(layer "B.Cu")
		(net 113)
	)
	(segment
		(start 174.225544 150.024544)
		(end 174.225543 150.024543)
		(width 0.16)
		(layer "B.Cu")
		(net 113)
	)
	(segment
		(start 175.47005 151.269049)
		(end 175.470049 151.269049)
		(width 0.16)
		(layer "B.Cu")
		(net 113)
	)
	(segment
		(start 172.727892 149.740289)
		(end 173.200239 149.267941)
		(width 0.16)
		(layer "B.Cu")
		(net 113)
	)
	(segment
		(start 174.091193 150.158894)
		(end 173.618845 150.631242)
		(width 0.16)
		(layer "B.Cu")
		(net 113)
	)
	(segment
		(start 157.916954 149.21)
		(end 158.34 149.21)
		(width 0.16)
		(layer "B.Cu")
		(net 113)
	)
	(segment
		(start 174.713445 150.243743)
		(end 174.812438 150.144747)
		(width 0.16)
		(layer "B.Cu")
		(net 113)
	)
	(segment
		(start 196.438847 156.091451)
		(end 196.522132 156.008166)
		(width 0.16)
		(layer "B.Cu")
		(net 113)
	)
	(segment
		(start 197.51 154.296034)
		(end 197.51 154.251965)
		(width 0.16)
		(layer "B.Cu")
		(net 113)
	)
	(segment
		(start 172.846689 148.91439)
		(end 172.374341 149.386738)
		(width 0.16)
		(layer "B.Cu")
		(net 113)
	)
	(segment
		(start 196.756447 155.173851)
		(end 196.765649 155.164649)
		(width 0.16)
		(layer "B.Cu")
		(net 113)
	)
	(segment
		(start 174.444743 150.512445)
		(end 174.713445 150.243743)
		(width 0.16)
		(layer "B.Cu")
		(net 113)
	)
	(segment
		(start 176.963457 152.493754)
		(end 177.087908 152.618206)
		(width 0.16)
		(layer "B.Cu")
		(net 113)
	)
	(segment
		(start 178.441311 152.26041)
		(end 178.565761 152.38486)
		(width 0.16)
		(layer "B.Cu")
		(net 113)
	)
	(segment
		(start 156.285 147.63)
		(end 156.14 147.775)
		(width 0.16)
		(layer "B.Cu")
		(net 113)
	)
	(segment
		(start 195.809166 156.721132)
		(end 195.825649 156.704649)
		(width 0.16)
		(layer "B.Cu")
		(net 113)
	)
	(segment
		(start 174.863351 152.104849)
		(end 174.987801 152.229299)
		(width 0.16)
		(layer "B.Cu")
		(net 113)
	)
	(segment
		(start 174.359895 149.890193)
		(end 174.225544 150.024544)
		(width 0.16)
		(layer "B.Cu")
		(net 113)
	)
	(segment
		(start 171.980386 147.510684)
		(end 172.109886 147.640184)
		(width 0.16)
		(layer "B.Cu")
		(net 113)
	)
	(segment
		(start 175.689249 151.756951)
		(end 175.8236 151.6226)
		(width 0.16)
		(layer "B.Cu")
		(net 113)
	)
	(segment
		(start 178.830215 154.360514)
		(end 178.954668 154.484966)
		(width 0.16)
		(layer "B.Cu")
		(net 113)
	)
	(segment
		(start 197.34318 153.960881)
		(end 197.138119 153.960881)
		(width 0.16)
		(layer "B.Cu")
		(net 113)
	)
	(segment
		(start 157.400954 148.765909)
		(end 157.486954 148.765909)
		(width 0.16)
		(layer "B.Cu")
		(net 113)
	)
	(segment
		(start 156.14 147.775)
		(end 156.14 148.364191)
		(width 0.16)
		(layer "B.Cu")
		(net 113)
	)
	(segment
		(start 177.31701 152.618207)
		(end 177.674805 152.260409)
		(width 0.16)
		(layer "B.Cu")
		(net 113)
	)
	(segment
		(start 177.352363 154.593861)
		(end 177.476813 154.718311)
		(width 0.16)
		(layer "B.Cu")
		(net 113)
	)
	(segment
		(start 171.326709 146.857007)
		(end 171.980386 147.510684)
		(width 0.16)
		(layer "B.Cu")
		(net 113)
	)
	(segment
		(start 175.8236 151.6226)
		(end 175.938149 151.508048)
		(width 0.16)
		(layer "B.Cu")
		(net 113)
	)
	(segment
		(start 178.954668 154.484966)
		(end 178.973851 154.504149)
		(width 0.16)
		(layer "B.Cu")
		(net 113)
	)
	(segment
		(start 195.825649 156.704649)
		(end 196.438847 156.091451)
		(width 0.16)
		(layer "B.Cu")
		(net 113)
	)
	(segment
		(start 156.985809 149.21)
		(end 157.056954 149.21)
		(width 0.16)
		(layer "B.Cu")
		(net 113)
	)
	(segment
		(start 177.196803 151.015901)
		(end 177.321253 151.140351)
		(width 0.16)
		(layer "B.Cu")
		(net 113)
	)
	(segment
		(start 157.658954 148.937909)
		(end 157.658954 149.038)
		(width 0.16)
		(layer "B.Cu")
		(net 113)
	)
	(segment
		(start 160.767745 149.062553)
		(end 162.964747 146.865551)
		(width 0.16)
		(layer "B.Cu")
		(net 113)
	)
	(segment
		(start 172.109886 147.640184)
		(end 172.109884 147.640183)
		(width 0.16)
		(layer "B.Cu")
		(net 113)
	)
	(segment
		(start 156.286447 148.717745)
		(end 156.632256 149.063554)
		(width 0.16)
		(layer "B.Cu")
		(net 113)
	)
	(segment
		(start 174.225543 150.024543)
		(end 174.091193 150.158894)
		(width 0.16)
		(layer "B.Cu")
		(net 113)
	)
	(segment
		(start 174.832244 149.417847)
		(end 174.359895 149.890193)
		(width 0.16)
		(layer "B.Cu")
		(net 113)
	)
	(segment
		(start 197.422132 154.039833)
		(end 197.34318 153.960881)
		(width 0.16)
		(layer "B.Cu")
		(net 113)
	)
	(segment
		(start 173.229942 148.531139)
		(end 172.98104 148.780041)
		(width 0.16)
		(layer "B.Cu")
		(net 113)
	)
	(segment
		(start 172.981039 148.780039)
		(end 172.846689 148.91439)
		(width 0.16)
		(layer "B.Cu")
		(net 113)
	)
	(segment
		(start 157.228954 149.038)
		(end 157.228954 148.937909)
		(width 0.16)
		(layer "B.Cu")
		(net 113)
	)
	(segment
		(start 177.959062 153.758063)
		(end 177.959061 153.758061)
		(width 0.16)
		(layer "B.Cu")
		(net 113)
	)
	(segment
		(start 173.463289 147.282388)
		(end 173.587739 147.406838)
		(width 0.16)
		(layer "B.Cu")
		(net 113)
	)
	(segment
		(start 196.765649 155.164649)
		(end 196.865649 155.064649)
		(width 0.16)
		(layer "B.Cu")
		(net 113)
	)
	(segment
		(start 177.844511 153.872612)
		(end 177.71016 154.006963)
		(width 0.16)
		(layer "B.Cu")
		(net 113)
	)
	(segment
		(start 175.335699 151.4034)
		(end 174.863351 151.875748)
		(width 0.16)
		(layer "B.Cu")
		(net 113)
	)
	(segment
		(start 160.091632 149.21)
		(end 160.092632 149.209)
		(width 0.16)
		(layer "B.Cu")
		(net 113)
	)
	(segment
		(start 177.321254 151.906857)
		(end 176.963456 152.264652)
		(width 0.16)
		(layer "B.Cu")
		(net 113)
	)
	(segment
		(start 175.470049 151.269049)
		(end 175.335699 151.4034)
		(width 0.16)
		(layer "B.Cu")
		(net 113)
	)
	(segment
		(start 197.414075 154.516223)
		(end 197.422132 154.508166)
		(width 0.16)
		(layer "B.Cu")
		(net 113)
	)
	(segment
		(start 172.98104 148.780041)
		(end 172.981039 148.780039)
		(width 0.16)
		(layer "B.Cu")
		(net 113)
	)
	(segment
		(start 191.725149 155.055447)
		(end 193.390834 156.721132)
		(width 0.16)
		(layer "B.Cu")
		(net 113)
	)
	(segment
		(start 163.584116 146.609)
		(end 170.727968 146.609)
		(width 0.16)
		(layer "B.Cu")
		(net 113)
	)
	(segment
		(start 195.58 156.809)
		(end 195.597034 156.809)
		(width 0.16)
		(layer "B.Cu")
		(net 113)
	)
	(segment
		(start 173.972396 150.984793)
		(end 174.444743 150.512445)
		(width 0.16)
		(layer "B.Cu")
		(net 113)
	)
	(segment
		(start 193.602966 156.809)
		(end 195.58 156.809)
		(width 0.16)
		(layer "B.Cu")
		(net 113)
	)
	(segment
		(start 175.938149 151.508048)
		(end 176.0725 151.373697)
		(width 0.16)
		(layer "B.Cu")
		(net 113)
	)
	(segment
		(start 178.56576 153.151364)
		(end 178.207964 153.509161)
		(width 0.16)
		(layer "B.Cu")
		(net 113)
	)
	(segment
		(start 173.587738 148.173342)
		(end 173.229942 148.531139)
		(width 0.16)
		(layer "B.Cu")
		(net 113)
	)
	(segment
		(start 177.71016 154.006963)
		(end 177.352363 154.36476)
		(width 0.16)
		(layer "B.Cu")
		(net 113)
	)
	(segment
		(start 196.865649 155.064649)
		(end 197.414075 154.516223)
		(width 0.16)
		(layer "B.Cu")
		(net 113)
	)
	(segment
		(start 175.216902 152.229299)
		(end 175.689249 151.756951)
		(width 0.16)
		(layer "B.Cu")
		(net 113)
	)
	(segment
		(start 179.585809 154.909)
		(end 191.371595 154.909)
		(width 0.16)
		(layer "B.Cu")
		(net 113)
	)
	(segment
		(start 157.830954 149.21)
		(end 157.916954 149.21)
		(width 0.16)
		(layer "B.Cu")
		(net 113)
	)
	(segment
		(start 178.207964 153.509161)
		(end 177.959062 153.758063)
		(width 0.16)
		(layer "B.Cu")
		(net 113)
	)
	(segment
		(start 177.959061 153.758061)
		(end 177.844511 153.872612)
		(width 0.16)
		(layer "B.Cu")
		(net 113)
	)
	(segment
		(start 175.703395 151.035703)
		(end 175.604401 151.134698)
		(width 0.16)
		(layer "B.Cu")
		(net 113)
	)
	(segment
		(start 158.34 149.21)
		(end 160.091632 149.21)
		(width 0.16)
		(layer "B.Cu")
		(net 113)
	)
	(segment
		(start 174.707793 148.526891)
		(end 174.832243 148.651341)
		(width 0.16)
		(layer "B.Cu")
		(net 113)
	)
	(segment
		(start 177.087908 152.618206)
		(end 177.087906 152.618205)
		(width 0.16)
		(layer "B.Cu")
		(net 113)
	)
	(segment
		(start 175.604401 151.134698)
		(end 175.47005 151.269049)
		(width 0.16)
		(layer "B.Cu")
		(net 113)
	)
	(arc
		(start 173.941287 148.52689)
		(mid 174.324539 148.368142)
		(end 174.707793 148.526891)
		(width 0.16)
		(layer "B.Cu")
		(net 113)
	)
	(arc
		(start 196.522132 156.008166)
		(mid 196.587164 155.910839)
		(end 196.61 155.796034)
		(width 0.16)
		(layer "B.Cu")
		(net 113)
	)
	(arc
		(start 173.743295 150.984793)
		(mid 173.857846 151.032241)
		(end 173.972396 150.984793)
		(width 0.16)
		(layer "B.Cu")
		(net 113)
	)
	(arc
		(start 174.812438 150.144747)
		(mid 175.180135 149.992443)
		(end 175.547832 150.144748)
		(width 0.16)
		(layer "B.Cu")
		(net 113)
	)
	(arc
		(start 157.486954 148.765909)
		(mid 157.608576 148.816287)
		(end 157.658954 148.937909)
		(width 0.16)
		(layer "B.Cu")
		(net 113)
	)
	(arc
		(start 157.056954 149.21)
		(mid 157.178576 149.159622)
		(end 157.228954 149.038)
		(width 0.16)
		(layer "B.Cu")
		(net 113)
	)
	(arc
		(start 162.964747 146.865551)
		(mid 163.248916 146.675675)
		(end 163.584116 146.609)
		(width 0.16)
		(layer "B.Cu")
		(net 113)
	)
	(arc
		(start 176.430297 151.0159)
		(mid 176.813549 150.857152)
		(end 177.196803 151.015901)
		(width 0.16)
		(layer "B.Cu")
		(net 113)
	)
	(arc
		(start 156.632256 149.063554)
		(mid 156.794468 149.17194)
		(end 156.985809 149.21)
		(width 0.16)
		(layer "B.Cu")
		(net 113)
	)
	(arc
		(start 174.987801 152.229299)
		(mid 175.102352 152.276747)
		(end 175.216902 152.229299)
		(width 0.16)
		(layer "B.Cu")
		(net 113)
	)
	(arc
		(start 179.232255 154.762553)
		(mid 179.394467 154.87094)
		(end 179.585809 154.909)
		(width 0.16)
		(layer "B.Cu")
		(net 113)
	)
	(arc
		(start 191.371595 154.909)
		(mid 191.562937 154.94706)
		(end 191.725149 155.055447)
		(width 0.16)
		(layer "B.Cu")
		(net 113)
	)
	(arc
		(start 177.087906 152.618205)
		(mid 177.202459 152.665656)
		(end 177.31701 152.618207)
		(width 0.16)
		(layer "B.Cu")
		(net 113)
	)
	(arc
		(start 177.321253 151.140351)
		(mid 177.480002 151.523605)
		(end 177.321254 151.906857)
		(width 0.16)
		(layer "B.Cu")
		(net 113)
	)
	(arc
		(start 177.674805 152.260409)
		(mid 178.058057 152.101661)
		(end 178.441311 152.26041)
		(width 0.16)
		(layer "B.Cu")
		(net 113)
	)
	(arc
		(start 177.476813 154.718311)
		(mid 177.591364 154.765759)
		(end 177.705914 154.718311)
		(width 0.16)
		(layer "B.Cu")
		(net 113)
	)
	(arc
		(start 196.61 155.527405)
		(mid 196.64806 155.336063)
		(end 196.756447 155.173851)
		(width 0.16)
		(layer "B.Cu")
		(net 113)
	)
	(arc
		(start 197.422132 154.508166)
		(mid 197.487164 154.410839)
		(end 197.51 154.296034)
		(width 0.16)
		(layer "B.Cu")
		(net 113)
	)
	(arc
		(start 175.703395 150.300311)
		(mid 175.855701 150.668008)
		(end 175.703395 151.035703)
		(width 0.16)
		(layer "B.Cu")
		(net 113)
	)
	(arc
		(start 170.727968 146.609)
		(mid 171.052004 146.673455)
		(end 171.326709 146.857007)
		(width 0.16)
		(layer "B.Cu")
		(net 113)
	)
	(arc
		(start 172.498791 149.740289)
		(mid 172.613342 149.787737)
		(end 172.727892 149.740289)
		(width 0.16)
		(layer "B.Cu")
		(net 113)
	)
	(arc
		(start 174.863351 151.875748)
		(mid 174.815903 151.990298)
		(end 174.863351 152.104849)
		(width 0.16)
		(layer "B.Cu")
		(net 113)
	)
	(arc
		(start 177.352363 154.36476)
		(mid 177.304915 154.47931)
		(end 177.352363 154.593861)
		(width 0.16)
		(layer "B.Cu")
		(net 113)
	)
	(arc
		(start 173.618845 150.631242)
		(mid 173.571397 150.745792)
		(end 173.618845 150.860343)
		(width 0.16)
		(layer "B.Cu")
		(net 113)
	)
	(arc
		(start 172.109884 147.640183)
		(mid 172.224437 147.687634)
		(end 172.338988 147.640185)
		(width 0.16)
		(layer "B.Cu")
		(net 113)
	)
	(arc
		(start 157.228954 148.937909)
		(mid 157.279332 148.816287)
		(end 157.400954 148.765909)
		(width 0.16)
		(layer "B.Cu")
		(net 113)
	)
	(arc
		(start 156.14 148.364191)
		(mid 156.17806 148.555533)
		(end 156.286447 148.717745)
		(width 0.16)
		(layer "B.Cu")
		(net 113)
	)
	(arc
		(start 178.06371 154.360514)
		(mid 178.446962 154.201766)
		(end 178.830215 154.360514)
		(width 0.16)
		(layer "B.Cu")
		(net 113)
	)
	(arc
		(start 173.587739 147.406838)
		(mid 173.746486 147.79009)
		(end 173.587738 148.173342)
		(width 0.16)
		(layer "B.Cu")
		(net 113)
	)
	(arc
		(start 195.597034 156.809)
		(mid 195.711839 156.786164)
		(end 195.809166 156.721132)
		(width 0.16)
		(layer "B.Cu")
		(net 113)
	)
	(arc
		(start 172.696783 147.282387)
		(mid 173.080035 147.123639)
		(end 173.463289 147.282388)
		(width 0.16)
		(layer "B.Cu")
		(net 113)
	)
	(arc
		(start 193.390834 156.721132)
		(mid 193.488161 156.786164)
		(end 193.602966 156.809)
		(width 0.16)
		(layer "B.Cu")
		(net 113)
	)
	(arc
		(start 172.374341 149.386738)
		(mid 172.326893 149.501288)
		(end 172.374341 149.615839)
		(width 0.16)
		(layer "B.Cu")
		(net 113)
	)
	(arc
		(start 160.414191 149.209)
		(mid 160.605533 149.17094)
		(end 160.767745 149.062553)
		(width 0.16)
		(layer "B.Cu")
		(net 113)
	)
	(arc
		(start 197.51 154.251965)
		(mid 197.487164 154.13716)
		(end 197.422132 154.039833)
		(width 0.16)
		(layer "B.Cu")
		(net 113)
	)
	(arc
		(start 174.832243 148.651341)
		(mid 174.990992 149.034595)
		(end 174.832244 149.417847)
		(width 0.16)
		(layer "B.Cu")
		(net 113)
	)
	(arc
		(start 157.658954 149.038)
		(mid 157.709332 149.159622)
		(end 157.830954 149.21)
		(width 0.16)
		(layer "B.Cu")
		(net 113)
	)
	(arc
		(start 176.963456 152.264652)
		(mid 176.916008 152.379202)
		(end 176.963457 152.493754)
		(width 0.16)
		(layer "B.Cu")
		(net 113)
	)
	(arc
		(start 178.565761 152.38486)
		(mid 178.724508 152.768112)
		(end 178.56576 153.151364)
		(width 0.16)
		(layer "B.Cu")
		(net 113)
	)
	(segment
		(start 156.33 146.96)
		(end 156.14 146.77)
		(width 0.16)
		(layer "F.Cu")
		(net 114)
	)
	(segment
		(start 156.14 146.77)
		(end 156.14 143.17)
		(width 0.16)
		(layer "F.Cu")
		(net 114)
	)
	(segment
		(start 156.14 143.17)
		(end 156.45 142.86)
		(width 0.16)
		(layer "F.Cu")
		(net 114)
	)
	(segment
		(start 122.905 140.993702)
		(end 123.461298 141.55)
		(width 0.16)
		(layer "F.Cu")
		(net 115)
	)
	(segment
		(start 124.025 141.55)
		(end 124.335 141.86)
		(width 0.16)
		(layer "F.Cu")
		(net 115)
	)
	(segment
		(start 122.905 139.455)
		(end 122.905 140.993702)
		(width 0.16)
		(layer "F.Cu")
		(net 115)
	)
	(segment
		(start 123.461298 141.55)
		(end 124.025 141.55)
		(width 0.16)
		(layer "F.Cu")
		(net 115)
	)
	(segment
		(start 122.45 139)
		(end 122.905 139.455)
		(width 0.16)
		(layer "F.Cu")
		(net 115)
	)
	(segment
		(start 125.655 141.17)
		(end 126.98 141.17)
		(width 0.16)
		(layer "F.Cu")
		(net 116)
	)
	(segment
		(start 125.345 140.86)
		(end 125.655 141.17)
		(width 0.16)
		(layer "F.Cu")
		(net 116)
	)
	(segment
		(start 126.98 141.17)
		(end 127.29 140.86)
		(width 0.16)
		(layer "F.Cu")
		(net 116)
	)
	(segment
		(start 123.285 140.68)
		(end 123.285 140.836298)
		(width 0.16)
		(layer "F.Cu")
		(net 117)
	)
	(segment
		(start 123.58 140.425)
		(end 123.54 140.425)
		(width 0.16)
		(layer "F.Cu")
		(net 117)
	)
	(segment
		(start 123.54 139.915)
		(end 123.58 139.915)
		(width 0.16)
		(layer "F.Cu")
		(net 117)
	)
	(segment
		(start 123.74 139)
		(end 123.285 139.455)
		(width 0.16)
		(layer "F.Cu")
		(net 117)
	)
	(segment
		(start 123.285 140.836298)
		(end 123.618702 141.17)
		(width 0.16)
		(layer "F.Cu")
		(net 117)
	)
	(segment
		(start 123.285 139.455)
		(end 123.285 139.66)
		(width 0.16)
		(layer "F.Cu")
		(net 117)
	)
	(segment
		(start 124.025 141.17)
		(end 124.335 140.86)
		(width 0.16)
		(layer "F.Cu")
		(net 117)
	)
	(segment
		(start 123.618702 141.17)
		(end 124.025 141.17)
		(width 0.16)
		(layer "F.Cu")
		(net 117)
	)
	(arc
		(start 123.58 139.915)
		(mid 123.760312 139.989688)
		(end 123.835 140.17)
		(width 0.16)
		(layer "F.Cu")
		(net 117)
	)
	(arc
		(start 123.835 140.17)
		(mid 123.760312 140.350312)
		(end 123.58 140.425)
		(width 0.16)
		(layer "F.Cu")
		(net 117)
	)
	(arc
		(start 123.285 139.66)
		(mid 123.359688 139.840312)
		(end 123.54 139.915)
		(width 0.16)
		(layer "F.Cu")
		(net 117)
	)
	(arc
		(start 123.54 140.425)
		(mid 123.359688 140.499688)
		(end 123.285 140.68)
		(width 0.16)
		(layer "F.Cu")
		(net 117)
	)
	(segment
		(start 125.345 141.86)
		(end 125.655 141.55)
		(width 0.16)
		(layer "F.Cu")
		(net 118)
	)
	(segment
		(start 125.655 141.55)
		(end 126.98 141.55)
		(width 0.16)
		(layer "F.Cu")
		(net 118)
	)
	(segment
		(start 126.98 141.55)
		(end 127.29 141.86)
		(width 0.16)
		(layer "F.Cu")
		(net 118)
	)
	(segment
		(start 196.585 151.92)
		(end 196.585 152.330736)
		(width 0.16)
		(layer "F.Cu")
		(net 119)
	)
	(segment
		(start 196.525 151.135)
		(end 196.525 151.86)
		(width 0.16)
		(layer "F.Cu")
		(net 119)
	)
	(segment
		(start 196.525 151.86)
		(end 196.585 151.92)
		(width 0.16)
		(layer "F.Cu")
		(net 119)
	)
	(segment
		(start 196.497132 152.542868)
		(end 196.44 152.6)
		(width 0.16)
		(layer "F.Cu")
		(net 119)
	)
	(via
		(at 137.46 147.62)
		(size 0.45)
		(drill 0.1)
		(layers "F.Cu" "B.Cu")
		(remove_unused_layers yes)
		(keep_end_layers yes)
		(zone_layer_connections)
		(teardrops
			(best_length_ratio 0.4)
			(max_length 1)
			(best_width_ratio 0.9)
			(max_width 2)
			(curved_edges yes)
			(filter_ratio 0.9)
			(enabled yes)
			(allow_two_segments yes)
			(prefer_zone_connections yes)
		)
		(net 119)
	)
	(via
		(at 196.44 152.6)
		(size 0.45)
		(drill 0.1)
		(layers "F.Cu" "B.Cu")
		(teardrops
			(best_length_ratio 0.4)
			(max_length 1)
			(best_width_ratio 0.9)
			(max_width 2)
			(curved_edges yes)
			(filter_ratio 0.9)
			(enabled yes)
			(allow_two_segments yes)
			(prefer_zone_connections yes)
		)
		(net 119)
	)
	(arc
		(start 196.585 152.330736)
		(mid 196.562164 152.445541)
		(end 196.497132 152.542868)
		(width 0.16)
		(layer "F.Cu")
		(net 119)
	)
	(segment
		(start 160.978405 143.36)
		(end 180.821595 143.36)
		(width 0.16)
		(layer "B.Cu")
		(net 119)
	)
	(segment
		(start 138.618405 144.52)
		(end 159.487034 144.52)
		(width 0.16)
		(layer "B.Cu")
		(net 119)
	)
	(segment
		(start 185.83255 148.163848)
		(end 185.534241 147.865539)
		(width 0.16)
		(layer "B.Cu")
		(net 119)
	)
	(segment
		(start 196.44 152.6)
		(end 196.520711 152.680711)
		(width 0.16)
		(layer "B.Cu")
		(net 119)
	)
	(segment
		(start 181.718314 145.873949)
		(end 181.845593 146.001228)
		(width 0.16)
		(layer "B.Cu")
		(net 119)
	)
	(segment
		(start 182.375924 144.975924)
		(end 182.255717 145.096132)
		(width 0.16)
		(layer "B.Cu")
		(net 119)
	)
	(segment
		(start 186.829569 149.698273)
		(end 186.96392 149.563922)
		(width 0.16)
		(layer "B.Cu")
		(net 119)
	)
	(segment
		(start 196.52071 152.90429)
		(end 196.444289 152.980711)
		(width 0.16)
		(layer "B.Cu")
		(net 119)
	)
	(segment
		(start 137.46 147.62)
		(end 137.605 147.475)
		(width 0.16)
		(layer "B.Cu")
		(net 119)
	)
	(segment
		(start 182.375923 144.975925)
		(end 182.375924 144.975924)
		(width 0.16)
		(layer "B.Cu")
		(net 119)
	)
	(segment
		(start 187.036133 150.285171)
		(end 186.734486 149.983524)
		(width 0.16)
		(layer "B.Cu")
		(net 119)
	)
	(segment
		(start 196.373579 153.01)
		(end 194.502966 153.01)
		(width 0.16)
		(layer "B.Cu")
		(net 119)
	)
	(segment
		(start 196.55 152.751421)
		(end 196.55 152.833579)
		(width 0.16)
		(layer "B.Cu")
		(net 119)
	)
	(segment
		(start 186.734485 149.793356)
		(end 186.829569 149.698273)
		(width 0.16)
		(layer "B.Cu")
		(net 119)
	)
	(segment
		(start 187.953873 150.285171)
		(end 187.953871 150.28517)
		(width 0.16)
		(layer "B.Cu")
		(net 119)
	)
	(segment
		(start 188.390834 150.722132)
		(end 187.953873 150.285171)
		(width 0.16)
		(layer "B.Cu")
		(net 119)
	)
	(segment
		(start 159.699166 144.432132)
		(end 160.624852 143.506446)
		(width 0.16)
		(layer "B.Cu")
		(net 119)
	)
	(segment
		(start 181.484971 143.816269)
		(end 181.484969 143.816268)
		(width 0.16)
		(layer "B.Cu")
		(net 119)
	)
	(segment
		(start 187.193341 148.606956)
		(end 186.945075 148.35869)
		(width 0.16)
		(layer "B.Cu")
		(net 119)
	)
	(segment
		(start 182.255717 145.096132)
		(end 182.121366 145.230483)
		(width 0.16)
		(layer "B.Cu")
		(net 119)
	)
	(segment
		(start 182.121366 145.230483)
		(end 181.718314 145.633535)
		(width 0.16)
		(layer "B.Cu")
		(net 119)
	)
	(segment
		(start 137.605 147.475)
		(end 137.605 145.533405)
		(width 0.16)
		(layer "B.Cu")
		(net 119)
	)
	(segment
		(start 181.175149 143.506447)
		(end 181.484971 143.816269)
		(width 0.16)
		(layer "B.Cu")
		(net 119)
	)
	(segment
		(start 181.725385 143.816269)
		(end 182.128437 143.413218)
		(width 0.16)
		(layer "B.Cu")
		(net 119)
	)
	(segment
		(start 187.05899 149.468851)
		(end 187.193341 149.3345)
		(width 0.16)
		(layer "B.Cu")
		(net 119)
	)
	(segment
		(start 186.027392 148.35869)
		(end 185.83255 148.163848)
		(width 0.16)
		(layer "B.Cu")
		(net 119)
	)
	(segment
		(start 194.290834 152.922132)
		(end 192.325148 150.956446)
		(width 0.16)
		(layer "B.Cu")
		(net 119)
	)
	(segment
		(start 182.906255 143.413217)
		(end 183.033534 143.540496)
		(width 0.16)
		(layer "B.Cu")
		(net 119)
	)
	(segment
		(start 185.534241 147.865539)
		(end 183.79626 146.127558)
		(width 0.16)
		(layer "B.Cu")
		(net 119)
	)
	(segment
		(start 186.96392 149.56392)
		(end 187.05899 149.468851)
		(width 0.16)
		(layer "B.Cu")
		(net 119)
	)
	(segment
		(start 182.630482 144.721366)
		(end 182.375923 144.975925)
		(width 0.16)
		(layer "B.Cu")
		(net 119)
	)
	(segment
		(start 191.971595 150.81)
		(end 188.602966 150.81)
		(width 0.16)
		(layer "B.Cu")
		(net 119)
	)
	(segment
		(start 183.394158 145.725456)
		(end 183.79626 146.127558)
		(width 0.16)
		(layer "B.Cu")
		(net 119)
	)
	(segment
		(start 137.751447 145.179851)
		(end 138.264852 144.666446)
		(width 0.16)
		(layer "B.Cu")
		(net 119)
	)
	(segment
		(start 183.033535 144.318316)
		(end 182.630482 144.721366)
		(width 0.16)
		(layer "B.Cu")
		(net 119)
	)
	(segment
		(start 183.266878 145.598176)
		(end 183.394158 145.725456)
		(width 0.16)
		(layer "B.Cu")
		(net 119)
	)
	(segment
		(start 182.086008 146.001228)
		(end 182.489059 145.598176)
		(width 0.16)
		(layer "B.Cu")
		(net 119)
	)
	(segment
		(start 186.96392 149.563922)
		(end 186.96392 149.56392)
		(width 0.16)
		(layer "B.Cu")
		(net 119)
	)
	(arc
		(start 196.520711 152.680711)
		(mid 196.542388 152.713153)
		(end 196.55 152.751421)
		(width 0.16)
		(layer "B.Cu")
		(net 119)
	)
	(arc
		(start 138.264852 144.666446)
		(mid 138.427064 144.55806)
		(end 138.618405 144.52)
		(width 0.16)
		(layer "B.Cu")
		(net 119)
	)
	(arc
		(start 182.489059 145.598176)
		(mid 182.877968 145.437085)
		(end 183.266878 145.598176)
		(width 0.16)
		(layer "B.Cu")
		(net 119)
	)
	(arc
		(start 187.226301 150.285171)
		(mid 187.131216 150.324555)
		(end 187.036133 150.285171)
		(width 0.16)
		(layer "B.Cu")
		(net 119)
	)
	(arc
		(start 194.502966 153.01)
		(mid 194.388161 152.987164)
		(end 194.290834 152.922132)
		(width 0.16)
		(layer "B.Cu")
		(net 119)
	)
	(arc
		(start 183.033534 143.540496)
		(mid 183.194626 143.929407)
		(end 183.033535 144.318316)
		(width 0.16)
		(layer "B.Cu")
		(net 119)
	)
	(arc
		(start 181.718314 145.633535)
		(mid 181.668523 145.753742)
		(end 181.718314 145.873949)
		(width 0.16)
		(layer "B.Cu")
		(net 119)
	)
	(arc
		(start 159.487034 144.52)
		(mid 159.601839 144.497164)
		(end 159.699166 144.432132)
		(width 0.16)
		(layer "B.Cu")
		(net 119)
	)
	(arc
		(start 182.128437 143.413218)
		(mid 182.517346 143.252127)
		(end 182.906255 143.413217)
		(width 0.16)
		(layer "B.Cu")
		(net 119)
	)
	(arc
		(start 192.325148 150.956446)
		(mid 192.162936 150.84806)
		(end 191.971595 150.81)
		(width 0.16)
		(layer "B.Cu")
		(net 119)
	)
	(arc
		(start 180.821595 143.36)
		(mid 181.012937 143.39806)
		(end 181.175149 143.506447)
		(width 0.16)
		(layer "B.Cu")
		(net 119)
	)
	(arc
		(start 160.624852 143.506446)
		(mid 160.787064 143.39806)
		(end 160.978405 143.36)
		(width 0.16)
		(layer "B.Cu")
		(net 119)
	)
	(arc
		(start 181.845593 146.001228)
		(mid 181.965801 146.051019)
		(end 182.086008 146.001228)
		(width 0.16)
		(layer "B.Cu")
		(net 119)
	)
	(arc
		(start 186.734486 149.983524)
		(mid 186.695101 149.888441)
		(end 186.734485 149.793356)
		(width 0.16)
		(layer "B.Cu")
		(net 119)
	)
	(arc
		(start 196.444289 152.980711)
		(mid 196.411847 153.002388)
		(end 196.373579 153.01)
		(width 0.16)
		(layer "B.Cu")
		(net 119)
	)
	(arc
		(start 186.945075 148.35869)
		(mid 186.581304 148.20801)
		(end 186.217532 148.35869)
		(width 0.16)
		(layer "B.Cu")
		(net 119)
	)
	(arc
		(start 187.193341 149.3345)
		(mid 187.34402 148.970728)
		(end 187.193341 148.606956)
		(width 0.16)
		(layer "B.Cu")
		(net 119)
	)
	(arc
		(start 187.953871 150.28517)
		(mid 187.590086 150.134485)
		(end 187.226301 150.285171)
		(width 0.16)
		(layer "B.Cu")
		(net 119)
	)
	(arc
		(start 137.605 145.533405)
		(mid 137.64306 145.342063)
		(end 137.751447 145.179851)
		(width 0.16)
		(layer "B.Cu")
		(net 119)
	)
	(arc
		(start 186.217532 148.35869)
		(mid 186.122462 148.398069)
		(end 186.027392 148.35869)
		(width 0.16)
		(layer "B.Cu")
		(net 119)
	)
	(arc
		(start 181.484969 143.816268)
		(mid 181.605178 143.86606)
		(end 181.725385 143.816269)
		(width 0.16)
		(layer "B.Cu")
		(net 119)
	)
	(arc
		(start 196.55 152.833579)
		(mid 196.542388 152.871848)
		(end 196.52071 152.90429)
		(width 0.16)
		(layer "B.Cu")
		(net 119)
	)
	(arc
		(start 188.602966 150.81)
		(mid 188.488161 150.787164)
		(end 188.390834 150.722132)
		(width 0.16)
		(layer "B.Cu")
		(net 119)
	)
	(segment
		(start 137.6 143.17)
		(end 137.29 142.86)
		(width 0.16)
		(layer "F.Cu")
		(net 120)
	)
	(segment
		(start 137.6 146.77)
		(end 137.6 143.17)
		(width 0.16)
		(layer "F.Cu")
		(net 120)
	)
	(segment
		(start 137.41 146.96)
		(end 137.6 146.77)
		(width 0.16)
		(layer "F.Cu")
		(net 120)
	)
	(segment
		(start 197.025 151.86)
		(end 196.965 151.92)
		(width 0.16)
		(layer "F.Cu")
		(net 121)
	)
	(segment
		(start 197.025 151.135)
		(end 197.025 151.86)
		(width 0.16)
		(layer "F.Cu")
		(net 121)
	)
	(segment
		(start 197.052868 152.542868)
		(end 197.11 152.6)
		(width 0.16)
		(layer "F.Cu")
		(net 121)
	)
	(segment
		(start 196.965 151.92)
		(end 196.965 152.330736)
		(width 0.16)
		(layer "F.Cu")
		(net 121)
	)
	(via
		(at 197.11 152.6)
		(size 0.45)
		(drill 0.1)
		(layers "F.Cu" "B.Cu")
		(teardrops
			(best_length_ratio 0.4)
			(max_length 1)
			(best_width_ratio 0.9)
			(max_width 2)
			(curved_edges yes)
			(filter_ratio 0.9)
			(enabled yes)
			(allow_two_segments yes)
			(prefer_zone_connections yes)
		)
		(net 121)
	)
	(via
		(at 138.13 147.62)
		(size 0.45)
		(drill 0.1)
		(layers "F.Cu" "B.Cu")
		(remove_unused_layers yes)
		(keep_end_layers yes)
		(zone_layer_connections)
		(teardrops
			(best_length_ratio 0.4)
			(max_length 1)
			(best_width_ratio 0.9)
			(max_width 2)
			(curved_edges yes)
			(filter_ratio 0.9)
			(enabled yes)
			(allow_two_segments yes)
			(prefer_zone_connections yes)
		)
		(net 121)
	)
	(arc
		(start 197.052868 152.542868)
		(mid 196.987836 152.445541)
		(end 196.965 152.330736)
		(width 0.16)
		(layer "F.Cu")
		(net 121)
	)
	(segment
		(start 188.142403 151.011105)
		(end 187.685171 150.553873)
		(width 0.16)
		(layer "B.Cu")
		(net 121)
	)
	(segment
		(start 186.790288 149.200149)
		(end 186.924639 149.065798)
		(width 0.16)
		(layer "B.Cu")
		(net 121)
	)
	(segment
		(start 181.994088 144.084971)
		(end 182.397138 143.681918)
		(width 0.16)
		(layer "B.Cu")
		(net 121)
	)
	(segment
		(start 186.76743 150.553871)
		(end 186.465783 150.252224)
		(width 0.16)
		(layer "B.Cu")
		(net 121)
	)
	(segment
		(start 180.959166 143.827868)
		(end 181.216269 144.084971)
		(width 0.16)
		(layer "B.Cu")
		(net 121)
	)
	(segment
		(start 161.052966 143.74)
		(end 180.747034 143.74)
		(width 0.16)
		(layer "B.Cu")
		(net 121)
	)
	(segment
		(start 186.924639 148.875658)
		(end 186.676373 148.627392)
		(width 0.16)
		(layer "B.Cu")
		(net 121)
	)
	(segment
		(start 191.897034 151.19)
		(end 188.574295 151.19)
		(width 0.16)
		(layer "B.Cu")
		(net 121)
	)
	(segment
		(start 185.265539 148.134241)
		(end 183.527558 146.39626)
		(width 0.16)
		(layer "B.Cu")
		(net 121)
	)
	(segment
		(start 197.11 152.6)
		(end 196.994289 152.715711)
		(width 0.16)
		(layer "B.Cu")
		(net 121)
	)
	(segment
		(start 182.35471 146.26993)
		(end 182.757761 145.866878)
		(width 0.16)
		(layer "B.Cu")
		(net 121)
	)
	(segment
		(start 185.75869 148.627392)
		(end 185.563848 148.43255)
		(width 0.16)
		(layer "B.Cu")
		(net 121)
	)
	(segment
		(start 186.465784 149.524654)
		(end 186.560866 149.429569)
		(width 0.16)
		(layer "B.Cu")
		(net 121)
	)
	(segment
		(start 137.985 147.475)
		(end 137.985 145.607966)
		(width 0.16)
		(layer "B.Cu")
		(net 121)
	)
	(segment
		(start 138.13 147.62)
		(end 137.985 147.475)
		(width 0.16)
		(layer "B.Cu")
		(net 121)
	)
	(segment
		(start 182.107223 144.707223)
		(end 181.987015 144.82743)
		(width 0.16)
		(layer "B.Cu")
		(net 121)
	)
	(segment
		(start 138.072868 145.395834)
		(end 138.480834 144.987868)
		(width 0.16)
		(layer "B.Cu")
		(net 121)
	)
	(segment
		(start 138.692966 144.9)
		(end 159.498738 144.9)
		(width 0.16)
		(layer "B.Cu")
		(net 121)
	)
	(segment
		(start 185.563848 148.43255)
		(end 185.265539 148.134241)
		(width 0.16)
		(layer "B.Cu")
		(net 121)
	)
	(segment
		(start 183.125456 145.994158)
		(end 183.527558 146.39626)
		(width 0.16)
		(layer "B.Cu")
		(net 121)
	)
	(segment
		(start 182.764832 144.049612)
		(end 182.361781 144.452664)
		(width 0.16)
		(layer "B.Cu")
		(net 121)
	)
	(segment
		(start 186.560866 149.429569)
		(end 186.695217 149.295218)
		(width 0.16)
		(layer "B.Cu")
		(net 121)
	)
	(segment
		(start 182.637554 143.681919)
		(end 182.764833 143.809198)
		(width 0.16)
		(layer "B.Cu")
		(net 121)
	)
	(segment
		(start 196.877132 153.06657)
		(end 196.64157 153.302132)
		(width 0.16)
		(layer "B.Cu")
		(net 121)
	)
	(segment
		(start 159.959595 144.709107)
		(end 160.840834 143.827868)
		(width 0.16)
		(layer "B.Cu")
		(net 121)
	)
	(segment
		(start 181.216269 144.084971)
		(end 181.216268 144.084969)
		(width 0.16)
		(layer "B.Cu")
		(net 121)
	)
	(segment
		(start 194.025011 153.193713)
		(end 192.109166 151.277868)
		(width 0.16)
		(layer "B.Cu")
		(net 121)
	)
	(segment
		(start 196.429438 153.39)
		(end 194.49889 153.39)
		(width 0.16)
		(layer "B.Cu")
		(net 121)
	)
	(segment
		(start 186.695219 149.295219)
		(end 186.790288 149.200149)
		(width 0.16)
		(layer "B.Cu")
		(net 121)
	)
	(segment
		(start 182.998176 145.866878)
		(end 183.125456 145.994158)
		(width 0.16)
		(layer "B.Cu")
		(net 121)
	)
	(segment
		(start 181.852664 144.961781)
		(end 181.449612 145.364833)
		(width 0.16)
		(layer "B.Cu")
		(net 121)
	)
	(segment
		(start 181.987015 144.82743)
		(end 181.852664 144.961781)
		(width 0.16)
		(layer "B.Cu")
		(net 121)
	)
	(segment
		(start 181.449612 146.142651)
		(end 181.576891 146.26993)
		(width 0.16)
		(layer "B.Cu")
		(net 121)
	)
	(segment
		(start 182.107222 144.707223)
		(end 182.107223 144.707223)
		(width 0.16)
		(layer "B.Cu")
		(net 121)
	)
	(segment
		(start 196.965 152.786421)
		(end 196.965 152.854438)
		(width 0.16)
		(layer "B.Cu")
		(net 121)
	)
	(segment
		(start 182.361781 144.452664)
		(end 182.107222 144.707223)
		(width 0.16)
		(layer "B.Cu")
		(net 121)
	)
	(segment
		(start 187.685171 150.553873)
		(end 187.68517 150.553871)
		(width 0.16)
		(layer "B.Cu")
		(net 121)
	)
	(segment
		(start 186.695217 149.295218)
		(end 186.695219 149.295219)
		(width 0.16)
		(layer "B.Cu")
		(net 121)
	)
	(arc
		(start 182.397138 143.681918)
		(mid 182.517345 143.632127)
		(end 182.637554 143.681919)
		(width 0.16)
		(layer "B.Cu")
		(net 121)
	)
	(arc
		(start 188.574295 151.19)
		(mid 188.340557 151.143507)
		(end 188.142403 151.011105)
		(width 0.16)
		(layer "B.Cu")
		(net 121)
	)
	(arc
		(start 187.68517 150.553871)
		(mid 187.590087 150.514487)
		(end 187.495002 150.553871)
		(width 0.16)
		(layer "B.Cu")
		(net 121)
	)
	(arc
		(start 137.985 145.607966)
		(mid 138.007836 145.493161)
		(end 138.072868 145.395834)
		(width 0.16)
		(layer "B.Cu")
		(net 121)
	)
	(arc
		(start 196.64157 153.302132)
		(mid 196.544243 153.367164)
		(end 196.429438 153.39)
		(width 0.16)
		(layer "B.Cu")
		(net 121)
	)
	(arc
		(start 192.109166 151.277868)
		(mid 192.011839 151.212836)
		(end 191.897034 151.19)
		(width 0.16)
		(layer "B.Cu")
		(net 121)
	)
	(arc
		(start 186.924639 149.065798)
		(mid 186.964018 148.970728)
		(end 186.924639 148.875658)
		(width 0.16)
		(layer "B.Cu")
		(net 121)
	)
	(arc
		(start 159.498738 144.9)
		(mid 159.748152 144.850388)
		(end 159.959595 144.709107)
		(width 0.16)
		(layer "B.Cu")
		(net 121)
	)
	(arc
		(start 180.747034 143.74)
		(mid 180.861839 143.762836)
		(end 180.959166 143.827868)
		(width 0.16)
		(layer "B.Cu")
		(net 121)
	)
	(arc
		(start 181.576891 146.26993)
		(mid 181.965801 146.431021)
		(end 182.35471 146.26993)
		(width 0.16)
		(layer "B.Cu")
		(net 121)
	)
	(arc
		(start 182.764833 143.809198)
		(mid 182.814623 143.929405)
		(end 182.764832 144.049612)
		(width 0.16)
		(layer "B.Cu")
		(net 121)
	)
	(arc
		(start 196.994289 152.715711)
		(mid 196.972612 152.748153)
		(end 196.965 152.786421)
		(width 0.16)
		(layer "B.Cu")
		(net 121)
	)
	(arc
		(start 186.465783 150.252224)
		(mid 186.315098 149.888439)
		(end 186.465784 149.524654)
		(width 0.16)
		(layer "B.Cu")
		(net 121)
	)
	(arc
		(start 182.757761 145.866878)
		(mid 182.877968 145.817087)
		(end 182.998176 145.866878)
		(width 0.16)
		(layer "B.Cu")
		(net 121)
	)
	(arc
		(start 138.480834 144.987868)
		(mid 138.578161 144.922836)
		(end 138.692966 144.9)
		(width 0.16)
		(layer "B.Cu")
		(net 121)
	)
	(arc
		(start 181.449612 145.364833)
		(mid 181.288521 145.753742)
		(end 181.449612 146.142651)
		(width 0.16)
		(layer "B.Cu")
		(net 121)
	)
	(arc
		(start 181.216268 144.084969)
		(mid 181.605179 144.246062)
		(end 181.994088 144.084971)
		(width 0.16)
		(layer "B.Cu")
		(net 121)
	)
	(arc
		(start 160.840834 143.827868)
		(mid 160.938161 143.762836)
		(end 161.052966 143.74)
		(width 0.16)
		(layer "B.Cu")
		(net 121)
	)
	(arc
		(start 196.965 152.854438)
		(mid 196.942164 152.969243)
		(end 196.877132 153.06657)
		(width 0.16)
		(layer "B.Cu")
		(net 121)
	)
	(arc
		(start 186.486234 148.627392)
		(mid 186.122462 148.778071)
		(end 185.75869 148.627392)
		(width 0.16)
		(layer "B.Cu")
		(net 121)
	)
	(arc
		(start 194.49889 153.39)
		(mid 194.242429 153.338987)
		(end 194.025011 153.193713)
		(width 0.16)
		(layer "B.Cu")
		(net 121)
	)
	(arc
		(start 187.495002 150.553871)
		(mid 187.131217 150.704557)
		(end 186.76743 150.553871)
		(width 0.16)
		(layer "B.Cu")
		(net 121)
	)
	(arc
		(start 186.676373 148.627392)
		(mid 186.581304 148.588012)
		(end 186.486234 148.627392)
		(width 0.16)
		(layer "B.Cu")
		(net 121)
	)
	(segment
		(start 137.98 146.77)
		(end 137.98 143.17)
		(width 0.16)
		(layer "F.Cu")
		(net 122)
	)
	(segment
		(start 138.17 146.96)
		(end 137.98 146.77)
		(width 0.16)
		(layer "F.Cu")
		(net 122)
	)
	(segment
		(start 137.98 143.17)
		(end 138.29 142.86)
		(width 0.16)
		(layer "F.Cu")
		(net 122)
	)
	(segment
		(start 102.471298 117.64)
		(end 99.36 114.528702)
		(width 0.185)
		(layer "F.Cu")
		(net 123)
	)
	(segment
		(start 129.64 118.85)
		(end 129.3295 118.5395)
		(width 0.185)
		(layer "F.Cu")
		(net 123)
	)
	(segment
		(start 99.36 109.121298)
		(end 103.306298 105.175)
		(width 0.185)
		(layer "F.Cu")
		(net 123)
	)
	(segment
		(start 104.355241 105.175)
		(end 104.487741 105.0425)
		(width 0.185)
		(layer "F.Cu")
		(net 123)
	)
	(segment
		(start 129.3295 118.5395)
		(end 124.920798 118.5395)
		(width 0.185)
		(layer "F.Cu")
		(net 123)
	)
	(segment
		(start 99.36 114.528702)
		(end 99.36 109.121298)
		(width 0.185)
		(layer "F.Cu")
		(net 123)
	)
	(segment
		(start 124.021298 117.64)
		(end 102.471298 117.64)
		(width 0.185)
		(layer "F.Cu")
		(net 123)
	)
	(segment
		(start 103.306298 105.175)
		(end 104.355241 105.175)
		(width 0.185)
		(layer "F.Cu")
		(net 123)
	)
	(segment
		(start 124.920798 118.5395)
		(end 124.021298 117.64)
		(width 0.185)
		(layer "F.Cu")
		(net 123)
	)
	(via
		(at 104.487741 105.0425)
		(size 0.45)
		(drill 0.1)
		(layers "F.Cu" "B.Cu")
		(remove_unused_layers yes)
		(keep_end_layers yes)
		(zone_layer_connections)
		(teardrops
			(best_length_ratio 0.4)
			(max_length 1)
			(best_width_ratio 0.9)
			(max_width 2)
			(curved_edges yes)
			(filter_ratio 0.9)
			(enabled yes)
			(allow_two_segments yes)
			(prefer_zone_connections yes)
		)
		(net 123)
	)
	(segment
		(start 104.858157 105.175)
		(end 104.620241 105.175)
		(width 0.185)
		(layer "B.Cu")
		(net 123)
	)
	(segment
		(start 105.94 105.175)
		(end 105.861 105.175)
		(width 0.185)
		(layer "B.Cu")
		(net 123)
	)
	(segment
		(start 106.75 104.365)
		(end 105.94 105.175)
		(width 0.185)
		(layer "B.Cu")
		(net 123)
	)
	(segment
		(start 104.620241 105.175)
		(end 104.487741 105.0425)
		(width 0.185)
		(layer "B.Cu")
		(net 123)
	)
	(segment
		(start 105.401 104.715)
		(end 104.999578 105.116422)
		(width 0.185)
		(layer "B.Cu")
		(net 123)
	)
	(segment
		(start 105.861 105.175)
		(end 105.401 104.715)
		(width 0.185)
		(layer "B.Cu")
		(net 123)
	)
	(arc
		(start 104.858157 105.175)
		(mid 104.934693 105.159776)
		(end 104.999578 105.116422)
		(width 0.185)
		(layer "B.Cu")
		(net 123)
	)
	(segment
		(start 99.74 113.509029)
		(end 99.74 114.371298)
		(width 0.185)
		(layer "F.Cu")
		(net 124)
	)
	(segment
		(start 104.355241 105.555)
		(end 103.463702 105.555)
		(width 0.185)
		(layer "F.Cu")
		(net 124)
	)
	(segment
		(start 125.078202 118.1595)
		(end 129.3295 118.1595)
		(width 0.185)
		(layer "F.Cu")
		(net 124)
	)
	(segment
		(start 99.98 112.086231)
		(end 100.046243 112.086231)
		(width 0.185)
		(layer "F.Cu")
		(net 124)
	)
	(segment
		(start 100.236227 111.126231)
		(end 100.236227 111.246231)
		(width 0.185)
		(layer "F.Cu")
		(net 124)
	)
	(segment
		(start 103.463702 105.555)
		(end 99.74 109.278702)
		(width 0.185)
		(layer "F.Cu")
		(net 124)
	)
	(segment
		(start 104.487741 105.6875)
		(end 104.355241 105.555)
		(width 0.185)
		(layer "F.Cu")
		(net 124)
	)
	(segment
		(start 102.628702 117.26)
		(end 124.178702 117.26)
		(width 0.185)
		(layer "F.Cu")
		(net 124)
	)
	(segment
		(start 99.98 110.886231)
		(end 99.996227 110.886231)
		(width 0.185)
		(layer "F.Cu")
		(net 124)
	)
	(segment
		(start 124.178702 117.26)
		(end 125.078202 118.1595)
		(width 0.185)
		(layer "F.Cu")
		(net 124)
	)
	(segment
		(start 100.046243 112.686231)
		(end 99.98 112.686231)
		(width 0.185)
		(layer "F.Cu")
		(net 124)
	)
	(segment
		(start 99.996227 111.486231)
		(end 99.98 111.486231)
		(width 0.185)
		(layer "F.Cu")
		(net 124)
	)
	(segment
		(start 99.74 114.371298)
		(end 102.628702 117.26)
		(width 0.185)
		(layer "F.Cu")
		(net 124)
	)
	(segment
		(start 99.74 113.046231)
		(end 99.74 113.509029)
		(width 0.185)
		(layer "F.Cu")
		(net 124)
	)
	(segment
		(start 129.3295 118.1595)
		(end 129.639 117.85)
		(width 0.185)
		(layer "F.Cu")
		(net 124)
	)
	(segment
		(start 99.74 109.278702)
		(end 99.74 110.646231)
		(width 0.185)
		(layer "F.Cu")
		(net 124)
	)
	(segment
		(start 99.74 112.926231)
		(end 99.74 113.046231)
		(width 0.185)
		(layer "F.Cu")
		(net 124)
	)
	(segment
		(start 99.74 111.726231)
		(end 99.74 111.846231)
		(width 0.185)
		(layer "F.Cu")
		(net 124)
	)
	(segment
		(start 100.286243 112.326231)
		(end 100.286243 112.446231)
		(width 0.185)
		(layer "F.Cu")
		(net 124)
	)
	(via
		(at 104.487741 105.6875)
		(size 0.45)
		(drill 0.1)
		(layers "F.Cu" "B.Cu")
		(remove_unused_layers yes)
		(keep_end_layers yes)
		(zone_layer_connections)
		(teardrops
			(best_length_ratio 0.4)
			(max_length 1)
			(best_width_ratio 0.9)
			(max_width 2)
			(curved_edges yes)
			(filter_ratio 0.9)
			(enabled yes)
			(allow_two_segments yes)
			(prefer_zone_connections yes)
		)
		(net 124)
	)
	(arc
		(start 99.996227 110.886231)
		(mid 100.165933 110.956525)
		(end 100.236227 111.126231)
		(width 0.185)
		(layer "F.Cu")
		(net 124)
	)
	(arc
		(start 100.046243 112.086231)
		(mid 100.215949 112.156525)
		(end 100.286243 112.326231)
		(width 0.185)
		(layer "F.Cu")
		(net 124)
	)
	(arc
		(start 100.286243 112.446231)
		(mid 100.215949 112.615937)
		(end 100.046243 112.686231)
		(width 0.185)
		(layer "F.Cu")
		(net 124)
	)
	(arc
		(start 99.98 111.486231)
		(mid 99.810294 111.556525)
		(end 99.74 111.726231)
		(width 0.185)
		(layer "F.Cu")
		(net 124)
	)
	(arc
		(start 99.74 111.846231)
		(mid 99.810294 112.015937)
		(end 99.98 112.086231)
		(width 0.185)
		(layer "F.Cu")
		(net 124)
	)
	(arc
		(start 99.74 110.646231)
		(mid 99.810294 110.815937)
		(end 99.98 110.886231)
		(width 0.185)
		(layer "F.Cu")
		(net 124)
	)
	(arc
		(start 99.98 112.686231)
		(mid 99.810294 112.756525)
		(end 99.74 112.926231)
		(width 0.185)
		(layer "F.Cu")
		(net 124)
	)
	(arc
		(start 100.236227 111.246231)
		(mid 100.165933 111.415937)
		(end 99.996227 111.486231)
		(width 0.185)
		(layer "F.Cu")
		(net 124)
	)
	(segment
		(start 106.75 106.365)
		(end 105.94 105.555)
		(width 0.185)
		(layer "B.Cu")
		(net 124)
	)
	(segment
		(start 104.858157 105.555)
		(end 104.620241 105.555)
		(width 0.185)
		(layer "B.Cu")
		(net 124)
	)
	(segment
		(start 105.94 105.555)
		(end 105.861 105.555)
		(width 0.185)
		(layer "B.Cu")
		(net 124)
	)
	(segment
		(start 104.620241 105.555)
		(end 104.487741 105.6875)
		(width 0.185)
		(layer "B.Cu")
		(net 124)
	)
	(segment
		(start 105.401 106.015)
		(end 104.999578 105.613578)
		(width 0.185)
		(layer "B.Cu")
		(net 124)
	)
	(segment
		(start 105.861 105.555)
		(end 105.401 106.015)
		(width 0.185)
		(layer "B.Cu")
		(net 124)
	)
	(arc
		(start 104.858157 105.555)
		(mid 104.934693 105.570224)
		(end 104.999578 105.613578)
		(width 0.185)
		(layer "B.Cu")
		(net 124)
	)
	(segment
		(start 118.756824 113.758122)
		(end 120.158702 115.16)
		(width 0.185)
		(layer "F.Cu")
		(net 125)
	)
	(segment
		(start 129.575 115.6)
		(end 129.6 115.6)
		(width 0.185)
		(layer "F.Cu")
		(net 125)
	)
	(segment
		(start 113.82 108.821298)
		(end 117.395472 112.39677)
		(width 0.185)
		(layer "F.Cu")
		(net 125)
	)
	(segment
		(start 113.9525 107.1)
		(end 113.82 107.2325)
		(width 0.185)
		(layer "F.Cu")
		(net 125)
	)
	(segment
		(start 120.158702 115.16)
		(end 124.208702 115.16)
		(width 0.185)
		(layer "F.Cu")
		(net 125)
	)
	(segment
		(start 118.102578 113.103876)
		(end 118.756824 113.758122)
		(width 0.185)
		(layer "F.Cu")
		(net 125)
	)
	(segment
		(start 124.208702 115.16)
		(end 124.958702 115.91)
		(width 0.185)
		(layer "F.Cu")
		(net 125)
	)
	(segment
		(start 129.265 115.91)
		(end 129.575 115.6)
		(width 0.185)
		(layer "F.Cu")
		(net 125)
	)
	(segment
		(start 117.678314 112.39677)
		(end 117.739503 112.335582)
		(width 0.185)
		(layer "F.Cu")
		(net 125)
	)
	(segment
		(start 124.958702 115.91)
		(end 129.265 115.91)
		(width 0.185)
		(layer "F.Cu")
		(net 125)
	)
	(segment
		(start 118.093056 112.689135)
		(end 118.031866 112.750322)
		(width 0.185)
		(layer "F.Cu")
		(net 125)
	)
	(segment
		(start 113.82 107.2325)
		(end 113.82 108.821298)
		(width 0.185)
		(layer "F.Cu")
		(net 125)
	)
	(segment
		(start 118.031867 113.033166)
		(end 118.102578 113.103876)
		(width 0.185)
		(layer "F.Cu")
		(net 125)
	)
	(segment
		(start 118.022345 112.335581)
		(end 118.093055 112.406291)
		(width 0.185)
		(layer "F.Cu")
		(net 125)
	)
	(via
		(at 113.9525 107.1)
		(size 0.45)
		(drill 0.1)
		(layers "F.Cu" "B.Cu")
		(teardrops
			(best_length_ratio 0.4)
			(max_length 1)
			(best_width_ratio 0.9)
			(max_width 2)
			(curved_edges yes)
			(filter_ratio 0.9)
			(enabled yes)
			(allow_two_segments yes)
			(prefer_zone_connections yes)
		)
		(net 125)
	)
	(arc
		(start 118.031866 112.750322)
		(mid 117.973289 112.891744)
		(end 118.031867 113.033166)
		(width 0.185)
		(layer "F.Cu")
		(net 125)
	)
	(arc
		(start 118.093055 112.406291)
		(mid 118.151633 112.547713)
		(end 118.093056 112.689135)
		(width 0.185)
		(layer "F.Cu")
		(net 125)
	)
	(arc
		(start 117.395472 112.39677)
		(mid 117.536894 112.455349)
		(end 117.678314 112.39677)
		(width 0.185)
		(layer "F.Cu")
		(net 125)
	)
	(arc
		(start 117.739503 112.335582)
		(mid 117.880923 112.277003)
		(end 118.022345 112.335581)
		(width 0.185)
		(layer "F.Cu")
		(net 125)
	)
	(segment
		(start 109.95 104.365)
		(end 112.895 104.365)
		(width 0.185)
		(layer "B.Cu")
		(net 125)
	)
	(segment
		(start 113.82 106.9675)
		(end 113.9525 107.1)
		(width 0.185)
		(layer "B.Cu")
		(net 125)
	)
	(segment
		(start 112.895 104.365)
		(end 114.28 105.75)
		(width 0.185)
		(layer "B.Cu")
		(net 125)
	)
	(segment
		(start 114.28 106.251)
		(end 113.82 106.711)
		(width 0.185)
		(layer "B.Cu")
		(net 125)
	)
	(segment
		(start 114.28 105.75)
		(end 114.28 106.251)
		(width 0.185)
		(layer "B.Cu")
		(net 125)
	)
	(segment
		(start 113.82 106.711)
		(end 113.82 106.9675)
		(width 0.185)
		(layer "B.Cu")
		(net 125)
	)
	(segment
		(start 129.6 116.6)
		(end 129.575 116.6)
		(width 0.185)
		(layer "F.Cu")
		(net 126)
	)
	(segment
		(start 124.051298 115.54)
		(end 120.001298 115.54)
		(width 0.185)
		(layer "F.Cu")
		(net 126)
	)
	(segment
		(start 113.44 107.2325)
		(end 113.3075 107.1)
		(width 0.185)
		(layer "F.Cu")
		(net 126)
	)
	(segment
		(start 113.44 108.978702)
		(end 113.44 107.2325)
		(width 0.185)
		(layer "F.Cu")
		(net 126)
	)
	(segment
		(start 129.575 116.6)
		(end 129.265 116.29)
		(width 0.185)
		(layer "F.Cu")
		(net 126)
	)
	(segment
		(start 120.001298 115.54)
		(end 113.44 108.978702)
		(width 0.185)
		(layer "F.Cu")
		(net 126)
	)
	(segment
		(start 124.801298 116.29)
		(end 124.051298 115.54)
		(width 0.185)
		(layer "F.Cu")
		(net 126)
	)
	(segment
		(start 129.265 116.29)
		(end 124.801298 116.29)
		(width 0.185)
		(layer "F.Cu")
		(net 126)
	)
	(via
		(at 113.3075 107.1)
		(size 0.45)
		(drill 0.1)
		(layers "F.Cu" "B.Cu")
		(teardrops
			(best_length_ratio 0.4)
			(max_length 1)
			(best_width_ratio 0.9)
			(max_width 2)
			(curved_edges yes)
			(filter_ratio 0.9)
			(enabled yes)
			(allow_two_segments yes)
			(prefer_zone_connections yes)
		)
		(net 126)
	)
	(segment
		(start 112.83 104.9)
		(end 112.98 105.05)
		(width 0.185)
		(layer "B.Cu")
		(net 126)
	)
	(segment
		(start 113.44 106.9675)
		(end 113.3075 107.1)
		(width 0.185)
		(layer "B.Cu")
		(net 126)
	)
	(segment
		(start 112.49875 104.9)
		(end 112.83 104.9)
		(width 0.185)
		(layer "B.Cu")
		(net 126)
	)
	(segment
		(start 112.98 106.251)
		(end 113.44 106.711)
		(width 0.185)
		(layer "B.Cu")
		(net 126)
	)
	(segment
		(start 112.98 105.05)
		(end 112.98 106.251)
		(width 0.185)
		(layer "B.Cu")
		(net 126)
	)
	(segment
		(start 109.95 106.365)
		(end 111.865 106.365)
		(width 0.185)
		(layer "B.Cu")
		(net 126)
	)
	(segment
		(start 112.38 105.01875)
		(end 112.49875 104.9)
		(width 0.185)
		(layer "B.Cu")
		(net 126)
	)
	(segment
		(start 112.38 105.85)
		(end 112.38 105.01875)
		(width 0.185)
		(layer "B.Cu")
		(net 126)
	)
	(segment
		(start 111.865 106.365)
		(end 112.38 105.85)
		(width 0.185)
		(layer "B.Cu")
		(net 126)
	)
	(segment
		(start 113.44 106.711)
		(end 113.44 106.9675)
		(width 0.185)
		(layer "B.Cu")
		(net 126)
	)
	(segment
		(start 112.4 73.06)
		(end 113.3 73.96)
		(width 0.125)
		(layer "F.Cu")
		(net 127)
	)
	(segment
		(start 112.4 70.56)
		(end 112.4 73.06)
		(width 0.125)
		(layer "F.Cu")
		(net 127)
	)
	(segment
		(start 115.484999 77.725)
		(end 115.484999 78.425001)
		(width 0.125)
		(layer "F.Cu")
		(net 127)
	)
	(segment
		(start 115.484999 78.425001)
		(end 115.05 78.86)
		(width 0.125)
		(layer "F.Cu")
		(net 127)
	)
	(via
		(at 113.3 73.96)
		(size 0.45)
		(drill 0.1)
		(layers "F.Cu" "B.Cu")
		(remove_unused_layers yes)
		(keep_end_layers yes)
		(zone_layer_connections "In3.Cu")
		(teardrops
			(best_length_ratio 0.4)
			(max_length 1)
			(best_width_ratio 0.9)
			(max_width 2)
			(curved_edges yes)
			(filter_ratio 0.9)
			(enabled yes)
			(allow_two_segments yes)
			(prefer_zone_connections yes)
		)
		(net 127)
	)
	(via
		(at 115.05 78.86)
		(size 0.45)
		(drill 0.1)
		(layers "F.Cu" "B.Cu")
		(remove_unused_layers yes)
		(keep_end_layers yes)
		(zone_layer_connections "In3.Cu")
		(teardrops
			(best_length_ratio 0.4)
			(max_length 1)
			(best_width_ratio 0.9)
			(max_width 2)
			(curved_edges yes)
			(filter_ratio 0.9)
			(enabled yes)
			(allow_two_segments yes)
			(prefer_zone_connections yes)
		)
		(net 127)
	)
	(segment
		(start 113.89 74.55)
		(end 113.3 73.96)
		(width 0.125)
		(layer "In3.Cu")
		(net 127)
	)
	(segment
		(start 115.05 78.86)
		(end 114.61 78.86)
		(width 0.125)
		(layer "In3.Cu")
		(net 127)
	)
	(segment
		(start 113.89 78.14)
		(end 113.89 74.55)
		(width 0.125)
		(layer "In3.Cu")
		(net 127)
	)
	(segment
		(start 114.61 78.86)
		(end 113.89 78.14)
		(width 0.125)
		(layer "In3.Cu")
		(net 127)
	)
	(segment
		(start 110.9 70.56)
		(end 110.9 73.06)
		(width 0.125)
		(layer "F.Cu")
		(net 128)
	)
	(segment
		(start 110.9 73.06)
		(end 112.69 74.85)
		(width 0.125)
		(layer "F.Cu")
		(net 128)
	)
	(segment
		(start 112.69 74.85)
		(end 113.259999 74.85)
		(width 0.125)
		(layer "F.Cu")
		(net 128)
	)
	(segment
		(start 101.7 78.81)
		(end 99.78 78.81)
		(width 0.125)
		(layer "F.Cu")
		(net 129)
	)
	(via
		(at 99.78 78.81)
		(size 0.45)
		(drill 0.1)
		(layers "F.Cu" "B.Cu")
		(remove_unused_layers yes)
		(keep_end_layers yes)
		(zone_layer_connections)
		(teardrops
			(best_length_ratio 0.4)
			(max_length 1)
			(best_width_ratio 0.9)
			(max_width 2)
			(curved_edges yes)
			(filter_ratio 0.9)
			(enabled yes)
			(allow_two_segments yes)
			(prefer_zone_connections yes)
		)
		(net 129)
	)
	(segment
		(start 101.7 76.31)
		(end 100.85 76.31)
		(width 0.125)
		(layer "F.Cu")
		(net 130)
	)
	(segment
		(start 100.85 76.31)
		(end 100.35 76.81)
		(width 0.125)
		(layer "F.Cu")
		(net 130)
	)
	(segment
		(start 100.35 76.81)
		(end 99.78 76.81)
		(width 0.125)
		(layer "F.Cu")
		(net 130)
	)
	(via
		(at 99.78 76.81)
		(size 0.45)
		(drill 0.1)
		(layers "F.Cu" "B.Cu")
		(remove_unused_layers yes)
		(keep_end_layers yes)
		(zone_layer_connections)
		(teardrops
			(best_length_ratio 0.4)
			(max_length 1)
			(best_width_ratio 0.9)
			(max_width 2)
			(curved_edges yes)
			(filter_ratio 0.9)
			(enabled yes)
			(allow_two_segments yes)
			(prefer_zone_connections yes)
		)
		(net 130)
	)
	(segment
		(start 103.2 76.31)
		(end 103.2 77.21)
		(width 0.125)
		(layer "F.Cu")
		(net 131)
	)
	(segment
		(start 100.6 77.81)
		(end 99.78 77.81)
		(width 0.125)
		(layer "F.Cu")
		(net 131)
	)
	(segment
		(start 103.2 77.21)
		(end 102.85 77.56)
		(width 0.125)
		(layer "F.Cu")
		(net 131)
	)
	(segment
		(start 100.85 77.56)
		(end 100.6 77.81)
		(width 0.125)
		(layer "F.Cu")
		(net 131)
	)
	(segment
		(start 102.85 77.56)
		(end 100.85 77.56)
		(width 0.125)
		(layer "F.Cu")
		(net 131)
	)
	(via
		(at 99.78 77.81)
		(size 0.45)
		(drill 0.1)
		(layers "F.Cu" "B.Cu")
		(remove_unused_layers yes)
		(keep_end_layers yes)
		(zone_layer_connections)
		(teardrops
			(best_length_ratio 0.4)
			(max_length 1)
			(best_width_ratio 0.9)
			(max_width 2)
			(curved_edges yes)
			(filter_ratio 0.9)
			(enabled yes)
			(allow_two_segments yes)
			(prefer_zone_connections yes)
		)
		(net 131)
	)
	(segment
		(start 100.4 75.81)
		(end 99.78 75.81)
		(width 0.125)
		(layer "F.Cu")
		(net 132)
	)
	(segment
		(start 101.71 73.565)
		(end 101.71 74.5)
		(width 0.125)
		(layer "F.Cu")
		(net 132)
	)
	(segment
		(start 101.71 74.5)
		(end 100.4 75.81)
		(width 0.125)
		(layer "F.Cu")
		(net 132)
	)
	(via
		(at 99.78 75.81)
		(size 0.45)
		(drill 0.1)
		(layers "F.Cu" "B.Cu")
		(remove_unused_layers yes)
		(keep_end_layers yes)
		(zone_layer_connections)
		(teardrops
			(best_length_ratio 0.4)
			(max_length 1)
			(best_width_ratio 0.9)
			(max_width 2)
			(curved_edges yes)
			(filter_ratio 0.9)
			(enabled yes)
			(allow_two_segments yes)
			(prefer_zone_connections yes)
		)
		(net 132)
	)
	(segment
		(start 100.75 72.71)
		(end 100.75 74.31)
		(width 0.125)
		(layer "F.Cu")
		(net 133)
	)
	(segment
		(start 100.25 74.81)
		(end 99.78 74.81)
		(width 0.125)
		(layer "F.Cu")
		(net 133)
	)
	(segment
		(start 101.71 71.065)
		(end 101.71 72.1)
		(width 0.125)
		(layer "F.Cu")
		(net 133)
	)
	(segment
		(start 101.71 72.1)
		(end 101.5 72.31)
		(width 0.125)
		(layer "F.Cu")
		(net 133)
	)
	(segment
		(start 101.5 72.31)
		(end 101.15 72.31)
		(width 0.125)
		(layer "F.Cu")
		(net 133)
	)
	(segment
		(start 100.75 74.31)
		(end 100.25 74.81)
		(width 0.125)
		(layer "F.Cu")
		(net 133)
	)
	(segment
		(start 101.15 72.31)
		(end 100.75 72.71)
		(width 0.125)
		(layer "F.Cu")
		(net 133)
	)
	(via
		(at 99.78 74.81)
		(size 0.45)
		(drill 0.1)
		(layers "F.Cu" "B.Cu")
		(remove_unused_layers yes)
		(keep_end_layers yes)
		(zone_layer_connections)
		(teardrops
			(best_length_ratio 0.4)
			(max_length 1)
			(best_width_ratio 0.9)
			(max_width 2)
			(curved_edges yes)
			(filter_ratio 0.9)
			(enabled yes)
			(allow_two_segments yes)
			(prefer_zone_connections yes)
		)
		(net 133)
	)
	(segment
		(start 309.62 74.81)
		(end 308.95 74.81)
		(width 0.3)
		(layer "F.Cu")
		(net 135)
	)
	(segment
		(start 221.498 78.41)
		(end 221.498 70.61)
		(width 0.5)
		(layer "F.Cu")
		(net 135)
	)
	(via
		(at 308.95 74.81)
		(size 0.45)
		(drill 0.1)
		(layers "F.Cu" "B.Cu")
		(remove_unused_layers yes)
		(keep_end_layers yes)
		(zone_layer_connections "In2.Cu")
		(teardrops
			(best_length_ratio 0.4)
			(max_length 1)
			(best_width_ratio 0.9)
			(max_width 2)
			(curved_edges yes)
			(filter_ratio 0.9)
			(enabled yes)
			(allow_two_segments yes)
			(prefer_zone_connections yes)
		)
		(net 135)
	)
	(segment
		(start 308.95 74.81)
		(end 303 68.86)
		(width 0.3)
		(layer "In2.Cu")
		(net 135)
	)
	(segment
		(start 303 68.86)
		(end 223.248 68.86)
		(width 0.3)
		(layer "In2.Cu")
		(net 135)
	)
	(segment
		(start 223.248 68.86)
		(end 221.498 70.61)
		(width 0.3)
		(layer "In2.Cu")
		(net 135)
	)
	(segment
		(start 251.625 132.84)
		(end 252.594 132.84)
		(width 0.125)
		(layer "F.Cu")
		(net 136)
	)
	(segment
		(start 202.525 155.425)
		(end 202.575 155.375)
		(width 0.125)
		(layer "F.Cu")
		(net 136)
	)
	(segment
		(start 202.525 156.685)
		(end 202.525 155.425)
		(width 0.125)
		(layer "F.Cu")
		(net 136)
	)
	(via
		(at 242.35 153.05)
		(size 0.45)
		(drill 0.1)
		(layers "F.Cu" "B.Cu")
		(remove_unused_layers yes)
		(keep_end_layers yes)
		(zone_layer_connections "In2.Cu" "In5.Cu")
		(teardrops
			(best_length_ratio 0.4)
			(max_length 1)
			(best_width_ratio 0.9)
			(max_width 2)
			(curved_edges yes)
			(filter_ratio 0.9)
			(enabled yes)
			(allow_two_segments yes)
			(prefer_zone_connections yes)
		)
		(net 136)
	)
	(via
		(at 202.575 155.375)
		(size 0.45)
		(drill 0.1)
		(layers "F.Cu" "B.Cu")
		(teardrops
			(best_length_ratio 0.4)
			(max_length 1)
			(best_width_ratio 0.9)
			(max_width 2)
			(curved_edges yes)
			(filter_ratio 0.9)
			(enabled yes)
			(allow_two_segments yes)
			(prefer_zone_connections yes)
		)
		(net 136)
	)
	(via
		(at 252.824 132.61)
		(size 0.45)
		(drill 0.1)
		(layers "F.Cu" "B.Cu")
		(remove_unused_layers yes)
		(keep_end_layers yes)
		(zone_layer_connections "In5.Cu")
		(teardrops
			(best_length_ratio 0.4)
			(max_length 1)
			(best_width_ratio 0.9)
			(max_width 2)
			(curved_edges yes)
			(filter_ratio 0.9)
			(enabled yes)
			(allow_two_segments yes)
			(prefer_zone_connections yes)
		)
		(net 136)
	)
	(segment
		(start 242.35 153.05)
		(end 242.275 152.975)
		(width 0.125)
		(layer "In2.Cu")
		(net 136)
	)
	(segment
		(start 226.4 143.575)
		(end 224.925 143.575)
		(width 0.125)
		(layer "In2.Cu")
		(net 136)
	)
	(segment
		(start 225.9 162.575)
		(end 225.55 162.225)
		(width 0.125)
		(layer "In2.Cu")
		(net 136)
	)
	(segment
		(start 214.5 154.2)
		(end 203.75 154.2)
		(width 0.125)
		(layer "In2.Cu")
		(net 136)
	)
	(segment
		(start 222.325 148.55)
		(end 219.1 148.55)
		(width 0.125)
		(layer "In2.Cu")
		(net 136)
	)
	(segment
		(start 222.35 148.575)
		(end 222.325 148.55)
		(width 0.125)
		(layer "In2.Cu")
		(net 136)
	)
	(segment
		(start 226.925 162.575)
		(end 225.9 162.575)
		(width 0.125)
		(layer "In2.Cu")
		(net 136)
	)
	(segment
		(start 226.3 157.5)
		(end 227.3125 156.4875)
		(width 0.125)
		(layer "In2.Cu")
		(net 136)
	)
	(segment
		(start 218.175 149.475)
		(end 218.175 150.525)
		(width 0.125)
		(layer "In2.Cu")
		(net 136)
	)
	(segment
		(start 219.1 148.55)
		(end 218.175 149.475)
		(width 0.125)
		(layer "In2.Cu")
		(net 136)
	)
	(segment
		(start 222.75 145.75)
		(end 222.75 148.175)
		(width 0.125)
		(layer "In2.Cu")
		(net 136)
	)
	(segment
		(start 232.625 155.125)
		(end 232.625 156.875)
		(width 0.125)
		(layer "In2.Cu")
		(net 136)
	)
	(segment
		(start 227.3125 144.4875)
		(end 226.4 143.575)
		(width 0.125)
		(layer "In2.Cu")
		(net 136)
	)
	(segment
		(start 232.625 156.875)
		(end 226.925 162.575)
		(width 0.125)
		(layer "In2.Cu")
		(net 136)
	)
	(segment
		(start 240.675 152.55)
		(end 235.2 152.55)
		(width 0.125)
		(layer "In2.Cu")
		(net 136)
	)
	(segment
		(start 218.175 150.525)
		(end 214.5 154.2)
		(width 0.125)
		(layer "In2.Cu")
		(net 136)
	)
	(segment
		(start 203.75 154.2)
		(end 202.575 155.375)
		(width 0.125)
		(layer "In2.Cu")
		(net 136)
	)
	(segment
		(start 226.3 160.875)
		(end 226.3 157.5)
		(width 0.125)
		(layer "In2.Cu")
		(net 136)
	)
	(segment
		(start 222.75 148.175)
		(end 222.35 148.575)
		(width 0.125)
		(layer "In2.Cu")
		(net 136)
	)
	(segment
		(start 241.1 152.975)
		(end 240.675 152.55)
		(width 0.125)
		(layer "In2.Cu")
		(net 136)
	)
	(segment
		(start 227.3125 156.4875)
		(end 227.3125 144.4875)
		(width 0.125)
		(layer "In2.Cu")
		(net 136)
	)
	(segment
		(start 242.275 152.975)
		(end 241.1 152.975)
		(width 0.125)
		(layer "In2.Cu")
		(net 136)
	)
	(segment
		(start 225.55 162.225)
		(end 225.55 161.625)
		(width 0.125)
		(layer "In2.Cu")
		(net 136)
	)
	(segment
		(start 235.2 152.55)
		(end 232.625 155.125)
		(width 0.125)
		(layer "In2.Cu")
		(net 136)
	)
	(segment
		(start 224.925 143.575)
		(end 222.75 145.75)
		(width 0.125)
		(layer "In2.Cu")
		(net 136)
	)
	(segment
		(start 225.55 161.625)
		(end 226.3 160.875)
		(width 0.125)
		(layer "In2.Cu")
		(net 136)
	)
	(segment
		(start 252.824 143.386)
		(end 252.824 132.61)
		(width 0.125)
		(layer "In5.Cu")
		(net 136)
	)
	(segment
		(start 243.16 153.05)
		(end 252.824 143.386)
		(width 0.125)
		(layer "In5.Cu")
		(net 136)
	)
	(segment
		(start 242.35 153.05)
		(end 243.16 153.05)
		(width 0.125)
		(layer "In5.Cu")
		(net 136)
	)
	(segment
		(start 204.025 149.275)
		(end 209.8 143.5)
		(width 0.125)
		(layer "F.Cu")
		(net 137)
	)
	(segment
		(start 255.975 132.84)
		(end 254.954 132.84)
		(width 0.125)
		(layer "F.Cu")
		(net 137)
	)
	(segment
		(start 209.8 143.5)
		(end 216.4 143.5)
		(width 0.125)
		(layer "F.Cu")
		(net 137)
	)
	(segment
		(start 204.025 151.135)
		(end 204.025 149.275)
		(width 0.125)
		(layer "F.Cu")
		(net 137)
	)
	(via
		(at 254.724 132.61)
		(size 0.45)
		(drill 0.1)
		(layers "F.Cu" "B.Cu")
		(remove_unused_layers yes)
		(keep_end_layers yes)
		(zone_layer_connections "In5.Cu")
		(teardrops
			(best_length_ratio 0.4)
			(max_length 1)
			(best_width_ratio 0.9)
			(max_width 2)
			(curved_edges yes)
			(filter_ratio 0.9)
			(enabled yes)
			(allow_two_segments yes)
			(prefer_zone_connections yes)
		)
		(net 137)
	)
	(via
		(at 216.4 143.5)
		(size 0.45)
		(drill 0.1)
		(layers "F.Cu" "B.Cu")
		(teardrops
			(best_length_ratio 0.4)
			(max_length 1)
			(best_width_ratio 0.9)
			(max_width 2)
			(curved_edges yes)
			(filter_ratio 0.9)
			(enabled yes)
			(allow_two_segments yes)
			(prefer_zone_connections yes)
		)
		(net 137)
	)
	(segment
		(start 230.1 135.6)
		(end 246.1 135.6)
		(width 0.125)
		(layer "In5.Cu")
		(net 137)
	)
	(segment
		(start 222.2 143.5)
		(end 230.1 135.6)
		(width 0.125)
		(layer "In5.Cu")
		(net 137)
	)
	(segment
		(start 249.6 132.1)
		(end 254.214 132.1)
		(width 0.125)
		(layer "In5.Cu")
		(net 137)
	)
	(segment
		(start 216.4 143.5)
		(end 222.2 143.5)
		(width 0.125)
		(layer "In5.Cu")
		(net 137)
	)
	(segment
		(start 254.214 132.1)
		(end 254.724 132.61)
		(width 0.125)
		(layer "In5.Cu")
		(net 137)
	)
	(segment
		(start 246.1 135.6)
		(end 249.6 132.1)
		(width 0.125)
		(layer "In5.Cu")
		(net 137)
	)
	(segment
		(start 250.475 129.51)
		(end 251.625 129.51)
		(width 0.125)
		(layer "F.Cu")
		(net 138)
	)
	(segment
		(start 253.575 129.51)
		(end 253.7745 129.7095)
		(width 0.125)
		(layer "F.Cu")
		(net 138)
	)
	(segment
		(start 250.467 129.518)
		(end 250.475 129.51)
		(width 0.125)
		(layer "F.Cu")
		(net 138)
	)
	(segment
		(start 249.969 130.138)
		(end 249.969 129.616)
		(width 0.125)
		(layer "F.Cu")
		(net 138)
	)
	(segment
		(start 253.7745 129.7095)
		(end 253.7745 130.41)
		(width 0.125)
		(layer "F.Cu")
		(net 138)
	)
	(segment
		(start 251.625 129.93)
		(end 251.625 129.51)
		(width 0.125)
		(layer "F.Cu")
		(net 138)
	)
	(segment
		(start 249.969 129.616)
		(end 250.075 129.51)
		(width 0.125)
		(layer "F.Cu")
		(net 138)
	)
	(segment
		(start 250.075 129.51)
		(end 250.475 129.51)
		(width 0.125)
		(layer "F.Cu")
		(net 138)
	)
	(segment
		(start 250.467 130.138)
		(end 250.467 129.518)
		(width 0.125)
		(layer "F.Cu")
		(net 138)
	)
	(segment
		(start 251.625 129.51)
		(end 253.575 129.51)
		(width 0.125)
		(layer "F.Cu")
		(net 138)
	)
	(segment
		(start 262.52 162.531)
		(end 263.869 162.531)
		(width 0.3)
		(layer "F.Cu")
		(net 139)
	)
	(segment
		(start 263.869 162.531)
		(end 263.9 162.5)
		(width 0.3)
		(layer "F.Cu")
		(net 139)
	)
	(segment
		(start 221.025 168.685)
		(end 221.025 166.925)
		(width 0.2)
		(layer "F.Cu")
		(net 139)
	)
	(segment
		(start 221.025 166.925)
		(end 221 166.9)
		(width 0.2)
		(layer "F.Cu")
		(net 139)
	)
	(via
		(at 221 166.9)
		(size 0.45)
		(drill 0.1)
		(layers "F.Cu" "B.Cu")
		(teardrops
			(best_length_ratio 0.4)
			(max_length 1)
			(best_width_ratio 0.9)
			(max_width 2)
			(curved_edges yes)
			(filter_ratio 0.9)
			(enabled yes)
			(allow_two_segments yes)
			(prefer_zone_connections yes)
		)
		(net 139)
	)
	(via
		(at 263.9 162.5)
		(size 0.45)
		(drill 0.1)
		(layers "F.Cu" "B.Cu")
		(teardrops
			(best_length_ratio 0.4)
			(max_length 1)
			(best_width_ratio 0.9)
			(max_width 2)
			(curved_edges yes)
			(filter_ratio 0.9)
			(enabled yes)
			(allow_two_segments yes)
			(prefer_zone_connections yes)
		)
		(net 139)
	)
	(segment
		(start 221 165.5)
		(end 222.65 163.85)
		(width 0.2)
		(layer "In2.Cu")
		(net 139)
	)
	(segment
		(start 243.12 158.38)
		(end 249.88 158.38)
		(width 0.2)
		(layer "In2.Cu")
		(net 139)
	)
	(segment
		(start 221 166.9)
		(end 221 165.5)
		(width 0.2)
		(layer "In2.Cu")
		(net 139)
	)
	(segment
		(start 260.1 162.5)
		(end 263.9 162.5)
		(width 0.2)
		(layer "In2.Cu")
		(net 139)
	)
	(segment
		(start 222.65 163.85)
		(end 227.65 163.85)
		(width 0.2)
		(layer "In2.Cu")
		(net 139)
	)
	(segment
		(start 259.31 161.71)
		(end 260.1 162.5)
		(width 0.2)
		(layer "In2.Cu")
		(net 139)
	)
	(segment
		(start 233.4 158.1)
		(end 242.84 158.1)
		(width 0.2)
		(layer "In2.Cu")
		(net 139)
	)
	(segment
		(start 253.21 161.71)
		(end 259.31 161.71)
		(width 0.2)
		(layer "In2.Cu")
		(net 139)
	)
	(segment
		(start 242.84 158.1)
		(end 243.12 158.38)
		(width 0.2)
		(layer "In2.Cu")
		(net 139)
	)
	(segment
		(start 249.88 158.38)
		(end 253.21 161.71)
		(width 0.2)
		(layer "In2.Cu")
		(net 139)
	)
	(segment
		(start 227.65 163.85)
		(end 233.4 158.1)
		(width 0.2)
		(layer "In2.Cu")
		(net 139)
	)
	(via
		(at 149.45 135.86)
		(size 0.45)
		(drill 0.1)
		(layers "F.Cu" "B.Cu")
		(remove_unused_layers yes)
		(keep_end_layers yes)
		(zone_layer_connections)
		(teardrops
			(best_length_ratio 0.4)
			(max_length 1)
			(best_width_ratio 0.9)
			(max_width 2)
			(curved_edges yes)
			(filter_ratio 0.9)
			(enabled yes)
			(allow_two_segments yes)
			(prefer_zone_connections yes)
		)
		(net 141)
	)
	(segment
		(start 139.6 131.561)
		(end 139.6 133.461)
		(width 0.125)
		(layer "B.Cu")
		(net 141)
	)
	(segment
		(start 144.73 136.06)
		(end 144.73 135.68)
		(width 0.125)
		(layer "B.Cu")
		(net 141)
	)
	(segment
		(start 142.401 131.561)
		(end 139.6 131.561)
		(width 0.125)
		(layer "B.Cu")
		(net 141)
	)
	(segment
		(start 143.25 132.41)
		(end 142.401 131.561)
		(width 0.125)
		(layer "B.Cu")
		(net 141)
	)
	(segment
		(start 145.05 135.36)
		(end 143.25 133.56)
		(width 0.125)
		(layer "B.Cu")
		(net 141)
	)
	(segment
		(start 145.05 135.36)
		(end 148.95 135.36)
		(width 0.125)
		(layer "B.Cu")
		(net 141)
	)
	(segment
		(start 148.95 135.36)
		(end 149.45 135.86)
		(width 0.125)
		(layer "B.Cu")
		(net 141)
	)
	(segment
		(start 144.73 135.68)
		(end 145.05 135.36)
		(width 0.125)
		(layer "B.Cu")
		(net 141)
	)
	(segment
		(start 143.25 133.56)
		(end 143.25 132.41)
		(width 0.125)
		(layer "B.Cu")
		(net 141)
	)
	(segment
		(start 160.1 153.2)
		(end 159.75 152.85)
		(width 0.125)
		(layer "F.Cu")
		(net 142)
	)
	(segment
		(start 189.625 155.425)
		(end 192.85 155.425)
		(width 0.125)
		(layer "F.Cu")
		(net 142)
	)
	(segment
		(start 193.025 155.6)
		(end 192.85 155.425)
		(width 0.125)
		(layer "F.Cu")
		(net 142)
	)
	(segment
		(start 161.05 153.2)
		(end 160.1 153.2)
		(width 0.125)
		(layer "F.Cu")
		(net 142)
	)
	(segment
		(start 188.8 154.6)
		(end 189.625 155.425)
		(width 0.125)
		(layer "F.Cu")
		(net 142)
	)
	(segment
		(start 159.75 148)
		(end 159.5 147.75)
		(width 0.125)
		(layer "F.Cu")
		(net 142)
	)
	(segment
		(start 193.025 156.685)
		(end 193.025 155.6)
		(width 0.125)
		(layer "F.Cu")
		(net 142)
	)
	(segment
		(start 188.8 154.6)
		(end 176.15 154.6)
		(width 0.125)
		(layer "F.Cu")
		(net 142)
	)
	(segment
		(start 159.75 152.85)
		(end 159.75 148)
		(width 0.125)
		(layer "F.Cu")
		(net 142)
	)
	(via
		(at 159.5 147.75)
		(size 0.45)
		(drill 0.1)
		(layers "F.Cu" "B.Cu")
		(remove_unused_layers yes)
		(keep_end_layers yes)
		(zone_layer_connections "In2.Cu")
		(teardrops
			(best_length_ratio 0.4)
			(max_length 1)
			(best_width_ratio 0.9)
			(max_width 2)
			(curved_edges yes)
			(filter_ratio 0.9)
			(enabled yes)
			(allow_two_segments yes)
			(prefer_zone_connections yes)
		)
		(net 142)
	)
	(via
		(at 176.15 154.6)
		(size 0.45)
		(drill 0.1)
		(layers "F.Cu" "B.Cu")
		(teardrops
			(best_length_ratio 0.4)
			(max_length 1)
			(best_width_ratio 0.9)
			(max_width 2)
			(curved_edges yes)
			(filter_ratio 0.9)
			(enabled yes)
			(allow_two_segments yes)
			(prefer_zone_connections yes)
		)
		(net 142)
	)
	(via
		(at 161.05 153.2)
		(size 0.45)
		(drill 0.1)
		(layers "F.Cu" "B.Cu")
		(remove_unused_layers yes)
		(keep_end_layers yes)
		(zone_layer_connections "In2.Cu")
		(teardrops
			(best_length_ratio 0.4)
			(max_length 1)
			(best_width_ratio 0.9)
			(max_width 2)
			(curved_edges yes)
			(filter_ratio 0.9)
			(enabled yes)
			(allow_two_segments yes)
			(prefer_zone_connections yes)
		)
		(net 142)
	)
	(via
		(at 141.05 135.81)
		(size 0.45)
		(drill 0.1)
		(layers "F.Cu" "B.Cu")
		(remove_unused_layers yes)
		(keep_end_layers yes)
		(zone_layer_connections "In2.Cu")
		(teardrops
			(best_length_ratio 0.4)
			(max_length 1)
			(best_width_ratio 0.9)
			(max_width 2)
			(curved_edges yes)
			(filter_ratio 0.9)
			(enabled yes)
			(allow_two_segments yes)
			(prefer_zone_connections yes)
		)
		(net 142)
	)
	(segment
		(start 141.0505 135.8105)
		(end 141.8 135.8105)
		(width 0.125)
		(layer "B.Cu")
		(net 142)
	)
	(segment
		(start 141.05 135.81)
		(end 141.0505 135.8105)
		(width 0.125)
		(layer "B.Cu")
		(net 142)
	)
	(segment
		(start 141.8 132.5105)
		(end 141.8 135.8105)
		(width 0.125)
		(layer "B.Cu")
		(net 142)
	)
	(segment
		(start 162.05 152.2)
		(end 171 152.2)
		(width 0.125)
		(layer "In2.Cu")
		(net 142)
	)
	(segment
		(start 159.49 147.75)
		(end 157.1 145.36)
		(width 0.125)
		(layer "In2.Cu")
		(net 142)
	)
	(segment
		(start 141.45 143.51)
		(end 141.45 136.21)
		(width 0.125)
		(layer "In2.Cu")
		(net 142)
	)
	(segment
		(start 175.2 154.6)
		(end 176.15 154.6)
		(width 0.125)
		(layer "In2.Cu")
		(net 142)
	)
	(segment
		(start 157.1 145.36)
		(end 143.3 145.36)
		(width 0.125)
		(layer "In2.Cu")
		(net 142)
	)
	(segment
		(start 161.05 153.2)
		(end 162.05 152.2)
		(width 0.125)
		(layer "In2.Cu")
		(net 142)
	)
	(segment
		(start 175 154.8)
		(end 175.2 154.6)
		(width 0.125)
		(layer "In2.Cu")
		(net 142)
	)
	(segment
		(start 159.5 147.75)
		(end 159.49 147.75)
		(width 0.125)
		(layer "In2.Cu")
		(net 142)
	)
	(segment
		(start 141.45 136.21)
		(end 141.05 135.81)
		(width 0.125)
		(layer "In2.Cu")
		(net 142)
	)
	(segment
		(start 143.3 145.36)
		(end 141.45 143.51)
		(width 0.125)
		(layer "In2.Cu")
		(net 142)
	)
	(segment
		(start 173.6 154.8)
		(end 175 154.8)
		(width 0.125)
		(layer "In2.Cu")
		(net 142)
	)
	(segment
		(start 171 152.2)
		(end 173.6 154.8)
		(width 0.125)
		(layer "In2.Cu")
		(net 142)
	)
	(via
		(at 140.25 135.81)
		(size 0.45)
		(drill 0.1)
		(layers "F.Cu" "B.Cu")
		(remove_unused_layers yes)
		(keep_end_layers yes)
		(zone_layer_connections "In2.Cu")
		(teardrops
			(best_length_ratio 0.4)
			(max_length 1)
			(best_width_ratio 0.9)
			(max_width 2)
			(curved_edges yes)
			(filter_ratio 0.9)
			(enabled yes)
			(allow_two_segments yes)
			(prefer_zone_connections yes)
		)
		(net 143)
	)
	(via
		(at 131.29 135.86)
		(size 0.45)
		(drill 0.1)
		(layers "F.Cu" "B.Cu")
		(remove_unused_layers yes)
		(keep_end_layers yes)
		(zone_layer_connections "In2.Cu")
		(teardrops
			(best_length_ratio 0.4)
			(max_length 1)
			(best_width_ratio 0.9)
			(max_width 2)
			(curved_edges yes)
			(filter_ratio 0.9)
			(enabled yes)
			(allow_two_segments yes)
			(prefer_zone_connections yes)
		)
		(net 143)
	)
	(segment
		(start 130.79 135.36)
		(end 131.29 135.86)
		(width 0.125)
		(layer "B.Cu")
		(net 143)
	)
	(segment
		(start 126.57 135.68)
		(end 126.89 135.36)
		(width 0.125)
		(layer "B.Cu")
		(net 143)
	)
	(segment
		(start 140.25 135.81)
		(end 140.25 136.66)
		(width 0.125)
		(layer "B.Cu")
		(net 143)
	)
	(segment
		(start 140.25 135.81)
		(end 140.25 134.96)
		(width 0.125)
		(layer "B.Cu")
		(net 143)
	)
	(segment
		(start 126.89 135.36)
		(end 130.79 135.36)
		(width 0.125)
		(layer "B.Cu")
		(net 143)
	)
	(segment
		(start 140.151 134.861)
		(end 139.6 134.861)
		(width 0.125)
		(layer "B.Cu")
		(net 143)
	)
	(segment
		(start 140.149 136.761)
		(end 139.6 136.761)
		(width 0.125)
		(layer "B.Cu")
		(net 143)
	)
	(segment
		(start 126.57 136.06)
		(end 126.57 135.68)
		(width 0.125)
		(layer "B.Cu")
		(net 143)
	)
	(segment
		(start 140.25 136.66)
		(end 140.149 136.761)
		(width 0.125)
		(layer "B.Cu")
		(net 143)
	)
	(segment
		(start 140.25 134.96)
		(end 140.151 134.861)
		(width 0.125)
		(layer "B.Cu")
		(net 143)
	)
	(segment
		(start 131.79 136.36)
		(end 139.7 136.36)
		(width 0.125)
		(layer "In2.Cu")
		(net 143)
	)
	(segment
		(start 131.29 135.86)
		(end 131.79 136.36)
		(width 0.125)
		(layer "In2.Cu")
		(net 143)
	)
	(segment
		(start 139.7 136.36)
		(end 140.25 135.81)
		(width 0.125)
		(layer "In2.Cu")
		(net 143)
	)
	(segment
		(start 319.45 155.31)
		(end 317.3 155.31)
		(width 0.55)
		(layer "F.Cu")
		(net 144)
	)
	(segment
		(start 319.45 153.71)
		(end 317.3 153.71)
		(width 0.55)
		(layer "F.Cu")
		(net 144)
	)
	(segment
		(start 319.45 154.51)
		(end 317.3 154.51)
		(width 0.55)
		(layer "F.Cu")
		(net 144)
	)
	(segment
		(start 319.45 152.91)
		(end 317.3 152.91)
		(width 0.55)
		(layer "F.Cu")
		(net 144)
	)
	(segment
		(start 319.5 156.11)
		(end 317.35 156.11)
		(width 0.55)
		(layer "F.Cu")
		(net 144)
	)
	(via
		(at 311.85 152.56)
		(size 0.45)
		(drill 0.1)
		(layers "F.Cu" "B.Cu")
		(remove_unused_layers yes)
		(keep_end_layers yes)
		(zone_layer_connections "In3.Cu")
		(teardrops
			(best_length_ratio 0.4)
			(max_length 1)
			(best_width_ratio 0.9)
			(max_width 2)
			(curved_edges yes)
			(filter_ratio 0.9)
			(enabled yes)
			(allow_two_segments yes)
			(prefer_zone_connections yes)
		)
		(net 144)
	)
	(via
		(at 311.3 150.91)
		(size 0.45)
		(drill 0.1)
		(layers "F.Cu" "B.Cu")
		(remove_unused_layers yes)
		(keep_end_layers yes)
		(zone_layer_connections "In3.Cu")
		(teardrops
			(best_length_ratio 0.4)
			(max_length 1)
			(best_width_ratio 0.9)
			(max_width 2)
			(curved_edges yes)
			(filter_ratio 0.9)
			(enabled yes)
			(allow_two_segments yes)
			(prefer_zone_connections yes)
		)
		(net 144)
	)
	(via
		(at 311.85 150.91)
		(size 0.45)
		(drill 0.1)
		(layers "F.Cu" "B.Cu")
		(remove_unused_layers yes)
		(keep_end_layers yes)
		(zone_layer_connections "In3.Cu")
		(teardrops
			(best_length_ratio 0.4)
			(max_length 1)
			(best_width_ratio 0.9)
			(max_width 2)
			(curved_edges yes)
			(filter_ratio 0.9)
			(enabled yes)
			(allow_two_segments yes)
			(prefer_zone_connections yes)
		)
		(net 144)
	)
	(via
		(at 310.75 150.91)
		(size 0.45)
		(drill 0.1)
		(layers "F.Cu" "B.Cu")
		(remove_unused_layers yes)
		(keep_end_layers yes)
		(zone_layer_connections "In3.Cu")
		(teardrops
			(best_length_ratio 0.4)
			(max_length 1)
			(best_width_ratio 0.9)
			(max_width 2)
			(curved_edges yes)
			(filter_ratio 0.9)
			(enabled yes)
			(allow_two_segments yes)
			(prefer_zone_connections yes)
		)
		(net 144)
	)
	(via
		(at 310.75 150.31)
		(size 0.45)
		(drill 0.1)
		(layers "F.Cu" "B.Cu")
		(remove_unused_layers yes)
		(keep_end_layers yes)
		(zone_layer_connections "In3.Cu")
		(teardrops
			(best_length_ratio 0.4)
			(max_length 1)
			(best_width_ratio 0.9)
			(max_width 2)
			(curved_edges yes)
			(filter_ratio 0.9)
			(enabled yes)
			(allow_two_segments yes)
			(prefer_zone_connections yes)
		)
		(net 144)
	)
	(via
		(at 311.3 152.56)
		(size 0.45)
		(drill 0.1)
		(layers "F.Cu" "B.Cu")
		(remove_unused_layers yes)
		(keep_end_layers yes)
		(zone_layer_connections "In3.Cu")
		(teardrops
			(best_length_ratio 0.4)
			(max_length 1)
			(best_width_ratio 0.9)
			(max_width 2)
			(curved_edges yes)
			(filter_ratio 0.9)
			(enabled yes)
			(allow_two_segments yes)
			(prefer_zone_connections yes)
		)
		(net 144)
	)
	(via
		(at 311.85 151.46)
		(size 0.45)
		(drill 0.1)
		(layers "F.Cu" "B.Cu")
		(remove_unused_layers yes)
		(keep_end_layers yes)
		(zone_layer_connections "In3.Cu")
		(teardrops
			(best_length_ratio 0.4)
			(max_length 1)
			(best_width_ratio 0.9)
			(max_width 2)
			(curved_edges yes)
			(filter_ratio 0.9)
			(enabled yes)
			(allow_two_segments yes)
			(prefer_zone_connections yes)
		)
		(net 144)
	)
	(via
		(at 311.3 152.01)
		(size 0.45)
		(drill 0.1)
		(layers "F.Cu" "B.Cu")
		(remove_unused_layers yes)
		(keep_end_layers yes)
		(zone_layer_connections "In3.Cu")
		(teardrops
			(best_length_ratio 0.4)
			(max_length 1)
			(best_width_ratio 0.9)
			(max_width 2)
			(curved_edges yes)
			(filter_ratio 0.9)
			(enabled yes)
			(allow_two_segments yes)
			(prefer_zone_connections yes)
		)
		(net 144)
	)
	(via
		(at 311.85 150.31)
		(size 0.45)
		(drill 0.1)
		(layers "F.Cu" "B.Cu")
		(remove_unused_layers yes)
		(keep_end_layers yes)
		(zone_layer_connections "In3.Cu")
		(teardrops
			(best_length_ratio 0.4)
			(max_length 1)
			(best_width_ratio 0.9)
			(max_width 2)
			(curved_edges yes)
			(filter_ratio 0.9)
			(enabled yes)
			(allow_two_segments yes)
			(prefer_zone_connections yes)
		)
		(net 144)
	)
	(via
		(at 310.75 151.46)
		(size 0.45)
		(drill 0.1)
		(layers "F.Cu" "B.Cu")
		(remove_unused_layers yes)
		(keep_end_layers yes)
		(zone_layer_connections "In3.Cu")
		(teardrops
			(best_length_ratio 0.4)
			(max_length 1)
			(best_width_ratio 0.9)
			(max_width 2)
			(curved_edges yes)
			(filter_ratio 0.9)
			(enabled yes)
			(allow_two_segments yes)
			(prefer_zone_connections yes)
		)
		(net 144)
	)
	(via
		(at 310.2 150.91)
		(size 0.45)
		(drill 0.1)
		(layers "F.Cu" "B.Cu")
		(remove_unused_layers yes)
		(keep_end_layers yes)
		(zone_layer_connections "In3.Cu")
		(teardrops
			(best_length_ratio 0.4)
			(max_length 1)
			(best_width_ratio 0.9)
			(max_width 2)
			(curved_edges yes)
			(filter_ratio 0.9)
			(enabled yes)
			(allow_two_segments yes)
			(prefer_zone_connections yes)
		)
		(net 144)
	)
	(via
		(at 311.3 150.31)
		(size 0.45)
		(drill 0.1)
		(layers "F.Cu" "B.Cu")
		(remove_unused_layers yes)
		(keep_end_layers yes)
		(zone_layer_connections "In3.Cu")
		(teardrops
			(best_length_ratio 0.4)
			(max_length 1)
			(best_width_ratio 0.9)
			(max_width 2)
			(curved_edges yes)
			(filter_ratio 0.9)
			(enabled yes)
			(allow_two_segments yes)
			(prefer_zone_connections yes)
		)
		(net 144)
	)
	(via
		(at 310.75 152.56)
		(size 0.45)
		(drill 0.1)
		(layers "F.Cu" "B.Cu")
		(remove_unused_layers yes)
		(keep_end_layers yes)
		(zone_layer_connections "In3.Cu")
		(teardrops
			(best_length_ratio 0.4)
			(max_length 1)
			(best_width_ratio 0.9)
			(max_width 2)
			(curved_edges yes)
			(filter_ratio 0.9)
			(enabled yes)
			(allow_two_segments yes)
			(prefer_zone_connections yes)
		)
		(net 144)
	)
	(via
		(at 310.2 152.01)
		(size 0.45)
		(drill 0.1)
		(layers "F.Cu" "B.Cu")
		(remove_unused_layers yes)
		(keep_end_layers yes)
		(zone_layer_connections "In3.Cu")
		(teardrops
			(best_length_ratio 0.4)
			(max_length 1)
			(best_width_ratio 0.9)
			(max_width 2)
			(curved_edges yes)
			(filter_ratio 0.9)
			(enabled yes)
			(allow_two_segments yes)
			(prefer_zone_connections yes)
		)
		(net 144)
	)
	(via
		(at 311.85 152.01)
		(size 0.45)
		(drill 0.1)
		(layers "F.Cu" "B.Cu")
		(remove_unused_layers yes)
		(keep_end_layers yes)
		(zone_layer_connections "In3.Cu")
		(teardrops
			(best_length_ratio 0.4)
			(max_length 1)
			(best_width_ratio 0.9)
			(max_width 2)
			(curved_edges yes)
			(filter_ratio 0.9)
			(enabled yes)
			(allow_two_segments yes)
			(prefer_zone_connections yes)
		)
		(net 144)
	)
	(via
		(at 310.75 152.01)
		(size 0.45)
		(drill 0.1)
		(layers "F.Cu" "B.Cu")
		(remove_unused_layers yes)
		(keep_end_layers yes)
		(zone_layer_connections "In3.Cu")
		(teardrops
			(best_length_ratio 0.4)
			(max_length 1)
			(best_width_ratio 0.9)
			(max_width 2)
			(curved_edges yes)
			(filter_ratio 0.9)
			(enabled yes)
			(allow_two_segments yes)
			(prefer_zone_connections yes)
		)
		(net 144)
	)
	(via
		(at 310.2 150.31)
		(size 0.45)
		(drill 0.1)
		(layers "F.Cu" "B.Cu")
		(remove_unused_layers yes)
		(keep_end_layers yes)
		(zone_layer_connections "In3.Cu")
		(teardrops
			(best_length_ratio 0.4)
			(max_length 1)
			(best_width_ratio 0.9)
			(max_width 2)
			(curved_edges yes)
			(filter_ratio 0.9)
			(enabled yes)
			(allow_two_segments yes)
			(prefer_zone_connections yes)
		)
		(net 144)
	)
	(via
		(at 311.3 151.46)
		(size 0.45)
		(drill 0.1)
		(layers "F.Cu" "B.Cu")
		(remove_unused_layers yes)
		(keep_end_layers yes)
		(zone_layer_connections "In3.Cu")
		(teardrops
			(best_length_ratio 0.4)
			(max_length 1)
			(best_width_ratio 0.9)
			(max_width 2)
			(curved_edges yes)
			(filter_ratio 0.9)
			(enabled yes)
			(allow_two_segments yes)
			(prefer_zone_connections yes)
		)
		(net 144)
	)
	(via
		(at 310.2 151.46)
		(size 0.45)
		(drill 0.1)
		(layers "F.Cu" "B.Cu")
		(remove_unused_layers yes)
		(keep_end_layers yes)
		(zone_layer_connections "In3.Cu")
		(teardrops
			(best_length_ratio 0.4)
			(max_length 1)
			(best_width_ratio 0.9)
			(max_width 2)
			(curved_edges yes)
			(filter_ratio 0.9)
			(enabled yes)
			(allow_two_segments yes)
			(prefer_zone_connections yes)
		)
		(net 144)
	)
	(via
		(at 310.2 152.56)
		(size 0.45)
		(drill 0.1)
		(layers "F.Cu" "B.Cu")
		(remove_unused_layers yes)
		(keep_end_layers yes)
		(zone_layer_connections "In3.Cu")
		(teardrops
			(best_length_ratio 0.4)
			(max_length 1)
			(best_width_ratio 0.9)
			(max_width 2)
			(curved_edges yes)
			(filter_ratio 0.9)
			(enabled yes)
			(allow_two_segments yes)
			(prefer_zone_connections yes)
		)
		(net 144)
	)
	(segment
		(start 319.45 154.51)
		(end 317.299999 154.51)
		(width 0.55)
		(layer "B.Cu")
		(net 144)
	)
	(segment
		(start 319.45 155.31)
		(end 317.299999 155.31)
		(width 0.55)
		(layer "B.Cu")
		(net 144)
	)
	(segment
		(start 319.45 153.71)
		(end 317.299999 153.71)
		(width 0.55)
		(layer "B.Cu")
		(net 144)
	)
	(segment
		(start 319.45 156.11)
		(end 317.299999 156.11)
		(width 0.55)
		(layer "B.Cu")
		(net 144)
	)
	(segment
		(start 319.45 152.91)
		(end 317.299999 152.91)
		(width 0.55)
		(layer "B.Cu")
		(net 144)
	)
	(segment
		(start 310.85 145.81)
		(end 310.85 145.11)
		(width 0.125)
		(layer "F.Cu")
		(net 145)
	)
	(segment
		(start 310.65 144.91)
		(end 308.35 144.91)
		(width 0.125)
		(layer "F.Cu")
		(net 145)
	)
	(segment
		(start 308.35 144.91)
		(end 306.475 146.785)
		(width 0.125)
		(layer "F.Cu")
		(net 145)
	)
	(segment
		(start 310.85 145.11)
		(end 310.65 144.91)
		(width 0.125)
		(layer "F.Cu")
		(net 145)
	)
	(segment
		(start 306.475 146.785)
		(end 306.475 147.809)
		(width 0.125)
		(layer "F.Cu")
		(net 145)
	)
	(segment
		(start 119.744699 108.675)
		(end 119.838699 108.675)
		(width 0.15)
		(layer "F.Cu")
		(net 146)
	)
	(segment
		(start 121.527512 108.675)
		(end 121.925 109.072488)
		(width 0.15)
		(layer "F.Cu")
		(net 146)
	)
	(segment
		(start 120.214699 109.07636)
		(end 120.308699 109.07636)
		(width 0.15)
		(layer "F.Cu")
		(net 146)
	)
	(segment
		(start 118.15 109.81)
		(end 118.15 108.787488)
		(width 0.15)
		(layer "F.Cu")
		(net 146)
	)
	(segment
		(start 125.905 113.485)
		(end 126.19 113.77)
		(width 0.15)
		(layer "F.Cu")
		(net 146)
	)
	(segment
		(start 122.185367 112.765661)
		(end 122.925514 112.025514)
		(width 0.15)
		(layer "F.Cu")
		(net 146)
	)
	(segment
		(start 119.086699 108.863)
		(end 119.086699 109.18836)
		(width 0.15)
		(layer "F.Cu")
		(net 146)
	)
	(segment
		(start 123.737271 113.084758)
		(end 124.137512 113.485)
		(width 0.15)
		(layer "F.Cu")
		(net 146)
	)
	(segment
		(start 122.113756 111.461244)
		(end 122.113755 111.461242)
		(width 0.15)
		(layer "F.Cu")
		(net 146)
	)
	(segment
		(start 120.778699 108.675)
		(end 120.83113 108.675)
		(width 0.15)
		(layer "F.Cu")
		(net 146)
	)
	(segment
		(start 121.925 111.272488)
		(end 122.113756 111.461244)
		(width 0.15)
		(layer "F.Cu")
		(net 146)
	)
	(segment
		(start 122.925513 112.025513)
		(end 123.665651 111.285378)
		(width 0.15)
		(layer "F.Cu")
		(net 146)
	)
	(segment
		(start 120.026699 108.863)
		(end 120.026699 108.88836)
		(width 0.15)
		(layer "F.Cu")
		(net 146)
	)
	(segment
		(start 118.262488 108.675)
		(end 118.898699 108.675)
		(width 0.15)
		(layer "F.Cu")
		(net 146)
	)
	(segment
		(start 118.15 108.787488)
		(end 118.262488 108.675)
		(width 0.15)
		(layer "F.Cu")
		(net 146)
	)
	(segment
		(start 121.925 109.072488)
		(end 121.925 111.272488)
		(width 0.15)
		(layer "F.Cu")
		(net 146)
	)
	(segment
		(start 122.925513 112.025513)
		(end 122.925514 112.025514)
		(width 0.15)
		(layer "F.Cu")
		(net 146)
	)
	(segment
		(start 123.012681 113.592975)
		(end 123.520897 113.084758)
		(width 0.15)
		(layer "F.Cu")
		(net 146)
	)
	(segment
		(start 123.549685 110.953037)
		(end 123.66565 111.069002)
		(width 0.15)
		(layer "F.Cu")
		(net 146)
	)
	(segment
		(start 119.274699 109.37636)
		(end 119.368699 109.37636)
		(width 0.15)
		(layer "F.Cu")
		(net 146)
	)
	(segment
		(start 122.825105 111.461243)
		(end 123.333311 110.953038)
		(width 0.15)
		(layer "F.Cu")
		(net 146)
	)
	(segment
		(start 120.83113 108.675)
		(end 121.527512 108.675)
		(width 0.15)
		(layer "F.Cu")
		(net 146)
	)
	(segment
		(start 120.496699 108.88836)
		(end 120.496699 108.863)
		(width 0.15)
		(layer "F.Cu")
		(net 146)
	)
	(segment
		(start 124.137512 113.485)
		(end 125.905 113.485)
		(width 0.15)
		(layer "F.Cu")
		(net 146)
	)
	(segment
		(start 126.19 113.77)
		(end 126.29 113.77)
		(width 0.15)
		(layer "F.Cu")
		(net 146)
	)
	(segment
		(start 120.684699 108.675)
		(end 120.778699 108.675)
		(width 0.15)
		(layer "F.Cu")
		(net 146)
	)
	(segment
		(start 122.185367 113.47701)
		(end 122.301332 113.592975)
		(width 0.15)
		(layer "F.Cu")
		(net 146)
	)
	(segment
		(start 119.556699 109.18836)
		(end 119.556699 108.863)
		(width 0.15)
		(layer "F.Cu")
		(net 146)
	)
	(arc
		(start 119.086699 109.18836)
		(mid 119.141763 109.321296)
		(end 119.274699 109.37636)
		(width 0.15)
		(layer "F.Cu")
		(net 146)
	)
	(arc
		(start 120.496699 108.863)
		(mid 120.551763 108.730064)
		(end 120.684699 108.675)
		(width 0.15)
		(layer "F.Cu")
		(net 146)
	)
	(arc
		(start 122.301332 113.592975)
		(mid 122.657007 113.7403)
		(end 123.012681 113.592975)
		(width 0.15)
		(layer "F.Cu")
		(net 146)
	)
	(arc
		(start 123.520897 113.084758)
		(mid 123.629084 113.039945)
		(end 123.737271 113.084758)
		(width 0.15)
		(layer "F.Cu")
		(net 146)
	)
	(arc
		(start 123.333311 110.953038)
		(mid 123.441498 110.908225)
		(end 123.549685 110.953037)
		(width 0.15)
		(layer "F.Cu")
		(net 146)
	)
	(arc
		(start 122.113755 111.461242)
		(mid 122.469432 111.608569)
		(end 122.825105 111.461243)
		(width 0.15)
		(layer "F.Cu")
		(net 146)
	)
	(arc
		(start 120.308699 109.07636)
		(mid 120.441635 109.021296)
		(end 120.496699 108.88836)
		(width 0.15)
		(layer "F.Cu")
		(net 146)
	)
	(arc
		(start 119.368699 109.37636)
		(mid 119.501635 109.321296)
		(end 119.556699 109.18836)
		(width 0.15)
		(layer "F.Cu")
		(net 146)
	)
	(arc
		(start 119.556699 108.863)
		(mid 119.611763 108.730064)
		(end 119.744699 108.675)
		(width 0.15)
		(layer "F.Cu")
		(net 146)
	)
	(arc
		(start 123.66565 111.069002)
		(mid 123.710462 111.17719)
		(end 123.665651 111.285378)
		(width 0.15)
		(layer "F.Cu")
		(net 146)
	)
	(arc
		(start 122.185367 112.765661)
		(mid 122.038042 113.121335)
		(end 122.185367 113.47701)
		(width 0.15)
		(layer "F.Cu")
		(net 146)
	)
	(arc
		(start 120.026699 108.88836)
		(mid 120.081763 109.021296)
		(end 120.214699 109.07636)
		(width 0.15)
		(layer "F.Cu")
		(net 146)
	)
	(arc
		(start 119.838699 108.675)
		(mid 119.971635 108.730064)
		(end 120.026699 108.863)
		(width 0.15)
		(layer "F.Cu")
		(net 146)
	)
	(arc
		(start 118.898699 108.675)
		(mid 119.031635 108.730064)
		(end 119.086699 108.863)
		(width 0.15)
		(layer "F.Cu")
		(net 146)
	)
	(segment
		(start 123.173 112.273)
		(end 123.913138 111.532865)
		(width 0.15)
		(layer "F.Cu")
		(net 147)
	)
	(segment
		(start 122.765194 113.345488)
		(end 123.27341 112.837271)
		(width 0.15)
		(layer "F.Cu")
		(net 147)
	)
	(segment
		(start 126.19 112.85)
		(end 126.29 112.85)
		(width 0.15)
		(layer "F.Cu")
		(net 147)
	)
	(segment
		(start 122.275 108.927512)
		(end 122.275 111.127512)
		(width 0.15)
		(layer "F.Cu")
		(net 147)
	)
	(segment
		(start 123.984759 112.837271)
		(end 124.282488 113.135)
		(width 0.15)
		(layer "F.Cu")
		(net 147)
	)
	(segment
		(start 122.432854 113.013148)
		(end 123.173001 112.273001)
		(width 0.15)
		(layer "F.Cu")
		(net 147)
	)
	(segment
		(start 122.432854 113.229523)
		(end 122.548819 113.345488)
		(width 0.15)
		(layer "F.Cu")
		(net 147)
	)
	(segment
		(start 122.577618 111.213756)
		(end 123.085824 110.705551)
		(width 0.15)
		(layer "F.Cu")
		(net 147)
	)
	(segment
		(start 123.173 112.273)
		(end 123.173001 112.273001)
		(width 0.15)
		(layer "F.Cu")
		(net 147)
	)
	(segment
		(start 117.902512 108.54)
		(end 118.117512 108.325)
		(width 0.15)
		(layer "F.Cu")
		(net 147)
	)
	(segment
		(start 125.905 113.135)
		(end 126.19 112.85)
		(width 0.15)
		(layer "F.Cu")
		(net 147)
	)
	(segment
		(start 115.61 108.54)
		(end 117.902512 108.54)
		(width 0.15)
		(layer "F.Cu")
		(net 147)
	)
	(segment
		(start 124.282488 113.135)
		(end 125.905 113.135)
		(width 0.15)
		(layer "F.Cu")
		(net 147)
	)
	(segment
		(start 121.672488 108.325)
		(end 122.275 108.927512)
		(width 0.15)
		(layer "F.Cu")
		(net 147)
	)
	(segment
		(start 122.275 111.127512)
		(end 122.361244 111.213756)
		(width 0.15)
		(layer "F.Cu")
		(net 147)
	)
	(segment
		(start 122.361244 111.213756)
		(end 122.361242 111.213755)
		(width 0.15)
		(layer "F.Cu")
		(net 147)
	)
	(segment
		(start 123.797172 110.70555)
		(end 123.913137 110.821515)
		(width 0.15)
		(layer "F.Cu")
		(net 147)
	)
	(segment
		(start 118.117512 108.325)
		(end 121.672488 108.325)
		(width 0.15)
		(layer "F.Cu")
		(net 147)
	)
	(arc
		(start 122.548819 113.345488)
		(mid 122.657007 113.3903)
		(end 122.765194 113.345488)
		(width 0.15)
		(layer "F.Cu")
		(net 147)
	)
	(arc
		(start 123.913137 110.821515)
		(mid 124.060462 111.17719)
		(end 123.913138 111.532865)
		(width 0.15)
		(layer "F.Cu")
		(net 147)
	)
	(arc
		(start 123.085824 110.705551)
		(mid 123.441497 110.558225)
		(end 123.797172 110.70555)
		(width 0.15)
		(layer "F.Cu")
		(net 147)
	)
	(arc
		(start 122.432854 113.013148)
		(mid 122.388041 113.121335)
		(end 122.432854 113.229523)
		(width 0.15)
		(layer "F.Cu")
		(net 147)
	)
	(arc
		(start 122.361242 111.213755)
		(mid 122.469432 111.258569)
		(end 122.577618 111.213756)
		(width 0.15)
		(layer "F.Cu")
		(net 147)
	)
	(arc
		(start 123.27341 112.837271)
		(mid 123.629084 112.689946)
		(end 123.984759 112.837271)
		(width 0.15)
		(layer "F.Cu")
		(net 147)
	)
	(segment
		(start 114.5 106.6)
		(end 115.17 107.27)
		(width 0.15)
		(layer "F.Cu")
		(net 148)
	)
	(segment
		(start 125.783749 105.96)
		(end 125.498749 105.675)
		(width 0.15)
		(layer "F.Cu")
		(net 148)
	)
	(segment
		(start 115.17 107.27)
		(end 118.15 107.27)
		(width 0.15)
		(layer "F.Cu")
		(net 148)
	)
	(segment
		(start 117.325 103.575)
		(end 116.2 104.7)
		(width 0.15)
		(layer "F.Cu")
		(net 148)
	)
	(segment
		(start 126.29 105.96)
		(end 125.783749 105.96)
		(width 0.15)
		(layer "F.Cu")
		(net 148)
	)
	(segment
		(start 114.5 105.1)
		(end 114.5 106.6)
		(width 0.15)
		(layer "F.Cu")
		(net 148)
	)
	(segment
		(start 123.427512 105.675)
		(end 121.327512 103.575)
		(width 0.15)
		(layer "F.Cu")
		(net 148)
	)
	(segment
		(start 116.2 104.7)
		(end 114.9 104.7)
		(width 0.15)
		(layer "F.Cu")
		(net 148)
	)
	(segment
		(start 121.327512 103.575)
		(end 117.325 103.575)
		(width 0.15)
		(layer "F.Cu")
		(net 148)
	)
	(segment
		(start 114.9 104.7)
		(end 114.5 105.1)
		(width 0.15)
		(layer "F.Cu")
		(net 148)
	)
	(segment
		(start 125.498749 105.675)
		(end 123.427512 105.675)
		(width 0.15)
		(layer "F.Cu")
		(net 148)
	)
	(segment
		(start 123.264184 109.664771)
		(end 123.377321 109.777908)
		(width 0.15)
		(layer "F.Cu")
		(net 149)
	)
	(segment
		(start 126.19 109.88)
		(end 126.29 109.88)
		(width 0.15)
		(layer "F.Cu")
		(net 149)
	)
	(segment
		(start 124.819556 109.467043)
		(end 124.947512 109.595)
		(width 0.15)
		(layer "F.Cu")
		(net 149)
	)
	(segment
		(start 124.947512 109.595)
		(end 125.905 109.595)
		(width 0.15)
		(layer "F.Cu")
		(net 149)
	)
	(segment
		(start 119.95506 105.696)
		(end 119.95506 104.842749)
		(width 0.15)
		(layer "F.Cu")
		(net 149)
	)
	(segment
		(start 123.914461 108.31446)
		(end 124.56475 107.66417)
		(width 0.15)
		(layer "F.Cu")
		(net 149)
	)
	(segment
		(start 123.914461 108.31446)
		(end 123.91446 108.31446)
		(width 0.15)
		(layer "F.Cu")
		(net 149)
	)
	(segment
		(start 123.264184 108.964736)
		(end 123.91446 108.31446)
		(width 0.15)
		(layer "F.Cu")
		(net 149)
	)
	(segment
		(start 119.47606 106.175)
		(end 115.785 106.175)
		(width 0.15)
		(layer "F.Cu")
		(net 149)
	)
	(segment
		(start 121.527512 106.175)
		(end 123.122501 107.769989)
		(width 0.15)
		(layer "F.Cu")
		(net 149)
	)
	(segment
		(start 124.451614 107.345973)
		(end 124.564751 107.45911)
		(width 0.15)
		(layer "F.Cu")
		(net 149)
	)
	(segment
		(start 123.822538 107.769989)
		(end 124.246552 107.345972)
		(width 0.15)
		(layer "F.Cu")
		(net 149)
	)
	(segment
		(start 120.36506 104.842749)
		(end 120.36506 105.696)
		(width 0.15)
		(layer "F.Cu")
		(net 149)
	)
	(segment
		(start 120.84406 106.175)
		(end 121.527512 106.175)
		(width 0.15)
		(layer "F.Cu")
		(net 149)
	)
	(segment
		(start 120.08406 104.713749)
		(end 120.23606 104.713749)
		(width 0.15)
		(layer "F.Cu")
		(net 149)
	)
	(segment
		(start 125.905 109.595)
		(end 126.19 109.88)
		(width 0.15)
		(layer "F.Cu")
		(net 149)
	)
	(segment
		(start 123.122501 107.769989)
		(end 123.1225 107.769987)
		(width 0.15)
		(layer "F.Cu")
		(net 149)
	)
	(segment
		(start 115.785 106.175)
		(end 115.61 106)
		(width 0.15)
		(layer "F.Cu")
		(net 149)
	)
	(segment
		(start 124.706418 109.353906)
		(end 124.819556 109.467043)
		(width 0.15)
		(layer "F.Cu")
		(net 149)
	)
	(segment
		(start 124.077356 109.777908)
		(end 124.501357 109.353906)
		(width 0.15)
		(layer "F.Cu")
		(net 149)
	)
	(arc
		(start 124.501357 109.353906)
		(mid 124.603887 109.311437)
		(end 124.706418 109.353906)
		(width 0.15)
		(layer "F.Cu")
		(net 149)
	)
	(arc
		(start 120.36506 105.696)
		(mid 120.505356 106.034704)
		(end 120.84406 106.175)
		(width 0.15)
		(layer "F.Cu")
		(net 149)
	)
	(arc
		(start 123.1225 107.769987)
		(mid 123.47252 107.914971)
		(end 123.822538 107.769989)
		(width 0.15)
		(layer "F.Cu")
		(net 149)
	)
	(arc
		(start 124.564751 107.45911)
		(mid 124.60722 107.561641)
		(end 124.56475 107.66417)
		(width 0.15)
		(layer "F.Cu")
		(net 149)
	)
	(arc
		(start 120.23606 104.713749)
		(mid 120.327277 104.751532)
		(end 120.36506 104.842749)
		(width 0.15)
		(layer "F.Cu")
		(net 149)
	)
	(arc
		(start 119.47606 106.175)
		(mid 119.814764 106.034704)
		(end 119.95506 105.696)
		(width 0.15)
		(layer "F.Cu")
		(net 149)
	)
	(arc
		(start 124.246552 107.345972)
		(mid 124.349083 107.303504)
		(end 124.451614 107.345973)
		(width 0.15)
		(layer "F.Cu")
		(net 149)
	)
	(arc
		(start 119.95506 104.842749)
		(mid 119.992843 104.751532)
		(end 120.08406 104.713749)
		(width 0.15)
		(layer "F.Cu")
		(net 149)
	)
	(arc
		(start 123.377321 109.777908)
		(mid 123.727339 109.922889)
		(end 124.077356 109.777908)
		(width 0.15)
		(layer "F.Cu")
		(net 149)
	)
	(arc
		(start 123.264184 108.964736)
		(mid 123.119202 109.314753)
		(end 123.264184 109.664771)
		(width 0.15)
		(layer "F.Cu")
		(net 149)
	)
	(segment
		(start 123.369989 107.522501)
		(end 123.369987 107.5225)
		(width 0.15)
		(layer "F.Cu")
		(net 150)
	)
	(segment
		(start 123.511671 109.417284)
		(end 123.624808 109.530421)
		(width 0.15)
		(layer "F.Cu")
		(net 150)
	)
	(segment
		(start 117.225 105.25)
		(end 117.225 104.875)
		(width 0.15)
		(layer "F.Cu")
		(net 150)
	)
	(segment
		(start 123.511671 109.212223)
		(end 124.161947 108.561947)
		(width 0.15)
		(layer "F.Cu")
		(net 150)
	)
	(segment
		(start 125.092488 109.245)
		(end 125.905 109.245)
		(width 0.15)
		(layer "F.Cu")
		(net 150)
	)
	(segment
		(start 125.905 109.245)
		(end 126.096546 109.053454)
		(width 0.15)
		(layer "F.Cu")
		(net 150)
	)
	(segment
		(start 125.067043 109.219556)
		(end 125.092488 109.245)
		(width 0.15)
		(layer "F.Cu")
		(net 150)
	)
	(segment
		(start 117.8 105.825)
		(end 117.225 105.25)
		(width 0.15)
		(layer "F.Cu")
		(net 150)
	)
	(segment
		(start 126.096546 109.053454)
		(end 126.19 108.96)
		(width 0.15)
		(layer "F.Cu")
		(net 150)
	)
	(segment
		(start 117.37 104.73)
		(end 118.15 104.73)
		(width 0.15)
		(layer "F.Cu")
		(net 150)
	)
	(segment
		(start 124.953906 109.106419)
		(end 125.067043 109.219556)
		(width 0.15)
		(layer "F.Cu")
		(net 150)
	)
	(segment
		(start 119.60506 105.696)
		(end 119.60506 104.842749)
		(width 0.15)
		(layer "F.Cu")
		(net 150)
	)
	(segment
		(start 124.699099 107.098485)
		(end 124.812236 107.211622)
		(width 0.15)
		(layer "F.Cu")
		(net 150)
	)
	(segment
		(start 124.161946 108.561946)
		(end 124.161947 108.561947)
		(width 0.15)
		(layer "F.Cu")
		(net 150)
	)
	(segment
		(start 117.225 104.875)
		(end 117.37 104.73)
		(width 0.15)
		(layer "F.Cu")
		(net 150)
	)
	(segment
		(start 124.161946 108.561946)
		(end 124.812237 107.911658)
		(width 0.15)
		(layer "F.Cu")
		(net 150)
	)
	(segment
		(start 123.829869 109.530421)
		(end 124.25387 109.106419)
		(width 0.15)
		(layer "F.Cu")
		(net 150)
	)
	(segment
		(start 126.19 108.96)
		(end 126.29 108.96)
		(width 0.15)
		(layer "F.Cu")
		(net 150)
	)
	(segment
		(start 123.575049 107.522501)
		(end 123.999065 107.098486)
		(width 0.15)
		(layer "F.Cu")
		(net 150)
	)
	(segment
		(start 120.71506 104.842749)
		(end 120.71506 105.696)
		(width 0.15)
		(layer "F.Cu")
		(net 150)
	)
	(segment
		(start 121.672488 105.825)
		(end 123.369989 107.522501)
		(width 0.15)
		(layer "F.Cu")
		(net 150)
	)
	(segment
		(start 120.08406 104.363749)
		(end 120.23606 104.363749)
		(width 0.15)
		(layer "F.Cu")
		(net 150)
	)
	(segment
		(start 119.47606 105.825)
		(end 117.8 105.825)
		(width 0.15)
		(layer "F.Cu")
		(net 150)
	)
	(segment
		(start 120.84406 105.825)
		(end 121.672488 105.825)
		(width 0.15)
		(layer "F.Cu")
		(net 150)
	)
	(arc
		(start 120.23606 104.363749)
		(mid 120.574764 104.504045)
		(end 120.71506 104.842749)
		(width 0.15)
		(layer "F.Cu")
		(net 150)
	)
	(arc
		(start 123.624808 109.530421)
		(mid 123.727339 109.57289)
		(end 123.829869 109.530421)
		(width 0.15)
		(layer "F.Cu")
		(net 150)
	)
	(arc
		(start 119.47606 105.825)
		(mid 119.567277 105.787217)
		(end 119.60506 105.696)
		(width 0.15)
		(layer "F.Cu")
		(net 150)
	)
	(arc
		(start 123.999065 107.098486)
		(mid 124.349081 106.953503)
		(end 124.699099 107.098485)
		(width 0.15)
		(layer "F.Cu")
		(net 150)
	)
	(arc
		(start 123.369987 107.5225)
		(mid 123.47252 107.564971)
		(end 123.575049 107.522501)
		(width 0.15)
		(layer "F.Cu")
		(net 150)
	)
	(arc
		(start 123.511671 109.212223)
		(mid 123.469202 109.314753)
		(end 123.511671 109.417284)
		(width 0.15)
		(layer "F.Cu")
		(net 150)
	)
	(arc
		(start 124.25387 109.106419)
		(mid 124.603888 108.961437)
		(end 124.953906 109.106419)
		(width 0.15)
		(layer "F.Cu")
		(net 150)
	)
	(arc
		(start 124.812236 107.211622)
		(mid 124.957218 107.561641)
		(end 124.812237 107.911658)
		(width 0.15)
		(layer "F.Cu")
		(net 150)
	)
	(arc
		(start 120.71506 105.696)
		(mid 120.752843 105.787217)
		(end 120.84406 105.825)
		(width 0.15)
		(layer "F.Cu")
		(net 150)
	)
	(arc
		(start 119.60506 104.842749)
		(mid 119.745356 104.504045)
		(end 120.08406 104.363749)
		(width 0.15)
		(layer "F.Cu")
		(net 150)
	)
	(segment
		(start 119.757596 102.575363)
		(end 119.757596 103.033)
		(width 0.15)
		(layer "F.Cu")
		(net 151)
	)
	(segment
		(start 114.3 103.3)
		(end 114.3 102.125)
		(width 0.15)
		(layer "F.Cu")
		(net 151)
	)
	(segment
		(start 123.572488 105.325)
		(end 125.498749 105.325)
		(width 0.15)
		(layer "F.Cu")
		(net 151)
	)
	(segment
		(start 119.949596 103.225)
		(end 120.045596 103.225)
		(width 0.15)
		(layer "F.Cu")
		(net 151)
	)
	(segment
		(start 114.3 102.125)
		(end 114.475 101.95)
		(width 0.15)
		(layer "F.Cu")
		(net 151)
	)
	(segment
		(start 119.469596 102.383363)
		(end 119.565596 102.383363)
		(width 0.15)
		(layer "F.Cu")
		(net 151)
	)
	(segment
		(start 120.909596 103.225)
		(end 121.472488 103.225)
		(width 0.15)
		(layer "F.Cu")
		(net 151)
	)
	(segment
		(start 114.46 103.46)
		(end 114.3 103.3)
		(width 0.15)
		(layer "F.Cu")
		(net 151)
	)
	(segment
		(start 119.277596 103.033)
		(end 119.277596 102.575363)
		(width 0.15)
		(layer "F.Cu")
		(net 151)
	)
	(segment
		(start 120.429596 102.383354)
		(end 120.525596 102.383354)
		(width 0.15)
		(layer "F.Cu")
		(net 151)
	)
	(segment
		(start 120.237596 103.033)
		(end 120.237596 102.575354)
		(width 0.15)
		(layer "F.Cu")
		(net 151)
	)
	(segment
		(start 125.498749 105.325)
		(end 125.783749 105.04)
		(width 0.15)
		(layer "F.Cu")
		(net 151)
	)
	(segment
		(start 121.472488 103.225)
		(end 123.572488 105.325)
		(width 0.15)
		(layer "F.Cu")
		(net 151)
	)
	(segment
		(start 120.717596 102.575354)
		(end 120.717596 103.033)
		(width 0.15)
		(layer "F.Cu")
		(net 151)
	)
	(segment
		(start 117.325 103.225)
		(end 119.085596 103.225)
		(width 0.15)
		(layer "F.Cu")
		(net 151)
	)
	(segment
		(start 114.475 101.95)
		(end 116.05 101.95)
		(width 0.15)
		(layer "F.Cu")
		(net 151)
	)
	(segment
		(start 125.783749 105.04)
		(end 126.29 105.04)
		(width 0.15)
		(layer "F.Cu")
		(net 151)
	)
	(segment
		(start 116.05 101.95)
		(end 117.325 103.225)
		(width 0.15)
		(layer "F.Cu")
		(net 151)
	)
	(segment
		(start 115.61 103.46)
		(end 114.46 103.46)
		(width 0.15)
		(layer "F.Cu")
		(net 151)
	)
	(arc
		(start 120.717596 103.033)
		(mid 120.773831 103.168765)
		(end 120.909596 103.225)
		(width 0.15)
		(layer "F.Cu")
		(net 151)
	)
	(arc
		(start 119.277596 102.575363)
		(mid 119.333831 102.439598)
		(end 119.469596 102.383363)
		(width 0.15)
		(layer "F.Cu")
		(net 151)
	)
	(arc
		(start 119.757596 103.033)
		(mid 119.813831 103.168765)
		(end 119.949596 103.225)
		(width 0.15)
		(layer "F.Cu")
		(net 151)
	)
	(arc
		(start 119.085596 103.225)
		(mid 119.221361 103.168765)
		(end 119.277596 103.033)
		(width 0.15)
		(layer "F.Cu")
		(net 151)
	)
	(arc
		(start 120.525596 102.383354)
		(mid 120.661361 102.439589)
		(end 120.717596 102.575354)
		(width 0.15)
		(layer "F.Cu")
		(net 151)
	)
	(arc
		(start 120.237596 102.575354)
		(mid 120.293831 102.439589)
		(end 120.429596 102.383354)
		(width 0.15)
		(layer "F.Cu")
		(net 151)
	)
	(arc
		(start 119.565596 102.383363)
		(mid 119.701361 102.439598)
		(end 119.757596 102.575363)
		(width 0.15)
		(layer "F.Cu")
		(net 151)
	)
	(arc
		(start 120.045596 103.225)
		(mid 120.181361 103.168765)
		(end 120.237596 103.033)
		(width 0.15)
		(layer "F.Cu")
		(net 151)
	)
	(segment
		(start 118.616751 99.730739)
		(end 118.728473 99.619015)
		(width 0.15)
		(layer "F.Cu")
		(net 152)
	)
	(segment
		(start 122.523001 99.770489)
		(end 122.523 99.770487)
		(width 0.15)
		(layer "F.Cu")
		(net 152)
	)
	(segment
		(start 123.693261 101.732708)
		(end 123.972568 101.4534)
		(width 0.15)
		(layer "F.Cu")
		(net 152)
	)
	(segment
		(start 117.4 100.947488)
		(end 117.611244 100.736244)
		(width 0.15)
		(layer "F.Cu")
		(net 152)
	)
	(segment
		(start 117.107361 98.915726)
		(end 117.922373 99.730738)
		(width 0.15)
		(layer "F.Cu")
		(net 152)
	)
	(segment
		(start 126.19 102.07)
		(end 126.29 102.07)
		(width 0.15)
		(layer "F.Cu")
		(net 152)
	)
	(segment
		(start 123.364458 100.364457)
		(end 123.884181 99.844733)
		(width 0.15)
		(layer "F.Cu")
		(net 152)
	)
	(segment
		(start 118.728473 99.619015)
		(end 118.772488 99.575)
		(width 0.15)
		(layer "F.Cu")
		(net 152)
	)
	(segment
		(start 117.4 101.44)
		(end 117.4 100.947488)
		(width 0.15)
		(layer "F.Cu")
		(net 152)
	)
	(segment
		(start 116.796233 99.027449)
		(end 116.907957 98.915726)
		(width 0.15)
		(layer "F.Cu")
		(net 152)
	)
	(segment
		(start 122.844733 101.6125)
		(end 122.964941 101.732708)
		(width 0.15)
		(layer "F.Cu")
		(net 152)
	)
	(segment
		(start 123.364458 100.364457)
		(end 123.364457 100.364457)
		(width 0.15)
		(layer "F.Cu")
		(net 152)
	)
	(segment
		(start 117.611245 100.041864)
		(end 116.796234 99.226853)
		(width 0.15)
		(layer "F.Cu")
		(net 152)
	)
	(segment
		(start 122.844733 100.88418)
		(end 123.364457 100.364457)
		(width 0.15)
		(layer "F.Cu")
		(net 152)
	)
	(segment
		(start 124.537512 101.785)
		(end 125.880791 101.785)
		(width 0.15)
		(layer "F.Cu")
		(net 152)
	)
	(segment
		(start 123.251322 99.770489)
		(end 123.530628 99.49118)
		(width 0.15)
		(layer "F.Cu")
		(net 152)
	)
	(segment
		(start 119.609351 99.575)
		(end 122.327512 99.575)
		(width 0.15)
		(layer "F.Cu")
		(net 152)
	)
	(segment
		(start 122.327512 99.575)
		(end 122.523001 99.770489)
		(width 0.15)
		(layer "F.Cu")
		(net 152)
	)
	(segment
		(start 125.880791 101.785)
		(end 125.905 101.785)
		(width 0.15)
		(layer "F.Cu")
		(net 152)
	)
	(segment
		(start 125.905 101.785)
		(end 126.19 102.07)
		(width 0.15)
		(layer "F.Cu")
		(net 152)
	)
	(segment
		(start 118.15 102.19)
		(end 117.4 101.44)
		(width 0.15)
		(layer "F.Cu")
		(net 152)
	)
	(segment
		(start 123.763974 99.491181)
		(end 123.884182 99.611389)
		(width 0.15)
		(layer "F.Cu")
		(net 152)
	)
	(segment
		(start 124.205913 101.4534)
		(end 124.537512 101.785)
		(width 0.15)
		(layer "F.Cu")
		(net 152)
	)
	(segment
		(start 118.772488 99.575)
		(end 118.923585 99.575)
		(width 0.15)
		(layer "F.Cu")
		(net 152)
	)
	(segment
		(start 119.209351 99.860766)
		(end 119.323585 99.860766)
		(width 0.15)
		(layer "F.Cu")
		(net 152)
	)
	(arc
		(start 122.844733 100.88418)
		(mid 122.693893 101.24834)
		(end 122.844733 101.6125)
		(width 0.15)
		(layer "F.Cu")
		(net 152)
	)
	(arc
		(start 116.907957 98.915726)
		(mid 117.007659 98.874428)
		(end 117.107361 98.915726)
		(width 0.15)
		(layer "F.Cu")
		(net 152)
	)
	(arc
		(start 122.523 99.770487)
		(mid 122.887162 99.921329)
		(end 123.251322 99.770489)
		(width 0.15)
		(layer "F.Cu")
		(net 152)
	)
	(arc
		(start 116.796234 99.226853)
		(mid 116.754935 99.127151)
		(end 116.796233 99.027449)
		(width 0.15)
		(layer "F.Cu")
		(net 152)
	)
	(arc
		(start 123.530628 99.49118)
		(mid 123.647301 99.442854)
		(end 123.763974 99.491181)
		(width 0.15)
		(layer "F.Cu")
		(net 152)
	)
	(arc
		(start 118.923585 99.575)
		(mid 119.024619 99.616849)
		(end 119.066468 99.717883)
		(width 0.15)
		(layer "F.Cu")
		(net 152)
	)
	(arc
		(start 117.611244 100.736244)
		(mid 117.755055 100.389054)
		(end 117.611245 100.041864)
		(width 0.15)
		(layer "F.Cu")
		(net 152)
	)
	(arc
		(start 119.323585 99.860766)
		(mid 119.424619 99.818917)
		(end 119.466468 99.717883)
		(width 0.15)
		(layer "F.Cu")
		(net 152)
	)
	(arc
		(start 123.884182 99.611389)
		(mid 123.932509 99.728062)
		(end 123.884181 99.844733)
		(width 0.15)
		(layer "F.Cu")
		(net 152)
	)
	(arc
		(start 122.964941 101.732708)
		(mid 123.329101 101.883548)
		(end 123.693261 101.732708)
		(width 0.15)
		(layer "F.Cu")
		(net 152)
	)
	(arc
		(start 119.066468 99.717883)
		(mid 119.108317 99.818917)
		(end 119.209351 99.860766)
		(width 0.15)
		(layer "F.Cu")
		(net 152)
	)
	(arc
		(start 117.922373 99.730738)
		(mid 118.269562 99.874549)
		(end 118.616751 99.730739)
		(width 0.15)
		(layer "F.Cu")
		(net 152)
	)
	(arc
		(start 123.972568 101.4534)
		(mid 124.08924 101.405073)
		(end 124.205913 101.4534)
		(width 0.15)
		(layer "F.Cu")
		(net 152)
	)
	(arc
		(start 119.466468 99.717883)
		(mid 119.508317 99.616849)
		(end 119.609351 99.575)
		(width 0.15)
		(layer "F.Cu")
		(net 152)
	)
	(segment
		(start 118.369265 99.483253)
		(end 118.480986 99.371528)
		(width 0.15)
		(layer "F.Cu")
		(net 153)
	)
	(segment
		(start 123.092221 101.131668)
		(end 123.85236 100.371528)
		(width 0.15)
		(layer "F.Cu")
		(net 153)
	)
	(segment
		(start 125.880791 101.435)
		(end 125.905 101.435)
		(width 0.15)
		(layer "F.Cu")
		(net 153)
	)
	(segment
		(start 124.453401 101.205913)
		(end 124.573609 101.326122)
		(width 0.15)
		(layer "F.Cu")
		(net 153)
	)
	(segment
		(start 115.755 100.775)
		(end 117.077512 100.775)
		(width 0.15)
		(layer "F.Cu")
		(net 153)
	)
	(segment
		(start 122.770489 99.523001)
		(end 122.770487 99.523)
		(width 0.15)
		(layer "F.Cu")
		(net 153)
	)
	(segment
		(start 117.363757 100.289353)
		(end 116.548746 99.474342)
		(width 0.15)
		(layer "F.Cu")
		(net 153)
	)
	(segment
		(start 118.480986 99.371528)
		(end 118.627512 99.225)
		(width 0.15)
		(layer "F.Cu")
		(net 153)
	)
	(segment
		(start 116.548747 98.779962)
		(end 116.660469 98.668241)
		(width 0.15)
		(layer "F.Cu")
		(net 153)
	)
	(segment
		(start 115.61 100.92)
		(end 115.755 100.775)
		(width 0.15)
		(layer "F.Cu")
		(net 153)
	)
	(segment
		(start 117.354849 98.66824)
		(end 118.169861 99.483252)
		(width 0.15)
		(layer "F.Cu")
		(net 153)
	)
	(segment
		(start 124.131669 100.092222)
		(end 123.85236 100.371528)
		(width 0.15)
		(layer "F.Cu")
		(net 153)
	)
	(segment
		(start 123.003833 99.523001)
		(end 123.283141 99.243694)
		(width 0.15)
		(layer "F.Cu")
		(net 153)
	)
	(segment
		(start 124.682488 101.435)
		(end 125.880791 101.435)
		(width 0.15)
		(layer "F.Cu")
		(net 153)
	)
	(segment
		(start 117.363756 100.488756)
		(end 117.363757 100.488757)
		(width 0.15)
		(layer "F.Cu")
		(net 153)
	)
	(segment
		(start 117.077512 100.775)
		(end 117.363756 100.488756)
		(width 0.15)
		(layer "F.Cu")
		(net 153)
	)
	(segment
		(start 123.092221 101.365013)
		(end 123.212429 101.485221)
		(width 0.15)
		(layer "F.Cu")
		(net 153)
	)
	(segment
		(start 126.19 101.15)
		(end 126.29 101.15)
		(width 0.15)
		(layer "F.Cu")
		(net 153)
	)
	(segment
		(start 123.445774 101.485221)
		(end 123.725081 101.205913)
		(width 0.15)
		(layer "F.Cu")
		(net 153)
	)
	(segment
		(start 124.573609 101.326122)
		(end 124.682488 101.435)
		(width 0.15)
		(layer "F.Cu")
		(net 153)
	)
	(segment
		(start 118.627512 99.225)
		(end 122.472488 99.225)
		(width 0.15)
		(layer "F.Cu")
		(net 153)
	)
	(segment
		(start 122.472488 99.225)
		(end 122.770489 99.523001)
		(width 0.15)
		(layer "F.Cu")
		(net 153)
	)
	(segment
		(start 124.011461 99.243694)
		(end 124.131669 99.363902)
		(width 0.15)
		(layer "F.Cu")
		(net 153)
	)
	(segment
		(start 125.905 101.435)
		(end 126.19 101.15)
		(width 0.15)
		(layer "F.Cu")
		(net 153)
	)
	(arc
		(start 123.725081 101.205913)
		(mid 124.089241 101.055073)
		(end 124.453401 101.205913)
		(width 0.15)
		(layer "F.Cu")
		(net 153)
	)
	(arc
		(start 116.548746 99.474342)
		(mid 116.404936 99.127152)
		(end 116.548747 98.779962)
		(width 0.15)
		(layer "F.Cu")
		(net 153)
	)
	(arc
		(start 123.283141 99.243694)
		(mid 123.647301 99.092854)
		(end 124.011461 99.243694)
		(width 0.15)
		(layer "F.Cu")
		(net 153)
	)
	(arc
		(start 122.770487 99.523)
		(mid 122.887162 99.571329)
		(end 123.003833 99.523001)
		(width 0.15)
		(layer "F.Cu")
		(net 153)
	)
	(arc
		(start 123.092221 101.131668)
		(mid 123.043894 101.24834)
		(end 123.092221 101.365013)
		(width 0.15)
		(layer "F.Cu")
		(net 153)
	)
	(arc
		(start 123.212429 101.485221)
		(mid 123.329102 101.533548)
		(end 123.445774 101.485221)
		(width 0.15)
		(layer "F.Cu")
		(net 153)
	)
	(arc
		(start 116.660469 98.668241)
		(mid 117.00766 98.524429)
		(end 117.354849 98.66824)
		(width 0.15)
		(layer "F.Cu")
		(net 153)
	)
	(arc
		(start 118.169861 99.483252)
		(mid 118.269562 99.524552)
		(end 118.369265 99.483253)
		(width 0.15)
		(layer "F.Cu")
		(net 153)
	)
	(arc
		(start 124.131669 99.363902)
		(mid 124.282509 99.728062)
		(end 124.131669 100.092222)
		(width 0.15)
		(layer "F.Cu")
		(net 153)
	)
	(arc
		(start 117.363757 100.488757)
		(mid 117.405055 100.389055)
		(end 117.363757 100.289353)
		(width 0.15)
		(layer "F.Cu")
		(net 153)
	)
	(segment
		(start 122.92 96.86)
		(end 122.92 95.86)
		(width 0.125)
		(layer "B.Cu")
		(net 154)
	)
	(segment
		(start 122.92 96.86)
		(end 122.92 97.86)
		(width 0.125)
		(layer "B.Cu")
		(net 154)
	)
	(segment
		(start 122.92 97.86)
		(end 121.165 97.86)
		(width 0.125)
		(layer "B.Cu")
		(net 154)
	)
	(segment
		(start 120.86 100.7)
		(end 121.7 99.86)
		(width 0.125)
		(layer "B.Cu")
		(net 155)
	)
	(segment
		(start 122.92 99.86)
		(end 122.92 98.86)
		(width 0.125)
		(layer "B.Cu")
		(net 155)
	)
	(segment
		(start 121.7 99.86)
		(end 122.92 99.86)
		(width 0.125)
		(layer "B.Cu")
		(net 155)
	)
	(segment
		(start 122.92 100.86)
		(end 122.92 99.86)
		(width 0.125)
		(layer "B.Cu")
		(net 155)
	)
	(segment
		(start 120.86 110.03)
		(end 121.87 110.03)
		(width 0.125)
		(layer "B.Cu")
		(net 156)
	)
	(segment
		(start 122.92 110.31)
		(end 122.92 110.81)
		(width 0.125)
		(layer "B.Cu")
		(net 156)
	)
	(segment
		(start 122.15 110.31)
		(end 122.92 110.31)
		(width 0.125)
		(layer "B.Cu")
		(net 156)
	)
	(segment
		(start 122.92 109.81)
		(end 122.92 110.31)
		(width 0.125)
		(layer "B.Cu")
		(net 156)
	)
	(segment
		(start 121.87 110.03)
		(end 122.15 110.31)
		(width 0.125)
		(layer "B.Cu")
		(net 156)
	)
	(segment
		(start 122.92 108.81)
		(end 122.92 109.81)
		(width 0.125)
		(layer "B.Cu")
		(net 156)
	)
	(segment
		(start 119.75 109.46)
		(end 119.75 111.455)
		(width 0.125)
		(layer "B.Cu")
		(net 157)
	)
	(segment
		(start 122.92 112.31)
		(end 122.92 112.81)
		(width 0.125)
		(layer "B.Cu")
		(net 157)
	)
	(segment
		(start 122.92 111.81)
		(end 122.92 112.31)
		(width 0.125)
		(layer "B.Cu")
		(net 157)
	)
	(segment
		(start 121.4 107.81)
		(end 119.75 109.46)
		(width 0.125)
		(layer "B.Cu")
		(net 157)
	)
	(segment
		(start 119.75 111.455)
		(end 120.86 112.565)
		(width 0.125)
		(layer "B.Cu")
		(net 157)
	)
	(segment
		(start 120.86 112.565)
		(end 121.825 112.565)
		(width 0.125)
		(layer "B.Cu")
		(net 157)
	)
	(segment
		(start 122.92 107.81)
		(end 121.4 107.81)
		(width 0.125)
		(layer "B.Cu")
		(net 157)
	)
	(segment
		(start 122.08 112.31)
		(end 122.92 112.31)
		(width 0.125)
		(layer "B.Cu")
		(net 157)
	)
	(segment
		(start 121.825 112.565)
		(end 122.08 112.31)
		(width 0.125)
		(layer "B.Cu")
		(net 157)
	)
	(segment
		(start 180.085 158.2175)
		(end 179.9525 158.35)
		(width 0.185)
		(layer "F.Cu")
		(net 158)
	)
	(segment
		(start 180.025 156.685)
		(end 180.025 157.41)
		(width 0.185)
		(layer "F.Cu")
		(net 158)
	)
	(segment
		(start 180.025 157.41)
		(end 180.085 157.47)
		(width 0.185)
		(layer "F.Cu")
		(net 158)
	)
	(segment
		(start 180.085 157.47)
		(end 180.085 158.2175)
		(width 0.185)
		(layer "F.Cu")
		(net 158)
	)
	(via
		(at 96.131958 106.028042)
		(size 0.45)
		(drill 0.1)
		(layers "F.Cu" "B.Cu")
		(net 158)
	)
	(via
		(at 179.9525 158.35)
		(size 0.45)
		(drill 0.1)
		(layers "F.Cu" "B.Cu")
		(teardrops
			(best_length_ratio 0.4)
			(max_length 1)
			(best_width_ratio 0.9)
			(max_width 2)
			(curved_edges yes)
			(filter_ratio 0.9)
			(enabled yes)
			(allow_two_segments yes)
			(prefer_zone_connections yes)
		)
		(net 158)
	)
	(segment
		(start 96.596299 106.305)
		(end 96.319341 106.028042)
		(width 0.185)
		(layer "B.Cu")
		(net 158)
	)
	(segment
		(start 106.542972 107.81)
		(end 104.262246 107.81)
		(width 0.185)
		(layer "B.Cu")
		(net 158)
	)
	(segment
		(start 96.319341 106.028042)
		(end 96.131958 106.028042)
		(width 0.185)
		(layer "B.Cu")
		(net 158)
	)
	(segment
		(start 108.25 109.365)
		(end 107.730395 108.845395)
		(width 0.185)
		(layer "B.Cu")
		(net 158)
	)
	(segment
		(start 101.535 106.305)
		(end 101.475 106.365)
		(width 0.185)
		(layer "B.Cu")
		(net 158)
	)
	(segment
		(start 100.343 106.305)
		(end 96.596299 106.305)
		(width 0.185)
		(layer "B.Cu")
		(net 158)
	)
	(segment
		(start 107.6425 108.633236)
		(end 107.6425 108.619578)
		(width 0.185)
		(layer "B.Cu")
		(net 158)
	)
	(segment
		(start 100.61 106.308)
		(end 100.553 106.365)
		(width 0.185)
		(layer "B.Cu")
		(net 158)
	)
	(segment
		(start 101.325 106.365)
		(end 101.268 106.308)
		(width 0.185)
		(layer "B.Cu")
		(net 158)
	)
	(segment
		(start 107.554662 108.407476)
		(end 107.250079 108.102893)
		(width 0.185)
		(layer "B.Cu")
		(net 158)
	)
	(segment
		(start 101.662034 106.305)
		(end 101.535 106.305)
		(width 0.185)
		(layer "B.Cu")
		(net 158)
	)
	(segment
		(start 102.604735 107.123437)
		(end 101.874166 106.392868)
		(width 0.185)
		(layer "B.Cu")
		(net 158)
	)
	(segment
		(start 100.403 106.365)
		(end 100.343 106.305)
		(width 0.185)
		(layer "B.Cu")
		(net 158)
	)
	(segment
		(start 101.268 106.308)
		(end 100.61 106.308)
		(width 0.185)
		(layer "B.Cu")
		(net 158)
	)
	(arc
		(start 106.542972 107.81)
		(mid 106.925655 107.88612)
		(end 107.250079 108.102893)
		(width 0.185)
		(layer "B.Cu")
		(net 158)
	)
	(arc
		(start 104.262246 107.81)
		(mid 103.365208 107.631568)
		(end 102.604735 107.123437)
		(width 0.185)
		(layer "B.Cu")
		(net 158)
	)
	(arc
		(start 107.730395 108.845395)
		(mid 107.66535 108.748055)
		(end 107.6425 108.633236)
		(width 0.185)
		(layer "B.Cu")
		(net 158)
	)
	(arc
		(start 101.662034 106.305)
		(mid 101.776839 106.327836)
		(end 101.874166 106.392868)
		(width 0.185)
		(layer "B.Cu")
		(net 158)
	)
	(arc
		(start 107.6425 108.619578)
		(mid 107.619668 108.504759)
		(end 107.554662 108.407476)
		(width 0.185)
		(layer "B.Cu")
		(net 158)
	)
	(segment
		(start 172.5185 133.90018)
		(end 160.74982 122.1315)
		(width 0.159)
		(layer "In5.Cu")
		(net 158)
	)
	(segment
		(start 96.6435 106.34018)
		(end 96.331362 106.028042)
		(width 0.159)
		(layer "In5.Cu")
		(net 158)
	)
	(segment
		(start 180.0935 158.209)
		(end 180.0935 153.55018)
		(width 0.159)
		(layer "In5.Cu")
		(net 158)
	)
	(segment
		(start 172.5185 144.17518)
		(end 172.5185 133.90018)
		(width 0.159)
		(layer "In5.Cu")
		(net 158)
	)
	(segment
		(start 160.74982 122.1315)
		(end 97.97482 122.1315)
		(width 0.159)
		(layer "In5.Cu")
		(net 158)
	)
	(segment
		(start 180.0935 153.55018)
		(end 177.0185 150.47518)
		(width 0.159)
		(layer "In5.Cu")
		(net 158)
	)
	(segment
		(start 177.0185 150.47518)
		(end 177.0185 148.67518)
		(width 0.159)
		(layer "In5.Cu")
		(net 158)
	)
	(segment
		(start 179.9525 158.35)
		(end 180.0935 158.209)
		(width 0.159)
		(layer "In5.Cu")
		(net 158)
	)
	(segment
		(start 96.6435 120.80018)
		(end 96.6435 106.34018)
		(width 0.159)
		(layer "In5.Cu")
		(net 158)
	)
	(segment
		(start 177.0185 148.67518)
		(end 172.5185 144.17518)
		(width 0.159)
		(layer "In5.Cu")
		(net 158)
	)
	(segment
		(start 97.97482 122.1315)
		(end 96.6435 120.80018)
		(width 0.159)
		(layer "In5.Cu")
		(net 158)
	)
	(segment
		(start 96.331362 106.028042)
		(end 96.131958 106.028042)
		(width 0.159)
		(layer "In5.Cu")
		(net 158)
	)
	(segment
		(start 180.525 156.685)
		(end 180.525 157.41)
		(width 0.185)
		(layer "F.Cu")
		(net 159)
	)
	(segment
		(start 180.465 158.2175)
		(end 180.5975 158.35)
		(width 0.185)
		(layer "F.Cu")
		(net 159)
	)
	(segment
		(start 180.525 157.41)
		(end 180.465 157.47)
		(width 0.185)
		(layer "F.Cu")
		(net 159)
	)
	(segment
		(start 180.465 157.47)
		(end 180.465 158.2175)
		(width 0.185)
		(layer "F.Cu")
		(net 159)
	)
	(via
		(at 96.588042 105.571958)
		(size 0.45)
		(drill 0.1)
		(layers "F.Cu" "B.Cu")
		(net 159)
	)
	(via
		(at 180.5975 158.35)
		(size 0.45)
		(drill 0.1)
		(layers "F.Cu" "B.Cu")
		(teardrops
			(best_length_ratio 0.4)
			(max_length 1)
			(best_width_ratio 0.9)
			(max_width 2)
			(curved_edges yes)
			(filter_ratio 0.9)
			(enabled yes)
			(allow_two_segments yes)
			(prefer_zone_connections yes)
		)
		(net 159)
	)
	(segment
		(start 100.553001 105.865)
		(end 100.61 105.922)
		(width 0.185)
		(layer "B.Cu")
		(net 159)
	)
	(segment
		(start 105.529476 107.253475)
		(end 105.529476 107.253476)
		(width 0.185)
		(layer "B.Cu")
		(net 159)
	)
	(segment
		(start 96.753701 105.925)
		(end 96.588042 105.759341)
		(width 0.185)
		(layer "B.Cu")
		(net 159)
	)
	(segment
		(start 105.306 107.43)
		(end 104.277129 107.43)
		(width 0.185)
		(layer "B.Cu")
		(net 159)
	)
	(segment
		(start 105.929476 107.253476)
		(end 105.929476 107.253475)
		(width 0.185)
		(layer "B.Cu")
		(net 159)
	)
	(segment
		(start 105.352952 107.43)
		(end 105.306 107.43)
		(width 0.185)
		(layer "B.Cu")
		(net 159)
	)
	(segment
		(start 96.588042 105.759341)
		(end 96.588042 105.571958)
		(width 0.185)
		(layer "B.Cu")
		(net 159)
	)
	(segment
		(start 106.557664 107.43)
		(end 106.106 107.43)
		(width 0.185)
		(layer "B.Cu")
		(net 159)
	)
	(segment
		(start 100.61 105.922)
		(end 101.268 105.922)
		(width 0.185)
		(layer "B.Cu")
		(net 159)
	)
	(segment
		(start 108.25 107.365)
		(end 107.7912 107.8238)
		(width 0.185)
		(layer "B.Cu")
		(net 159)
	)
	(segment
		(start 101.535 105.925)
		(end 101.475 105.865)
		(width 0.185)
		(layer "B.Cu")
		(net 159)
	)
	(segment
		(start 105.752952 107.076951)
		(end 105.706 107.076951)
		(width 0.185)
		(layer "B.Cu")
		(net 159)
	)
	(segment
		(start 100.403 105.865)
		(end 100.343 105.925)
		(width 0.185)
		(layer "B.Cu")
		(net 159)
	)
	(segment
		(start 101.268 105.922)
		(end 101.325 105.865)
		(width 0.185)
		(layer "B.Cu")
		(net 159)
	)
	(segment
		(start 100.343 105.925)
		(end 96.753701 105.925)
		(width 0.185)
		(layer "B.Cu")
		(net 159)
	)
	(segment
		(start 101.6696 105.925)
		(end 101.535 105.925)
		(width 0.185)
		(layer "B.Cu")
		(net 159)
	)
	(segment
		(start 102.862915 106.844213)
		(end 102.137522 106.11882)
		(width 0.185)
		(layer "B.Cu")
		(net 159)
	)
	(arc
		(start 106.106 107.43)
		(mid 105.981179 107.378297)
		(end 105.929476 107.253476)
		(width 0.185)
		(layer "B.Cu")
		(net 159)
	)
	(arc
		(start 105.929476 107.253475)
		(mid 105.877773 107.128654)
		(end 105.752952 107.076951)
		(width 0.185)
		(layer "B.Cu")
		(net 159)
	)
	(arc
		(start 102.137522 106.11882)
		(mid 101.922838 105.975372)
		(end 101.6696 105.925)
		(width 0.185)
		(layer "B.Cu")
		(net 159)
	)
	(arc
		(start 105.529476 107.253476)
		(mid 105.477773 107.378297)
		(end 105.352952 107.43)
		(width 0.185)
		(layer "B.Cu")
		(net 159)
	)
	(arc
		(start 107.7912 107.8238)
		(mid 107.649778 107.882378)
		(end 107.508357 107.823799)
		(width 0.185)
		(layer "B.Cu")
		(net 159)
	)
	(arc
		(start 107.508357 107.823799)
		(mid 107.072168 107.532341)
		(end 106.557664 107.43)
		(width 0.185)
		(layer "B.Cu")
		(net 159)
	)
	(arc
		(start 105.706 107.076951)
		(mid 105.581179 107.128654)
		(end 105.529476 107.253475)
		(width 0.185)
		(layer "B.Cu")
		(net 159)
	)
	(arc
		(start 104.277129 107.43)
		(mid 103.511762 107.277759)
		(end 102.862915 106.844213)
		(width 0.185)
		(layer "B.Cu")
		(net 159)
	)
	(segment
		(start 96.588042 105.771362)
		(end 96.588042 105.571958)
		(width 0.159)
		(layer "In5.Cu")
		(net 159)
	)
	(segment
		(start 172.8815 133.74982)
		(end 160.90018 121.7685)
		(width 0.159)
		(layer "In5.Cu")
		(net 159)
	)
	(segment
		(start 180.4565 158.209)
		(end 180.4565 153.39982)
		(width 0.159)
		(layer "In5.Cu")
		(net 159)
	)
	(segment
		(start 160.90018 121.7685)
		(end 98.12518 121.7685)
		(width 0.159)
		(layer "In5.Cu")
		(net 159)
	)
	(segment
		(start 98.12518 121.7685)
		(end 97.0065 120.64982)
		(width 0.159)
		(layer "In5.Cu")
		(net 159)
	)
	(segment
		(start 180.4565 153.39982)
		(end 177.3815 150.32482)
		(width 0.159)
		(layer "In5.Cu")
		(net 159)
	)
	(segment
		(start 97.0065 120.64982)
		(end 97.0065 106.18982)
		(width 0.159)
		(layer "In5.Cu")
		(net 159)
	)
	(segment
		(start 172.8815 144.02482)
		(end 172.8815 133.74982)
		(width 0.159)
		(layer "In5.Cu")
		(net 159)
	)
	(segment
		(start 177.3815 148.52482)
		(end 172.8815 144.02482)
		(width 0.159)
		(layer "In5.Cu")
		(net 159)
	)
	(segment
		(start 180.5975 158.35)
		(end 180.4565 158.209)
		(width 0.159)
		(layer "In5.Cu")
		(net 159)
	)
	(segment
		(start 97.0065 106.18982)
		(end 96.588042 105.771362)
		(width 0.159)
		(layer "In5.Cu")
		(net 159)
	)
	(segment
		(start 177.3815 150.32482)
		(end 177.3815 148.52482)
		(width 0.159)
		(layer "In5.Cu")
		(net 159)
	)
	(segment
		(start 181.585 158.1925)
		(end 181.4525 158.325)
		(width 0.185)
		(layer "F.Cu")
		(net 160)
	)
	(segment
		(start 181.585 157.47)
		(end 181.585 158.1925)
		(width 0.185)
		(layer "F.Cu")
		(net 160)
	)
	(segment
		(start 181.525 157.41)
		(end 181.585 157.47)
		(width 0.185)
		(layer "F.Cu")
		(net 160)
	)
	(segment
		(start 181.525 156.685)
		(end 181.525 157.41)
		(width 0.185)
		(layer "F.Cu")
		(net 160)
	)
	(via
		(at 127.5025 107.75)
		(size 0.45)
		(drill 0.1)
		(layers "F.Cu" "B.Cu")
		(teardrops
			(best_length_ratio 0.4)
			(max_length 1)
			(best_width_ratio 0.9)
			(max_width 2)
			(curved_edges yes)
			(filter_ratio 0.9)
			(enabled yes)
			(allow_two_segments yes)
			(prefer_zone_connections yes)
		)
		(net 160)
	)
	(via
		(at 181.4525 158.325)
		(size 0.45)
		(drill 0.1)
		(layers "F.Cu" "B.Cu")
		(teardrops
			(best_length_ratio 0.4)
			(max_length 1)
			(best_width_ratio 0.9)
			(max_width 2)
			(curved_edges yes)
			(filter_ratio 0.9)
			(enabled yes)
			(allow_two_segments yes)
			(prefer_zone_connections yes)
		)
		(net 160)
	)
	(segment
		(start 127.635 106.578702)
		(end 127.635 107.6175)
		(width 0.185)
		(layer "B.Cu")
		(net 160)
	)
	(segment
		(start 122.803 105.24)
		(end 122.775809 105.24)
		(width 0.185)
		(layer "B.Cu")
		(net 160)
	)
	(segment
		(start 122.422255 105.386447)
		(end 119.489635 108.319067)
		(width 0.185)
		(layer "B.Cu")
		(net 160)
	)
	(segment
		(start 112.742084 108.555)
		(end 112.342843 108.555)
		(width 0.185)
		(layer "B.Cu")
		(net 160)
	)
	(segment
		(start 122.863 105.3)
		(end 122.803 105.24)
		(width 0.185)
		(layer "B.Cu")
		(net 160)
	)
	(segment
		(start 126.296298 105.24)
		(end 127.635 106.578702)
		(width 0.185)
		(layer "B.Cu")
		(net 160)
	)
	(segment
		(start 118.521698 108.72)
		(end 118.062916 108.72)
		(width 0.185)
		(layer "B.Cu")
		(net 160)
	)
	(segment
		(start 123.995 105.24)
		(end 126.296298 105.24)
		(width 0.185)
		(layer "B.Cu")
		(net 160)
	)
	(segment
		(start 123.935 105.3)
		(end 123.995 105.24)
		(width 0.185)
		(layer "B.Cu")
		(net 160)
	)
	(segment
		(start 112.201421 108.613579)
		(end 111.45 109.365)
		(width 0.185)
		(layer "B.Cu")
		(net 160)
	)
	(segment
		(start 127.635 107.6175)
		(end 127.5025 107.75)
		(width 0.185)
		(layer "B.Cu")
		(net 160)
	)
	(segment
		(start 114.369538 109.76824)
		(end 113.449191 108.847893)
		(width 0.185)
		(layer "B.Cu")
		(net 160)
	)
	(segment
		(start 117.355809 109.012893)
		(end 116.598293 109.770409)
		(width 0.185)
		(layer "B.Cu")
		(net 160)
	)
	(segment
		(start 123.785 105.3)
		(end 123.013 105.3)
		(width 0.185)
		(layer "B.Cu")
		(net 160)
	)
	(segment
		(start 115.633595 110.17)
		(end 115.339473 110.17)
		(width 0.185)
		(layer "B.Cu")
		(net 160)
	)
	(arc
		(start 122.775809 105.24)
		(mid 122.584467 105.27806)
		(end 122.422255 105.386447)
		(width 0.185)
		(layer "B.Cu")
		(net 160)
	)
	(arc
		(start 118.062916 108.72)
		(mid 117.680233 108.79612)
		(end 117.355809 109.012893)
		(width 0.185)
		(layer "B.Cu")
		(net 160)
	)
	(arc
		(start 116.598293 109.770409)
		(mid 116.155686 110.06615)
		(end 115.633595 110.17)
		(width 0.185)
		(layer "B.Cu")
		(net 160)
	)
	(arc
		(start 114.369538 109.76824)
		(mid 114.814548 110.065586)
		(end 115.339473 110.17)
		(width 0.185)
		(layer "B.Cu")
		(net 160)
	)
	(arc
		(start 112.342843 108.555)
		(mid 112.266306 108.570224)
		(end 112.201421 108.613579)
		(width 0.185)
		(layer "B.Cu")
		(net 160)
	)
	(arc
		(start 112.742084 108.555)
		(mid 113.124767 108.63112)
		(end 113.449191 108.847893)
		(width 0.185)
		(layer "B.Cu")
		(net 160)
	)
	(arc
		(start 119.489635 108.319067)
		(mid 119.045542 108.615801)
		(end 118.521698 108.72)
		(width 0.185)
		(layer "B.Cu")
		(net 160)
	)
	(segment
		(start 181.5935 158.466)
		(end 181.5935 159.07518)
		(width 0.159)
		(layer "In5.Cu")
		(net 160)
	)
	(segment
		(start 183.6565 158.90018)
		(end 183.6565 146.79982)
		(width 0.159)
		(layer "In5.Cu")
		(net 160)
	)
	(segment
		(start 129.04518 106.7385)
		(end 128.116746 106.7385)
		(width 0.159)
		(layer "In5.Cu")
		(net 160)
	)
	(segment
		(start 127.6435 107.609)
		(end 127.5025 107.75)
		(width 0.159)
		(layer "In5.Cu")
		(net 160)
	)
	(segment
		(start 164.55018 116.3685)
		(end 138.67518 116.3685)
		(width 0.159)
		(layer "In5.Cu")
		(net 160)
	)
	(segment
		(start 128.116746 106.7385)
		(end 127.6435 107.211746)
		(width 0.159)
		(layer "In5.Cu")
		(net 160)
	)
	(segment
		(start 138.67518 116.3685)
		(end 129.04518 106.7385)
		(width 0.159)
		(layer "In5.Cu")
		(net 160)
	)
	(segment
		(start 181.4525 158.325)
		(end 181.5935 158.466)
		(width 0.159)
		(layer "In5.Cu")
		(net 160)
	)
	(segment
		(start 182.07482 159.5565)
		(end 183.00018 159.5565)
		(width 0.159)
		(layer "In5.Cu")
		(net 160)
	)
	(segment
		(start 127.6435 107.211746)
		(end 127.6435 107.609)
		(width 0.159)
		(layer "In5.Cu")
		(net 160)
	)
	(segment
		(start 178.3315 141.47482)
		(end 178.3315 130.14982)
		(width 0.159)
		(layer "In5.Cu")
		(net 160)
	)
	(segment
		(start 183.6565 146.79982)
		(end 178.3315 141.47482)
		(width 0.159)
		(layer "In5.Cu")
		(net 160)
	)
	(segment
		(start 183.00018 159.5565)
		(end 183.6565 158.90018)
		(width 0.159)
		(layer "In5.Cu")
		(net 160)
	)
	(segment
		(start 181.5935 159.07518)
		(end 182.07482 159.5565)
		(width 0.159)
		(layer "In5.Cu")
		(net 160)
	)
	(segment
		(start 178.3315 130.14982)
		(end 164.55018 116.3685)
		(width 0.159)
		(layer "In5.Cu")
		(net 160)
	)
	(segment
		(start 181.965 158.1925)
		(end 182.0975 158.325)
		(width 0.185)
		(layer "F.Cu")
		(net 161)
	)
	(segment
		(start 181.965 157.47)
		(end 181.965 158.1925)
		(width 0.185)
		(layer "F.Cu")
		(net 161)
	)
	(segment
		(start 182.025 157.41)
		(end 181.965 157.47)
		(width 0.185)
		(layer "F.Cu")
		(net 161)
	)
	(segment
		(start 182.025 156.685)
		(end 182.025 157.41)
		(width 0.185)
		(layer "F.Cu")
		(net 161)
	)
	(via
		(at 182.0975 158.325)
		(size 0.45)
		(drill 0.1)
		(layers "F.Cu" "B.Cu")
		(teardrops
			(best_length_ratio 0.4)
			(max_length 1)
			(best_width_ratio 0.9)
			(max_width 2)
			(curved_edges yes)
			(filter_ratio 0.9)
			(enabled yes)
			(allow_two_segments yes)
			(prefer_zone_connections yes)
		)
		(net 161)
	)
	(via
		(at 128.1475 107.75)
		(size 0.45)
		(drill 0.1)
		(layers "F.Cu" "B.Cu")
		(teardrops
			(best_length_ratio 0.4)
			(max_length 1)
			(best_width_ratio 0.9)
			(max_width 2)
			(curved_edges yes)
			(filter_ratio 0.9)
			(enabled yes)
			(allow_two_segments yes)
			(prefer_zone_connections yes)
		)
		(net 161)
	)
	(segment
		(start 112.201421 108.116421)
		(end 111.45 107.365)
		(width 0.185)
		(layer "B.Cu")
		(net 161)
	)
	(segment
		(start 122.780386 104.86)
		(end 122.766751 104.86)
		(width 0.185)
		(layer "B.Cu")
		(net 161)
	)
	(segment
		(start 122.803 104.86)
		(end 122.786351 104.86)
		(width 0.185)
		(layer "B.Cu")
		(net 161)
	)
	(segment
		(start 128.015 106.421298)
		(end 128.015 107.6175)
		(width 0.185)
		(layer "B.Cu")
		(net 161)
	)
	(segment
		(start 117.087027 108.744271)
		(end 116.334191 109.497107)
		(width 0.185)
		(layer "B.Cu")
		(net 161)
	)
	(segment
		(start 123.935 104.8)
		(end 123.995 104.86)
		(width 0.185)
		(layer "B.Cu")
		(net 161)
	)
	(segment
		(start 114.635809 109.497107)
		(end 113.710566 108.571864)
		(width 0.185)
		(layer "B.Cu")
		(net 161)
	)
	(segment
		(start 123.995 104.86)
		(end 126.453702 104.86)
		(width 0.185)
		(layer "B.Cu")
		(net 161)
	)
	(segment
		(start 122.786351 104.86)
		(end 122.780386 104.86)
		(width 0.185)
		(layer "B.Cu")
		(net 161)
	)
	(segment
		(start 112.752451 108.175)
		(end 112.342843 108.175)
		(width 0.185)
		(layer "B.Cu")
		(net 161)
	)
	(segment
		(start 126.453702 104.86)
		(end 128.015 106.421298)
		(width 0.185)
		(layer "B.Cu")
		(net 161)
	)
	(segment
		(start 122.863 104.8)
		(end 122.803 104.86)
		(width 0.185)
		(layer "B.Cu")
		(net 161)
	)
	(segment
		(start 123.785 104.8)
		(end 123.013 104.8)
		(width 0.185)
		(layer "B.Cu")
		(net 161)
	)
	(segment
		(start 115.627084 109.79)
		(end 115.342916 109.79)
		(width 0.185)
		(layer "B.Cu")
		(net 161)
	)
	(segment
		(start 128.015 107.6175)
		(end 128.1475 107.75)
		(width 0.185)
		(layer "B.Cu")
		(net 161)
	)
	(segment
		(start 118.517084 108.34)
		(end 118.063023 108.34)
		(width 0.185)
		(layer "B.Cu")
		(net 161)
	)
	(segment
		(start 122.159943 105.111355)
		(end 119.224191 108.047107)
		(width 0.185)
		(layer "B.Cu")
		(net 161)
	)
	(arc
		(start 113.710566 108.571864)
		(mid 113.270979 108.278141)
		(end 112.752451 108.175)
		(width 0.185)
		(layer "B.Cu")
		(net 161)
	)
	(arc
		(start 112.201421 108.116421)
		(mid 112.266306 108.159776)
		(end 112.342843 108.175)
		(width 0.185)
		(layer "B.Cu")
		(net 161)
	)
	(arc
		(start 114.635809 109.497107)
		(mid 114.960232 109.71388)
		(end 115.342916 109.79)
		(width 0.185)
		(layer "B.Cu")
		(net 161)
	)
	(arc
		(start 117.087027 108.744271)
		(mid 117.534818 108.445067)
		(end 118.063023 108.34)
		(width 0.185)
		(layer "B.Cu")
		(net 161)
	)
	(arc
		(start 122.766751 104.86)
		(mid 122.438348 104.925328)
		(end 122.159943 105.111355)
		(width 0.185)
		(layer "B.Cu")
		(net 161)
	)
	(arc
		(start 116.334191 109.497107)
		(mid 116.009768 109.71388)
		(end 115.627084 109.79)
		(width 0.185)
		(layer "B.Cu")
		(net 161)
	)
	(arc
		(start 118.517084 108.34)
		(mid 118.899767 108.26388)
		(end 119.224191 108.047107)
		(width 0.185)
		(layer "B.Cu")
		(net 161)
	)
	(segment
		(start 182.22518 159.1935)
		(end 182.84982 159.1935)
		(width 0.159)
		(layer "In5.Cu")
		(net 161)
	)
	(segment
		(start 183.2935 153.831201)
		(end 183.2935 146.95018)
		(width 0.159)
		(layer "In5.Cu")
		(net 161)
	)
	(segment
		(start 183.0535 155.94)
		(end 182.883452 155.94)
		(width 0.159)
		(layer "In5.Cu")
		(net 161)
	)
	(segment
		(start 183.0535 157.14)
		(end 182.883446 157.14)
		(width 0.159)
		(layer "In5.Cu")
		(net 161)
	)
	(segment
		(start 128.0065 107.609)
		(end 128.1475 107.75)
		(width 0.159)
		(layer "In5.Cu")
		(net 161)
	)
	(segment
		(start 182.643452 155.7)
		(end 182.643452 155.58)
		(width 0.159)
		(layer "In5.Cu")
		(net 161)
	)
	(segment
		(start 182.0975 158.325)
		(end 181.9565 158.466)
		(width 0.159)
		(layer "In5.Cu")
		(net 161)
	)
	(segment
		(start 183.2935 146.95018)
		(end 177.9685 141.62518)
		(width 0.159)
		(layer "In5.Cu")
		(net 161)
	)
	(segment
		(start 181.9565 158.92482)
		(end 182.22518 159.1935)
		(width 0.159)
		(layer "In5.Cu")
		(net 161)
	)
	(segment
		(start 128.0065 107.362106)
		(end 128.0065 107.609)
		(width 0.159)
		(layer "In5.Cu")
		(net 161)
	)
	(segment
		(start 128.89482 107.1015)
		(end 128.267106 107.1015)
		(width 0.159)
		(layer "In5.Cu")
		(net 161)
	)
	(segment
		(start 182.883452 155.34)
		(end 183.0535 155.34)
		(width 0.159)
		(layer "In5.Cu")
		(net 161)
	)
	(segment
		(start 181.9565 158.466)
		(end 181.9565 158.92482)
		(width 0.159)
		(layer "In5.Cu")
		(net 161)
	)
	(segment
		(start 128.267106 107.1015)
		(end 128.0065 107.362106)
		(width 0.159)
		(layer "In5.Cu")
		(net 161)
	)
	(segment
		(start 182.643446 156.9)
		(end 182.643446 156.78)
		(width 0.159)
		(layer "In5.Cu")
		(net 161)
	)
	(segment
		(start 164.39982 116.7315)
		(end 138.52482 116.7315)
		(width 0.159)
		(layer "In5.Cu")
		(net 161)
	)
	(segment
		(start 138.52482 116.7315)
		(end 128.89482 107.1015)
		(width 0.159)
		(layer "In5.Cu")
		(net 161)
	)
	(segment
		(start 182.883446 156.54)
		(end 183.0535 156.54)
		(width 0.159)
		(layer "In5.Cu")
		(net 161)
	)
	(segment
		(start 183.2935 156.3)
		(end 183.2935 156.18)
		(width 0.159)
		(layer "In5.Cu")
		(net 161)
	)
	(segment
		(start 177.9685 141.62518)
		(end 177.9685 130.30018)
		(width 0.159)
		(layer "In5.Cu")
		(net 161)
	)
	(segment
		(start 183.2935 158.74982)
		(end 183.2935 157.38)
		(width 0.159)
		(layer "In5.Cu")
		(net 161)
	)
	(segment
		(start 177.9685 130.30018)
		(end 164.39982 116.7315)
		(width 0.159)
		(layer "In5.Cu")
		(net 161)
	)
	(segment
		(start 182.84982 159.1935)
		(end 183.2935 158.74982)
		(width 0.159)
		(layer "In5.Cu")
		(net 161)
	)
	(segment
		(start 183.2935 154.98)
		(end 183.2935 153.831201)
		(width 0.159)
		(layer "In5.Cu")
		(net 161)
	)
	(segment
		(start 183.2935 155.1)
		(end 183.2935 154.98)
		(width 0.159)
		(layer "In5.Cu")
		(net 161)
	)
	(arc
		(start 182.643452 155.58)
		(mid 182.713746 155.410294)
		(end 182.883452 155.34)
		(width 0.159)
		(layer "In5.Cu")
		(net 161)
	)
	(arc
		(start 182.883452 155.94)
		(mid 182.713746 155.869706)
		(end 182.643452 155.7)
		(width 0.159)
		(layer "In5.Cu")
		(net 161)
	)
	(arc
		(start 183.0535 155.34)
		(mid 183.223206 155.269706)
		(end 183.2935 155.1)
		(width 0.159)
		(layer "In5.Cu")
		(net 161)
	)
	(arc
		(start 182.643446 156.78)
		(mid 182.71374 156.610294)
		(end 182.883446 156.54)
		(width 0.159)
		(layer "In5.Cu")
		(net 161)
	)
	(arc
		(start 182.883446 157.14)
		(mid 182.71374 157.069706)
		(end 182.643446 156.9)
		(width 0.159)
		(layer "In5.Cu")
		(net 161)
	)
	(arc
		(start 183.0535 156.54)
		(mid 183.223206 156.469706)
		(end 183.2935 156.3)
		(width 0.159)
		(layer "In5.Cu")
		(net 161)
	)
	(arc
		(start 183.2935 157.38)
		(mid 183.223206 157.210294)
		(end 183.0535 157.14)
		(width 0.159)
		(layer "In5.Cu")
		(net 161)
	)
	(arc
		(start 183.2935 156.18)
		(mid 183.223206 156.010294)
		(end 183.0535 155.94)
		(width 0.159)
		(layer "In5.Cu")
		(net 161)
	)
	(segment
		(start 143.05 166.61)
		(end 144 165.66)
		(width 0.125)
		(layer "F.Cu")
		(net 162)
	)
	(segment
		(start 143.05 167.71)
		(end 143.05 166.61)
		(width 0.125)
		(layer "F.Cu")
		(net 162)
	)
	(segment
		(start 144 160.46)
		(end 144.75 159.71)
		(width 0.125)
		(layer "F.Cu")
		(net 162)
	)
	(segment
		(start 144 165.66)
		(end 144 160.46)
		(width 0.125)
		(layer "F.Cu")
		(net 162)
	)
	(via
		(at 143.05 167.71)
		(size 0.45)
		(drill 0.1)
		(layers "F.Cu" "B.Cu")
		(remove_unused_layers yes)
		(keep_end_layers yes)
		(zone_layer_connections)
		(teardrops
			(best_length_ratio 0.4)
			(max_length 1)
			(best_width_ratio 0.9)
			(max_width 2)
			(curved_edges yes)
			(filter_ratio 0.9)
			(enabled yes)
			(allow_two_segments yes)
			(prefer_zone_connections yes)
		)
		(net 162)
	)
	(segment
		(start 143.05 167.71)
		(end 143.55 167.21)
		(width 0.125)
		(layer "B.Cu")
		(net 162)
	)
	(segment
		(start 143.05 168.68)
		(end 143.05 167.71)
		(width 0.125)
		(layer "B.Cu")
		(net 162)
	)
	(segment
		(start 148.05 168.68)
		(end 148.05 167.21)
		(width 0.125)
		(layer "B.Cu")
		(net 163)
	)
	(segment
		(start 148.05 167.21)
		(end 146.85 166.01)
		(width 0.125)
		(layer "B.Cu")
		(net 163)
	)
	(segment
		(start 146.85 166.01)
		(end 146.85 161.23)
		(width 0.125)
		(layer "B.Cu")
		(net 163)
	)
	(segment
		(start 146.85 161.23)
		(end 146.13 160.51)
		(width 0.125)
		(layer "B.Cu")
		(net 163)
	)
	(segment
		(start 175.999998 142.999998)
		(end 175.7 142.7)
		(width 0.125)
		(layer "F.Cu")
		(net 164)
	)
	(segment
		(start 177.92 142.999998)
		(end 175.999998 142.999998)
		(width 0.125)
		(layer "F.Cu")
		(net 164)
	)
	(via
		(at 165.5 146.1)
		(size 0.45)
		(drill 0.1)
		(layers "F.Cu" "B.Cu")
		(teardrops
			(best_length_ratio 0.4)
			(max_length 1)
			(best_width_ratio 0.9)
			(max_width 2)
			(curved_edges yes)
			(filter_ratio 0.9)
			(enabled yes)
			(allow_two_segments yes)
			(prefer_zone_connections yes)
		)
		(net 164)
	)
	(via
		(at 175.7 142.7)
		(size 0.45)
		(drill 0.1)
		(layers "F.Cu" "B.Cu")
		(teardrops
			(best_length_ratio 0.4)
			(max_length 1)
			(best_width_ratio 0.9)
			(max_width 2)
			(curved_edges yes)
			(filter_ratio 0.9)
			(enabled yes)
			(allow_two_segments yes)
			(prefer_zone_connections yes)
		)
		(net 164)
	)
	(segment
		(start 171.1 142.7)
		(end 175.7 142.7)
		(width 0.125)
		(layer "In2.Cu")
		(net 164)
	)
	(segment
		(start 167.7 146.1)
		(end 171.1 142.7)
		(width 0.125)
		(layer "In2.Cu")
		(net 164)
	)
	(segment
		(start 165.5 146.1)
		(end 167.7 146.1)
		(width 0.125)
		(layer "In2.Cu")
		(net 164)
	)
	(segment
		(start 168.6 157.6)
		(end 167.9 156.9)
		(width 0.125)
		(layer "In5.Cu")
		(net 164)
	)
	(segment
		(start 161 147.7)
		(end 162.6 146.1)
		(width 0.125)
		(layer "In5.Cu")
		(net 164)
	)
	(segment
		(start 152.95 160.91)
		(end 155.7975 163.7575)
		(width 0.125)
		(layer "In5.Cu")
		(net 164)
	)
	(segment
		(start 155.7975 163.7575)
		(end 160.0625 163.7575)
		(width 0.125)
		(layer "In5.Cu")
		(net 164)
	)
	(segment
		(start 167.9 156.9)
		(end 167.9 153.7)
		(width 0.125)
		(layer "In5.Cu")
		(net 164)
	)
	(segment
		(start 164.7 164.7)
		(end 167.9 164.7)
		(width 0.125)
		(layer "In5.Cu")
		(net 164)
	)
	(segment
		(start 147.2075 160.2675)
		(end 148.2075 160.2675)
		(width 0.125)
		(layer "In5.Cu")
		(net 164)
	)
	(segment
		(start 167.9 153.7)
		(end 166.025 151.825)
		(width 0.125)
		(layer "In5.Cu")
		(net 164)
	)
	(segment
		(start 166.025 151.825)
		(end 161.125 151.825)
		(width 0.125)
		(layer "In5.Cu")
		(net 164)
	)
	(segment
		(start 168.6 164)
		(end 168.6 157.6)
		(width 0.125)
		(layer "In5.Cu")
		(net 164)
	)
	(segment
		(start 145.584389 159.8675)
		(end 146.8075 159.8675)
		(width 0.125)
		(layer "In5.Cu")
		(net 164)
	)
	(segment
		(start 160.305 164)
		(end 164 164)
		(width 0.125)
		(layer "In5.Cu")
		(net 164)
	)
	(segment
		(start 148.2075 160.2675)
		(end 148.85 160.91)
		(width 0.125)
		(layer "In5.Cu")
		(net 164)
	)
	(segment
		(start 146.8075 159.8675)
		(end 147.2075 160.2675)
		(width 0.125)
		(layer "In5.Cu")
		(net 164)
	)
	(segment
		(start 160.0625 163.7575)
		(end 160.305 164)
		(width 0.125)
		(layer "In5.Cu")
		(net 164)
	)
	(segment
		(start 144.75 160.701889)
		(end 145.584389 159.8675)
		(width 0.125)
		(layer "In5.Cu")
		(net 164)
	)
	(segment
		(start 167.9 164.7)
		(end 168.6 164)
		(width 0.125)
		(layer "In5.Cu")
		(net 164)
	)
	(segment
		(start 164 164)
		(end 164.7 164.7)
		(width 0.125)
		(layer "In5.Cu")
		(net 164)
	)
	(segment
		(start 144.75 161.31)
		(end 144.75 160.701889)
		(width 0.125)
		(layer "In5.Cu")
		(net 164)
	)
	(segment
		(start 148.85 160.91)
		(end 152.95 160.91)
		(width 0.125)
		(layer "In5.Cu")
		(net 164)
	)
	(segment
		(start 161 151.7)
		(end 161 147.7)
		(width 0.125)
		(layer "In5.Cu")
		(net 164)
	)
	(segment
		(start 161.125 151.825)
		(end 161 151.7)
		(width 0.125)
		(layer "In5.Cu")
		(net 164)
	)
	(segment
		(start 162.6 146.1)
		(end 165.5 146.1)
		(width 0.125)
		(layer "In5.Cu")
		(net 164)
	)
	(segment
		(start 177 147)
		(end 177.92 147)
		(width 0.125)
		(layer "F.Cu")
		(net 165)
	)
	(via
		(at 165.5 147.7)
		(size 0.45)
		(drill 0.1)
		(layers "F.Cu" "B.Cu")
		(teardrops
			(best_length_ratio 0.4)
			(max_length 1)
			(best_width_ratio 0.9)
			(max_width 2)
			(curved_edges yes)
			(filter_ratio 0.9)
			(enabled yes)
			(allow_two_segments yes)
			(prefer_zone_connections yes)
		)
		(net 165)
	)
	(via
		(at 177 147)
		(size 0.45)
		(drill 0.1)
		(layers "F.Cu" "B.Cu")
		(teardrops
			(best_length_ratio 0.4)
			(max_length 1)
			(best_width_ratio 0.9)
			(max_width 2)
			(curved_edges yes)
			(filter_ratio 0.9)
			(enabled yes)
			(allow_two_segments yes)
			(prefer_zone_connections yes)
		)
		(net 165)
	)
	(segment
		(start 175 147.8)
		(end 175.8 147)
		(width 0.125)
		(layer "In2.Cu")
		(net 165)
	)
	(segment
		(start 167.8 147.8)
		(end 175 147.8)
		(width 0.125)
		(layer "In2.Cu")
		(net 165)
	)
	(segment
		(start 167.4 148.2)
		(end 167.8 147.8)
		(width 0.125)
		(layer "In2.Cu")
		(net 165)
	)
	(segment
		(start 166.4 147.7)
		(end 166.9 148.2)
		(width 0.125)
		(layer "In2.Cu")
		(net 165)
	)
	(segment
		(start 175.8 147)
		(end 177 147)
		(width 0.125)
		(layer "In2.Cu")
		(net 165)
	)
	(segment
		(start 166.9 148.2)
		(end 167.4 148.2)
		(width 0.125)
		(layer "In2.Cu")
		(net 165)
	)
	(segment
		(start 165.5 147.7)
		(end 166.4 147.7)
		(width 0.125)
		(layer "In2.Cu")
		(net 165)
	)
	(segment
		(start 168.15 153.35)
		(end 166.35 151.55)
		(width 0.125)
		(layer "In5.Cu")
		(net 165)
	)
	(segment
		(start 148.8 162.56)
		(end 150.68191 162.56)
		(width 0.125)
		(layer "In5.Cu")
		(net 165)
	)
	(segment
		(start 146.13 162.11)
		(end 146.559999 161.680001)
		(width 0.125)
		(layer "In5.Cu")
		(net 165)
	)
	(segment
		(start 161.5 151.3)
		(end 161.5 148.6)
		(width 0.125)
		(layer "In5.Cu")
		(net 165)
	)
	(segment
		(start 150.68191 162.56)
		(end 152.37191 164.25)
		(width 0.125)
		(layer "In5.Cu")
		(net 165)
	)
	(segment
		(start 146.559999 161.680001)
		(end 147.920001 161.680001)
		(width 0.125)
		(layer "In5.Cu")
		(net 165)
	)
	(segment
		(start 161.75 151.55)
		(end 161.5 151.3)
		(width 0.125)
		(layer "In5.Cu")
		(net 165)
	)
	(segment
		(start 168.1 165.2)
		(end 169 164.3)
		(width 0.125)
		(layer "In5.Cu")
		(net 165)
	)
	(segment
		(start 166.35 151.55)
		(end 161.75 151.55)
		(width 0.125)
		(layer "In5.Cu")
		(net 165)
	)
	(segment
		(start 162.4 147.7)
		(end 165.5 147.7)
		(width 0.125)
		(layer "In5.Cu")
		(net 165)
	)
	(segment
		(start 152.37191 164.25)
		(end 163.896446 164.25)
		(width 0.125)
		(layer "In5.Cu")
		(net 165)
	)
	(segment
		(start 161.5 148.6)
		(end 162.4 147.7)
		(width 0.125)
		(layer "In5.Cu")
		(net 165)
	)
	(segment
		(start 168.15 156.775)
		(end 168.15 153.35)
		(width 0.125)
		(layer "In5.Cu")
		(net 165)
	)
	(segment
		(start 164.846446 165.2)
		(end 168.1 165.2)
		(width 0.125)
		(layer "In5.Cu")
		(net 165)
	)
	(segment
		(start 147.920001 161.680001)
		(end 148.8 162.56)
		(width 0.125)
		(layer "In5.Cu")
		(net 165)
	)
	(segment
		(start 163.896446 164.25)
		(end 164.846446 165.2)
		(width 0.125)
		(layer "In5.Cu")
		(net 165)
	)
	(segment
		(start 169 164.3)
		(end 169 157.625)
		(width 0.125)
		(layer "In5.Cu")
		(net 165)
	)
	(segment
		(start 169 157.625)
		(end 168.15 156.775)
		(width 0.125)
		(layer "In5.Cu")
		(net 165)
	)
	(segment
		(start 143.85 167.91)
		(end 143.929317 167.91)
		(width 0.125)
		(layer "F.Cu")
		(net 166)
	)
	(segment
		(start 143.929317 167.91)
		(end 145.45 166.389317)
		(width 0.125)
		(layer "F.Cu")
		(net 166)
	)
	(segment
		(start 145.45 163.61)
		(end 144.75 162.91)
		(width 0.125)
		(layer "F.Cu")
		(net 166)
	)
	(segment
		(start 145.45 166.389317)
		(end 145.45 163.61)
		(width 0.125)
		(layer "F.Cu")
		(net 166)
	)
	(segment
		(start 177.2 145)
		(end 177.92 145)
		(width 0.125)
		(layer "F.Cu")
		(net 166)
	)
	(via
		(at 177.2 145)
		(size 0.45)
		(drill 0.1)
		(layers "F.Cu" "B.Cu")
		(teardrops
			(best_length_ratio 0.4)
			(max_length 1)
			(best_width_ratio 0.9)
			(max_width 2)
			(curved_edges yes)
			(filter_ratio 0.9)
			(enabled yes)
			(allow_two_segments yes)
			(prefer_zone_connections yes)
		)
		(net 166)
	)
	(via
		(at 143.85 167.91)
		(size 0.45)
		(drill 0.1)
		(layers "F.Cu" "B.Cu")
		(remove_unused_layers yes)
		(keep_end_layers yes)
		(zone_layer_connections)
		(teardrops
			(best_length_ratio 0.4)
			(max_length 1)
			(best_width_ratio 0.9)
			(max_width 2)
			(curved_edges yes)
			(filter_ratio 0.9)
			(enabled yes)
			(allow_two_segments yes)
			(prefer_zone_connections yes)
		)
		(net 166)
	)
	(via
		(at 165.2 148.3)
		(size 0.45)
		(drill 0.1)
		(layers "F.Cu" "B.Cu")
		(teardrops
			(best_length_ratio 0.4)
			(max_length 1)
			(best_width_ratio 0.9)
			(max_width 2)
			(curved_edges yes)
			(filter_ratio 0.9)
			(enabled yes)
			(allow_two_segments yes)
			(prefer_zone_connections yes)
		)
		(net 166)
	)
	(segment
		(start 143.85 167.91)
		(end 144.05 168.11)
		(width 0.125)
		(layer "B.Cu")
		(net 166)
	)
	(segment
		(start 144.05 168.11)
		(end 144.05 168.68)
		(width 0.125)
		(layer "B.Cu")
		(net 166)
	)
	(segment
		(start 170.4 146.9)
		(end 172.3 145)
		(width 0.125)
		(layer "In2.Cu")
		(net 166)
	)
	(segment
		(start 165.3 146.9)
		(end 170.4 146.9)
		(width 0.125)
		(layer "In2.Cu")
		(net 166)
	)
	(segment
		(start 164.8 147.9)
		(end 164.8 147.4)
		(width 0.125)
		(layer "In2.Cu")
		(net 166)
	)
	(segment
		(start 172.3 145)
		(end 177.2 145)
		(width 0.125)
		(layer "In2.Cu")
		(net 166)
	)
	(segment
		(start 165.2 148.3)
		(end 164.8 147.9)
		(width 0.125)
		(layer "In2.Cu")
		(net 166)
	)
	(segment
		(start 164.8 147.4)
		(end 165.3 146.9)
		(width 0.125)
		(layer "In2.Cu")
		(net 166)
	)
	(segment
		(start 166.6 151.3)
		(end 162.2 151.3)
		(width 0.125)
		(layer "In5.Cu")
		(net 166)
	)
	(segment
		(start 151.855 164.7)
		(end 154.43 164.7)
		(width 0.125)
		(layer "In5.Cu")
		(net 166)
	)
	(segment
		(start 161.9 151)
		(end 161.9 149.3)
		(width 0.125)
		(layer "In5.Cu")
		(net 166)
	)
	(segment
		(start 162.9 148.3)
		(end 165.2 148.3)
		(width 0.125)
		(layer "In5.Cu")
		(net 166)
	)
	(segment
		(start 161.9 149.3)
		(end 162.9 148.3)
		(width 0.125)
		(layer "In5.Cu")
		(net 166)
	)
	(segment
		(start 168.425 156.625)
		(end 168.425 153.125)
		(width 0.125)
		(layer "In5.Cu")
		(net 166)
	)
	(segment
		(start 147.830683 163.190683)
		(end 148.75 164.11)
		(width 0.125)
		(layer "In5.Cu")
		(net 166)
	)
	(segment
		(start 144.75 162.91)
		(end 146.5 162.91)
		(width 0.125)
		(layer "In5.Cu")
		(net 166)
	)
	(segment
		(start 146.5 162.91)
		(end 146.780683 163.190683)
		(width 0.125)
		(layer "In5.Cu")
		(net 166)
	)
	(segment
		(start 159.43 165.25)
		(end 160.18 164.5)
		(width 0.125)
		(layer "In5.Cu")
		(net 166)
	)
	(segment
		(start 160.18 164.5)
		(end 163.6 164.5)
		(width 0.125)
		(layer "In5.Cu")
		(net 166)
	)
	(segment
		(start 168.425 153.125)
		(end 166.6 151.3)
		(width 0.125)
		(layer "In5.Cu")
		(net 166)
	)
	(segment
		(start 162.2 151.3)
		(end 161.9 151)
		(width 0.125)
		(layer "In5.Cu")
		(net 166)
	)
	(segment
		(start 168.3 165.7)
		(end 169.4 164.6)
		(width 0.125)
		(layer "In5.Cu")
		(net 166)
	)
	(segment
		(start 146.780683 163.190683)
		(end 147.830683 163.190683)
		(width 0.125)
		(layer "In5.Cu")
		(net 166)
	)
	(segment
		(start 154.98 165.25)
		(end 159.43 165.25)
		(width 0.125)
		(layer "In5.Cu")
		(net 166)
	)
	(segment
		(start 163.6 164.5)
		(end 164.8 165.7)
		(width 0.125)
		(layer "In5.Cu")
		(net 166)
	)
	(segment
		(start 169.4 164.6)
		(end 169.4 157.6)
		(width 0.125)
		(layer "In5.Cu")
		(net 166)
	)
	(segment
		(start 164.8 165.7)
		(end 168.3 165.7)
		(width 0.125)
		(layer "In5.Cu")
		(net 166)
	)
	(segment
		(start 148.75 164.11)
		(end 151.265 164.11)
		(width 0.125)
		(layer "In5.Cu")
		(net 166)
	)
	(segment
		(start 154.43 164.7)
		(end 154.98 165.25)
		(width 0.125)
		(layer "In5.Cu")
		(net 166)
	)
	(segment
		(start 169.4 157.6)
		(end 168.425 156.625)
		(width 0.125)
		(layer "In5.Cu")
		(net 166)
	)
	(segment
		(start 151.265 164.11)
		(end 151.855 164.7)
		(width 0.125)
		(layer "In5.Cu")
		(net 166)
	)
	(segment
		(start 146.05 166.66)
		(end 145.45 166.06)
		(width 0.125)
		(layer "B.Cu")
		(net 167)
	)
	(segment
		(start 145.45 166.06)
		(end 145.45 164.39)
		(width 0.125)
		(layer "B.Cu")
		(net 167)
	)
	(segment
		(start 145.45 164.39)
		(end 146.13 163.71)
		(width 0.125)
		(layer "B.Cu")
		(net 167)
	)
	(segment
		(start 146.05 168.68)
		(end 146.05 166.66)
		(width 0.125)
		(layer "B.Cu")
		(net 167)
	)
	(segment
		(start 145.05 168.68)
		(end 145.05 167.71)
		(width 0.125)
		(layer "B.Cu")
		(net 168)
	)
	(segment
		(start 145.05 167.45)
		(end 145.05 167.71)
		(width 0.125)
		(layer "B.Cu")
		(net 168)
	)
	(segment
		(start 145.35 167.21)
		(end 145.29 167.21)
		(width 0.125)
		(layer "B.Cu")
		(net 168)
	)
	(segment
		(start 145.29 167.21)
		(end 145.05 167.45)
		(width 0.125)
		(layer "B.Cu")
		(net 168)
	)
	(segment
		(start 144.05 165.21)
		(end 144.75 164.51)
		(width 0.125)
		(layer "B.Cu")
		(net 168)
	)
	(segment
		(start 144.955 167.605)
		(end 144.945 167.605)
		(width 0.125)
		(layer "B.Cu")
		(net 168)
	)
	(segment
		(start 144.945 167.605)
		(end 145.05 167.71)
		(width 0.125)
		(layer "B.Cu")
		(net 168)
	)
	(segment
		(start 144.05 166.71)
		(end 144.945 167.605)
		(width 0.125)
		(layer "B.Cu")
		(net 168)
	)
	(segment
		(start 144.05 166.71)
		(end 144.05 165.21)
		(width 0.125)
		(layer "B.Cu")
		(net 168)
	)
	(segment
		(start 145.35 167.21)
		(end 144.955 167.605)
		(width 0.125)
		(layer "B.Cu")
		(net 168)
	)
	(segment
		(start 147.05 166.86)
		(end 146.13 165.94)
		(width 0.125)
		(layer "B.Cu")
		(net 169)
	)
	(segment
		(start 146.13 165.94)
		(end 146.13 165.31)
		(width 0.125)
		(layer "B.Cu")
		(net 169)
	)
	(segment
		(start 147.05 168.68)
		(end 147.05 166.86)
		(width 0.125)
		(layer "B.Cu")
		(net 169)
	)
	(via
		(at 150.285 147.63)
		(size 0.45)
		(drill 0.1)
		(layers "F.Cu" "B.Cu")
		(remove_unused_layers yes)
		(keep_end_layers yes)
		(zone_layer_connections)
		(teardrops
			(best_length_ratio 0.4)
			(max_length 1)
			(best_width_ratio 0.9)
			(max_width 2)
			(curved_edges yes)
			(filter_ratio 0.9)
			(enabled yes)
			(allow_two_segments yes)
			(prefer_zone_connections yes)
		)
		(net 170)
	)
	(segment
		(start 153.36132 156.552618)
		(end 151.018679 154.209977)
		(width 0.16)
		(layer "B.Cu")
		(net 170)
	)
	(segment
		(start 150.14 147.775)
		(end 150.285 147.63)
		(width 0.16)
		(layer "B.Cu")
		(net 170)
	)
	(segment
		(start 149.572842 164.490001)
		(end 149.85 164.490001)
		(width 0.16)
		(layer "B.Cu")
		(net 170)
	)
	(segment
		(start 150.123448 164.76345)
		(end 150.15 164.76345)
		(width 0.16)
		(layer "B.Cu")
		(net 170)
	)
	(segment
		(start 150.886724 164.626726)
		(end 150.886724 164.626725)
		(width 0.16)
		(layer "B.Cu")
		(net 170)
	)
	(segment
		(start 150.586724 164.626725)
		(end 150.586724 164.626726)
		(width 0.16)
		(layer "B.Cu")
		(net 170)
	)
	(segment
		(start 150.286724 164.626726)
		(end 150.286724 164.626725)
		(width 0.16)
		(layer "B.Cu")
		(net 170)
	)
	(segment
		(start 149.986724 164.626725)
		(end 149.986724 164.626726)
		(width 0.16)
		(layer "B.Cu")
		(net 170)
	)
	(segment
		(start 151.05 164.490001)
		(end 152.040444 164.490001)
		(width 0.16)
		(layer "B.Cu")
		(net 170)
	)
	(segment
		(start 149.07 164.91)
		(end 149.431421 164.548579)
		(width 0.16)
		(layer "B.Cu")
		(net 170)
	)
	(segment
		(start 150.723448 164.76345)
		(end 150.75 164.76345)
		(width 0.16)
		(layer "B.Cu")
		(net 170)
	)
	(segment
		(start 153.573864 163.854838)
		(end 153.613639 163.815063)
		(width 0.16)
		(layer "B.Cu")
		(net 170)
	)
	(segment
		(start 154.24 162.302896)
		(end 154.24 158.673939)
		(width 0.16)
		(layer "B.Cu")
		(net 170)
	)
	(segment
		(start 150.423448 164.490001)
		(end 150.45 164.490001)
		(width 0.16)
		(layer "B.Cu")
		(net 170)
	)
	(segment
		(start 150.14 152.088657)
		(end 150.14 147.775)
		(width 0.16)
		(layer "B.Cu")
		(net 170)
	)
	(segment
		(start 151.023448 164.490001)
		(end 151.05 164.490001)
		(width 0.16)
		(layer "B.Cu")
		(net 170)
	)
	(arc
		(start 149.986724 164.626726)
		(mid 150.02677 164.723404)
		(end 150.123448 164.76345)
		(width 0.16)
		(layer "B.Cu")
		(net 170)
	)
	(arc
		(start 150.586724 164.626726)
		(mid 150.62677 164.723404)
		(end 150.723448 164.76345)
		(width 0.16)
		(layer "B.Cu")
		(net 170)
	)
	(arc
		(start 152.040444 164.490001)
		(mid 152.870325 164.324928)
		(end 153.573864 163.854838)
		(width 0.16)
		(layer "B.Cu")
		(net 170)
	)
	(arc
		(start 150.286724 164.626725)
		(mid 150.32677 164.530047)
		(end 150.423448 164.490001)
		(width 0.16)
		(layer "B.Cu")
		(net 170)
	)
	(arc
		(start 154.24 158.673939)
		(mid 154.011639 157.525888)
		(end 153.36132 156.552618)
		(width 0.16)
		(layer "B.Cu")
		(net 170)
	)
	(arc
		(start 149.85 164.490001)
		(mid 149.946678 164.530047)
		(end 149.986724 164.626725)
		(width 0.16)
		(layer "B.Cu")
		(net 170)
	)
	(arc
		(start 153.613639 163.815063)
		(mid 154.077213 163.121275)
		(end 154.24 162.302896)
		(width 0.16)
		(layer "B.Cu")
		(net 170)
	)
	(arc
		(start 150.75 164.76345)
		(mid 150.846678 164.723404)
		(end 150.886724 164.626726)
		(width 0.16)
		(layer "B.Cu")
		(net 170)
	)
	(arc
		(start 150.15 164.76345)
		(mid 150.246678 164.723404)
		(end 150.286724 164.626726)
		(width 0.16)
		(layer "B.Cu")
		(net 170)
	)
	(arc
		(start 151.018679 154.209977)
		(mid 150.368361 153.236707)
		(end 150.14 152.088657)
		(width 0.16)
		(layer "B.Cu")
		(net 170)
	)
	(arc
		(start 149.431421 164.548579)
		(mid 149.496306 164.505225)
		(end 149.572842 164.490001)
		(width 0.16)
		(layer "B.Cu")
		(net 170)
	)
	(arc
		(start 150.45 164.490001)
		(mid 150.546678 164.530047)
		(end 150.586724 164.626725)
		(width 0.16)
		(layer "B.Cu")
		(net 170)
	)
	(arc
		(start 150.886724 164.626725)
		(mid 150.92677 164.530047)
		(end 151.023448 164.490001)
		(width 0.16)
		(layer "B.Cu")
		(net 170)
	)
	(via
		(at 149.615 147.63)
		(size 0.45)
		(drill 0.1)
		(layers "F.Cu" "B.Cu")
		(remove_unused_layers yes)
		(keep_end_layers yes)
		(zone_layer_connections)
		(teardrops
			(best_length_ratio 0.4)
			(max_length 1)
			(best_width_ratio 0.9)
			(max_width 2)
			(curved_edges yes)
			(filter_ratio 0.9)
			(enabled yes)
			(allow_two_segments yes)
			(prefer_zone_connections yes)
		)
		(net 171)
	)
	(segment
		(start 152.98132 156.710022)
		(end 150.638679 154.367381)
		(width 0.16)
		(layer "B.Cu")
		(net 171)
	)
	(segment
		(start 153.328092 163.563206)
		(end 153.323548 163.56775)
		(width 0.16)
		(layer "B.Cu")
		(net 171)
	)
	(segment
		(start 149.76 152.246061)
		(end 149.76 147.775)
		(width 0.16)
		(layer "B.Cu")
		(net 171)
	)
	(segment
		(start 149.76 147.775)
		(end 149.615 147.63)
		(width 0.16)
		(layer "B.Cu")
		(net 171)
	)
	(segment
		(start 153.86 162.279068)
		(end 153.86 158.831343)
		(width 0.16)
		(layer "B.Cu")
		(net 171)
	)
	(segment
		(start 153.323548 163.56775)
		(end 153.311983 163.579315)
		(width 0.16)
		(layer "B.Cu")
		(net 171)
	)
	(segment
		(start 147.68 164.11)
		(end 152.03084 164.11)
		(width 0.16)
		(layer "B.Cu")
		(net 171)
	)
	(arc
		(start 153.86 162.279068)
		(mid 153.72176 162.974043)
		(end 153.328092 163.563206)
		(width 0.16)
		(layer "B.Cu")
		(net 171)
	)
	(arc
		(start 153.86 158.831343)
		(mid 153.631638 157.683292)
		(end 152.98132 156.710022)
		(width 0.16)
		(layer "B.Cu")
		(net 171)
	)
	(arc
		(start 153.311983 163.579315)
		(mid 152.724163 163.97209)
		(end 152.03084 164.11)
		(width 0.16)
		(layer "B.Cu")
		(net 171)
	)
	(arc
		(start 149.76 152.246061)
		(mid 149.988361 153.394111)
		(end 150.638679 154.367381)
		(width 0.16)
		(layer "B.Cu")
		(net 171)
	)
	(via
		(at 147.28 147.63)
		(size 0.45)
		(drill 0.1)
		(layers "F.Cu" "B.Cu")
		(remove_unused_layers yes)
		(keep_end_layers yes)
		(zone_layer_connections)
		(teardrops
			(best_length_ratio 0.4)
			(max_length 1)
			(best_width_ratio 0.9)
			(max_width 2)
			(curved_edges yes)
			(filter_ratio 0.9)
			(enabled yes)
			(allow_two_segments yes)
			(prefer_zone_connections yes)
		)
		(net 172)
	)
	(segment
		(start 147.91 152.975)
		(end 145.98 152.975)
		(width 0.16)
		(layer "B.Cu")
		(net 172)
	)
	(segment
		(start 148.165 158.665)
		(end 148.4 158.9)
		(width 0.16)
		(layer "B.Cu")
		(net 172)
	)
	(segment
		(start 147.57 148.845)
		(end 147.91 148.845)
		(width 0.16)
		(layer "B.Cu")
		(net 172)
	)
	(segment
		(start 148.4 158.9)
		(end 148.4 159.4)
		(width 0.16)
		(layer "B.Cu")
		(net 172)
	)
	(segment
		(start 147.135 147.775)
		(end 147.135 148.41)
		(width 0.16)
		(layer "B.Cu")
		(net 172)
	)
	(segment
		(start 147.135 154.66)
		(end 147.135 154.819191)
		(width 0.16)
		(layer "B.Cu")
		(net 172)
	)
	(segment
		(start 149.07 160.07)
		(end 149.07 160.11)
		(width 0.16)
		(layer "B.Cu")
		(net 172)
	)
	(segment
		(start 145.98 153.845)
		(end 146.32 153.845)
		(width 0.16)
		(layer "B.Cu")
		(net 172)
	)
	(segment
		(start 147.281446 155.172744)
		(end 148.018553 155.909851)
		(width 0.16)
		(layer "B.Cu")
		(net 172)
	)
	(segment
		(start 147.91 150.475)
		(end 145.98 150.475)
		(width 0.16)
		(layer "B.Cu")
		(net 172)
	)
	(segment
		(start 148.4 159.4)
		(end 149.07 160.07)
		(width 0.16)
		(layer "B.Cu")
		(net 172)
	)
	(segment
		(start 145.98 151.345)
		(end 147.91 151.345)
		(width 0.16)
		(layer "B.Cu")
		(net 172)
	)
	(segment
		(start 148.165 156.263405)
		(end 148.165 158.665)
		(width 0.16)
		(layer "B.Cu")
		(net 172)
	)
	(segment
		(start 147.28 147.63)
		(end 147.135 147.775)
		(width 0.16)
		(layer "B.Cu")
		(net 172)
	)
	(arc
		(start 147.91 148.845)
		(mid 148.486292 149.083708)
		(end 148.725 149.66)
		(width 0.16)
		(layer "B.Cu")
		(net 172)
	)
	(arc
		(start 147.91 151.345)
		(mid 148.486292 151.583708)
		(end 148.725 152.16)
		(width 0.16)
		(layer "B.Cu")
		(net 172)
	)
	(arc
		(start 145.98 150.475)
		(mid 145.672409 150.602409)
		(end 145.545 150.91)
		(width 0.16)
		(layer "B.Cu")
		(net 172)
	)
	(arc
		(start 148.018553 155.909851)
		(mid 148.12694 156.072063)
		(end 148.165 156.263405)
		(width 0.16)
		(layer "B.Cu")
		(net 172)
	)
	(arc
		(start 145.545 153.41)
		(mid 145.672409 153.717591)
		(end 145.98 153.845)
		(width 0.16)
		(layer "B.Cu")
		(net 172)
	)
	(arc
		(start 145.98 152.975)
		(mid 145.672409 153.102409)
		(end 145.545 153.41)
		(width 0.16)
		(layer "B.Cu")
		(net 172)
	)
	(arc
		(start 148.725 152.16)
		(mid 148.486292 152.736292)
		(end 147.91 152.975)
		(width 0.16)
		(layer "B.Cu")
		(net 172)
	)
	(arc
		(start 147.135 154.819191)
		(mid 147.17306 155.010532)
		(end 147.281446 155.172744)
		(width 0.16)
		(layer "B.Cu")
		(net 172)
	)
	(arc
		(start 146.32 153.845)
		(mid 146.896292 154.083708)
		(end 147.135 154.66)
		(width 0.16)
		(layer "B.Cu")
		(net 172)
	)
	(arc
		(start 147.135 148.41)
		(mid 147.262409 148.717591)
		(end 147.57 148.845)
		(width 0.16)
		(layer "B.Cu")
		(net 172)
	)
	(arc
		(start 145.545 150.91)
		(mid 145.672409 151.217591)
		(end 145.98 151.345)
		(width 0.16)
		(layer "B.Cu")
		(net 172)
	)
	(arc
		(start 148.725 149.66)
		(mid 148.486292 150.236292)
		(end 147.91 150.475)
		(width 0.16)
		(layer "B.Cu")
		(net 172)
	)
	(via
		(at 146.61 147.63)
		(size 0.45)
		(drill 0.1)
		(layers "F.Cu" "B.Cu")
		(remove_unused_layers yes)
		(keep_end_layers yes)
		(zone_layer_connections)
		(teardrops
			(best_length_ratio 0.4)
			(max_length 1)
			(best_width_ratio 0.9)
			(max_width 2)
			(curved_edges yes)
			(filter_ratio 0.9)
			(enabled yes)
			(allow_two_segments yes)
			(prefer_zone_connections yes)
		)
		(net 173)
	)
	(segment
		(start 147.492077 157.905298)
		(end 147.613 157.905298)
		(width 0.16)
		(layer "B.Cu")
		(net 173)
	)
	(segment
		(start 146.755 154.976595)
		(end 146.755 154.66)
		(width 0.16)
		(layer "B.Cu")
		(net 173)
	)
	(segment
		(start 147.785 159.205)
		(end 147.785 158.507298)
		(width 0.16)
		(layer "B.Cu")
		(net 173)
	)
	(segment
		(start 147.638553 156.067255)
		(end 146.901446 155.330148)
		(width 0.16)
		(layer "B.Cu")
		(net 173)
	)
	(segment
		(start 147.320077 158.163298)
		(end 147.320077 158.077298)
		(width 0.16)
		(layer "B.Cu")
		(net 173)
	)
	(segment
		(start 147.613 157.475298)
		(end 147.492077 157.475298)
		(width 0.16)
		(layer "B.Cu")
		(net 173)
	)
	(segment
		(start 147.785 157.733298)
		(end 147.785 157.647298)
		(width 0.16)
		(layer "B.Cu")
		(net 173)
	)
	(segment
		(start 147.613 158.335298)
		(end 147.492077 158.335298)
		(width 0.16)
		(layer "B.Cu")
		(net 173)
	)
	(segment
		(start 147.91 149.225)
		(end 147.57 149.225)
		(width 0.16)
		(layer "B.Cu")
		(net 173)
	)
	(segment
		(start 145.98 152.595)
		(end 147.91 152.595)
		(width 0.16)
		(layer "B.Cu")
		(net 173)
	)
	(segment
		(start 145.98 150.095)
		(end 147.91 150.095)
		(width 0.16)
		(layer "B.Cu")
		(net 173)
	)
	(segment
		(start 146.755 147.775)
		(end 146.61 147.63)
		(width 0.16)
		(layer "B.Cu")
		(net 173)
	)
	(segment
		(start 147.320077 157.303298)
		(end 147.320077 157.217298)
		(width 0.16)
		(layer "B.Cu")
		(net 173)
	)
	(segment
		(start 147.91 151.725)
		(end 145.98 151.725)
		(width 0.16)
		(layer "B.Cu")
		(net 173)
	)
	(segment
		(start 146.755 148.41)
		(end 146.755 147.775)
		(width 0.16)
		(layer "B.Cu")
		(net 173)
	)
	(segment
		(start 147.785 156.873298)
		(end 147.785 156.420809)
		(width 0.16)
		(layer "B.Cu")
		(net 173)
	)
	(segment
		(start 147.492077 157.045298)
		(end 147.613 157.045298)
		(width 0.16)
		(layer "B.Cu")
		(net 173)
	)
	(segment
		(start 146.32 154.225)
		(end 145.98 154.225)
		(width 0.16)
		(layer "B.Cu")
		(net 173)
	)
	(arc
		(start 147.613 157.045298)
		(mid 147.734622 156.99492)
		(end 147.785 156.873298)
		(width 0.16)
		(layer "B.Cu")
		(net 173)
	)
	(arc
		(start 148.345 152.16)
		(mid 148.217591 151.852409)
		(end 147.91 151.725)
		(width 0.16)
		(layer "B.Cu")
		(net 173)
	)
	(arc
		(start 146.755 154.66)
		(mid 146.627591 154.352409)
		(end 146.32 154.225)
		(width 0.16)
		(layer "B.Cu")
		(net 173)
	)
	(arc
		(start 147.57 149.225)
		(mid 146.993708 148.986292)
		(end 146.755 148.41)
		(width 0.16)
		(layer "B.Cu")
		(net 173)
	)
	(arc
		(start 147.785 157.647298)
		(mid 147.734622 157.525676)
		(end 147.613 157.475298)
		(width 0.16)
		(layer "B.Cu")
		(net 173)
	)
	(arc
		(start 147.492077 157.475298)
		(mid 147.370455 157.42492)
		(end 147.320077 157.303298)
		(width 0.16)
		(layer "B.Cu")
		(net 173)
	)
	(arc
		(start 147.91 152.595)
		(mid 148.217591 152.467591)
		(end 148.345 152.16)
		(width 0.16)
		(layer "B.Cu")
		(net 173)
	)
	(arc
		(start 147.91 150.095)
		(mid 148.217591 149.967591)
		(end 148.345 149.66)
		(width 0.16)
		(layer "B.Cu")
		(net 173)
	)
	(arc
		(start 145.165 153.41)
		(mid 145.403708 152.833708)
		(end 145.98 152.595)
		(width 0.16)
		(layer "B.Cu")
		(net 173)
	)
	(arc
		(start 145.98 151.725)
		(mid 145.403708 151.486292)
		(end 145.165 150.91)
		(width 0.16)
		(layer "B.Cu")
		(net 173)
	)
	(arc
		(start 147.320077 158.077298)
		(mid 147.370455 157.955676)
		(end 147.492077 157.905298)
		(width 0.16)
		(layer "B.Cu")
		(net 173)
	)
	(arc
		(start 148.345 149.66)
		(mid 148.217591 149.352409)
		(end 147.91 149.225)
		(width 0.16)
		(layer "B.Cu")
		(net 173)
	)
	(arc
		(start 147.492077 158.335298)
		(mid 147.370455 158.28492)
		(end 147.320077 158.163298)
		(width 0.16)
		(layer "B.Cu")
		(net 173)
	)
	(arc
		(start 146.901446 155.330148)
		(mid 146.79306 155.167936)
		(end 146.755 154.976595)
		(width 0.16)
		(layer "B.Cu")
		(net 173)
	)
	(arc
		(start 147.613 157.905298)
		(mid 147.734622 157.85492)
		(end 147.785 157.733298)
		(width 0.16)
		(layer "B.Cu")
		(net 173)
	)
	(arc
		(start 147.785 156.420809)
		(mid 147.74694 156.229467)
		(end 147.638553 156.067255)
		(width 0.16)
		(layer "B.Cu")
		(net 173)
	)
	(arc
		(start 145.165 150.91)
		(mid 145.403708 150.333708)
		(end 145.98 150.095)
		(width 0.16)
		(layer "B.Cu")
		(net 173)
	)
	(arc
		(start 147.785 158.507298)
		(mid 147.734622 158.385676)
		(end 147.613 158.335298)
		(width 0.16)
		(layer "B.Cu")
		(net 173)
	)
	(arc
		(start 147.320077 157.217298)
		(mid 147.370455 157.095676)
		(end 147.492077 157.045298)
		(width 0.16)
		(layer "B.Cu")
		(net 173)
	)
	(arc
		(start 145.98 154.225)
		(mid 145.403708 153.986292)
		(end 145.165 153.41)
		(width 0.16)
		(layer "B.Cu")
		(net 173)
	)
	(via
		(at 103.1 86.81)
		(size 0.45)
		(drill 0.1)
		(layers "F.Cu" "B.Cu")
		(remove_unused_layers yes)
		(keep_end_layers yes)
		(zone_layer_connections)
		(teardrops
			(best_length_ratio 0.4)
			(max_length 1)
			(best_width_ratio 0.9)
			(max_width 2)
			(curved_edges yes)
			(filter_ratio 0.9)
			(enabled yes)
			(allow_two_segments yes)
			(prefer_zone_connections yes)
		)
		(net 176)
	)
	(segment
		(start 100.8 86.81)
		(end 103.1 86.81)
		(width 0.2)
		(layer "B.Cu")
		(net 176)
	)
	(segment
		(start 100.58 85.46)
		(end 100.58 86.59)
		(width 0.2)
		(layer "B.Cu")
		(net 176)
	)
	(segment
		(start 100.58 86.59)
		(end 100.8 86.81)
		(width 0.2)
		(layer "B.Cu")
		(net 176)
	)
	(via
		(at 101.6 83.085)
		(size 0.45)
		(drill 0.1)
		(layers "F.Cu" "B.Cu")
		(remove_unused_layers yes)
		(keep_end_layers yes)
		(zone_layer_connections)
		(teardrops
			(best_length_ratio 0.4)
			(max_length 1)
			(best_width_ratio 0.9)
			(max_width 2)
			(curved_edges yes)
			(filter_ratio 0.9)
			(enabled yes)
			(allow_two_segments yes)
			(prefer_zone_connections yes)
		)
		(net 182)
	)
	(segment
		(start 100.58 84.46)
		(end 100.58 83.43)
		(width 0.2)
		(layer "B.Cu")
		(net 182)
	)
	(segment
		(start 100.925 83.085)
		(end 101.6 83.085)
		(width 0.2)
		(layer "B.Cu")
		(net 182)
	)
	(segment
		(start 100.58 83.43)
		(end 100.925 83.085)
		(width 0.2)
		(layer "B.Cu")
		(net 182)
	)
	(segment
		(start 96.502 150.7)
		(end 96.502 150.287499)
		(width 0.202)
		(layer "F.Cu")
		(net 186)
	)
	(segment
		(start 96.502 150.287499)
		(end 96.5575 150.231999)
		(width 0.202)
		(layer "F.Cu")
		(net 186)
	)
	(segment
		(start 97.104786 148.800149)
		(end 97.104786 148.624786)
		(width 0.202)
		(layer "F.Cu")
		(net 186)
	)
	(segment
		(start 98.906 166.0495)
		(end 99.03 166.1735)
		(width 0.202)
		(layer "F.Cu")
		(net 186)
	)
	(segment
		(start 96.502 151.884501)
		(end 96.5575 151.940001)
		(width 0.202)
		(layer "F.Cu")
		(net 186)
	)
	(segment
		(start 96.5575 150.231999)
		(end 96.5575 149.347435)
		(width 0.202)
		(layer "F.Cu")
		(net 186)
	)
	(segment
		(start 96.5575 151.940001)
		(end 96.5575 157.297434)
		(width 0.202)
		(layer "F.Cu")
		(net 186)
	)
	(segment
		(start 96.502 151.472)
		(end 96.502 151.884501)
		(width 0.202)
		(layer "F.Cu")
		(net 186)
	)
	(segment
		(start 95.9855 164.280566)
		(end 97.754434 166.0495)
		(width 0.202)
		(layer "F.Cu")
		(net 186)
	)
	(segment
		(start 97.754434 166.0495)
		(end 98.906 166.0495)
		(width 0.202)
		(layer "F.Cu")
		(net 186)
	)
	(segment
		(start 96.502 150.7)
		(end 96.502 151.472)
		(width 0.202)
		(layer "F.Cu")
		(net 186)
	)
	(segment
		(start 95.9855 157.869434)
		(end 95.9855 164.280566)
		(width 0.202)
		(layer "F.Cu")
		(net 186)
	)
	(segment
		(start 96.5575 157.297434)
		(end 95.9855 157.869434)
		(width 0.202)
		(layer "F.Cu")
		(net 186)
	)
	(segment
		(start 96.5575 149.347435)
		(end 97.104786 148.800149)
		(width 0.202)
		(layer "F.Cu")
		(net 186)
	)
	(via
		(at 99.03 166.1735)
		(size 0.45)
		(drill 0.1)
		(layers "F.Cu" "B.Cu")
		(teardrops
			(best_length_ratio 0.4)
			(max_length 1)
			(best_width_ratio 0.9)
			(max_width 2)
			(curved_edges yes)
			(filter_ratio 0.9)
			(enabled yes)
			(allow_two_segments yes)
			(prefer_zone_connections yes)
		)
		(net 186)
	)
	(via
		(at 97.104786 148.624786)
		(size 0.45)
		(drill 0.1)
		(layers "F.Cu" "B.Cu")
		(teardrops
			(best_length_ratio 0.4)
			(max_length 1)
			(best_width_ratio 0.9)
			(max_width 2)
			(curved_edges yes)
			(filter_ratio 0.9)
			(enabled yes)
			(allow_two_segments yes)
			(prefer_zone_connections yes)
		)
		(net 186)
	)
	(segment
		(start 100.275 166.105)
		(end 99.975 166.105)
		(width 0.202)
		(layer "B.Cu")
		(net 186)
	)
	(segment
		(start 99.9195 166.0495)
		(end 99.154 166.0495)
		(width 0.202)
		(layer "B.Cu")
		(net 186)
	)
	(segment
		(start 97.4245 144.280566)
		(end 97.4245 146.380566)
		(width 0.202)
		(layer "B.Cu")
		(net 186)
	)
	(segment
		(start 193.812474 133.257388)
		(end 192.917544 132.362458)
		(width 0.202)
		(layer "B.Cu")
		(net 186)
	)
	(segment
		(start 97.104786 148.800149)
		(end 97.104786 148.624786)
		(width 0.202)
		(layer "B.Cu")
		(net 186)
	)
	(segment
		(start 99.975 166.105)
		(end 99.9195 166.0495)
		(width 0.202)
		(layer "B.Cu")
		(net 186)
	)
	(segment
		(start 192.917544 132.362456)
		(end 190.649588 130.0945)
		(width 0.202)
		(layer "B.Cu")
		(net 186)
	)
	(segment
		(start 192.917544 132.362458)
		(end 192.917544 132.362456)
		(width 0.202)
		(layer "B.Cu")
		(net 186)
	)
	(segment
		(start 193.812474 133.335876)
		(end 193.812474 133.257388)
		(width 0.202)
		(layer "B.Cu")
		(net 186)
	)
	(segment
		(start 96.395109 147.409958)
		(end 96.0245 147.780566)
		(width 0.202)
		(layer "B.Cu")
		(net 186)
	)
	(segment
		(start 160.649434 117.1445)
		(end 118.110566 117.1445)
		(width 0.202)
		(layer "B.Cu")
		(net 186)
	)
	(segment
		(start 96.270208 148.865142)
		(end 96.410566 149.0055)
		(width 0.202)
		(layer "B.Cu")
		(net 186)
	)
	(segment
		(start 190.649588 130.0945)
		(end 173.599434 130.0945)
		(width 0.202)
		(layer "B.Cu")
		(net 186)
	)
	(segment
		(start 96.0245 147.780566)
		(end 96.0245 148.619434)
		(width 0.202)
		(layer "B.Cu")
		(net 186)
	)
	(segment
		(start 96.410566 149.0055)
		(end 96.899435 149.0055)
		(width 0.202)
		(layer "B.Cu")
		(net 186)
	)
	(segment
		(start 106.3745 128.880566)
		(end 106.3745 135.330566)
		(width 0.202)
		(layer "B.Cu")
		(net 186)
	)
	(segment
		(start 99.154 166.0495)
		(end 99.03 166.1735)
		(width 0.202)
		(layer "B.Cu")
		(net 186)
	)
	(segment
		(start 96.899435 149.0055)
		(end 97.104786 148.800149)
		(width 0.202)
		(layer "B.Cu")
		(net 186)
	)
	(segment
		(start 97.102215 146.985694)
		(end 97.510437 147.393916)
		(width 0.202)
		(layer "B.Cu")
		(net 186)
	)
	(segment
		(start 97.156885 147.747469)
		(end 96.748664 147.339248)
		(width 0.202)
		(layer "B.Cu")
		(net 186)
	)
	(segment
		(start 118.110566 117.1445)
		(end 106.3745 128.880566)
		(width 0.202)
		(layer "B.Cu")
		(net 186)
	)
	(segment
		(start 106.3745 135.330566)
		(end 97.4245 144.280566)
		(width 0.202)
		(layer "B.Cu")
		(net 186)
	)
	(segment
		(start 173.599434 130.0945)
		(end 160.649434 117.1445)
		(width 0.202)
		(layer "B.Cu")
		(net 186)
	)
	(segment
		(start 96.0245 148.619434)
		(end 96.270208 148.865142)
		(width 0.202)
		(layer "B.Cu")
		(net 186)
	)
	(segment
		(start 97.510438 147.676758)
		(end 97.439727 147.74747)
		(width 0.202)
		(layer "B.Cu")
		(net 186)
	)
	(segment
		(start 97.4245 146.380566)
		(end 97.102216 146.70285)
		(width 0.202)
		(layer "B.Cu")
		(net 186)
	)
	(segment
		(start 96.46582 147.339249)
		(end 96.395109 147.409958)
		(width 0.202)
		(layer "B.Cu")
		(net 186)
	)
	(arc
		(start 97.102216 146.70285)
		(mid 97.043636 146.844273)
		(end 97.102215 146.985694)
		(width 0.202)
		(layer "B.Cu")
		(net 186)
	)
	(arc
		(start 96.748664 147.339248)
		(mid 96.607242 147.28067)
		(end 96.46582 147.339249)
		(width 0.202)
		(layer "B.Cu")
		(net 186)
	)
	(arc
		(start 97.439727 147.74747)
		(mid 97.298307 147.806047)
		(end 97.156885 147.747469)
		(width 0.202)
		(layer "B.Cu")
		(net 186)
	)
	(arc
		(start 97.510437 147.393916)
		(mid 97.569016 147.535337)
		(end 97.510438 147.676758)
		(width 0.202)
		(layer "B.Cu")
		(net 186)
	)
	(segment
		(start 96.9465 150.231999)
		(end 96.9465 149.508565)
		(width 0.202)
		(layer "F.Cu")
		(net 187)
	)
	(segment
		(start 97.379851 149.075214)
		(end 97.555214 149.075214)
		(width 0.202)
		(layer "F.Cu")
		(net 187)
	)
	(segment
		(start 96.3745 158.030566)
		(end 96.3745 164.119434)
		(width 0.202)
		(layer "F.Cu")
		(net 187)
	)
	(segment
		(start 97.002 151.472)
		(end 97.002 150.7)
		(width 0.202)
		(layer "F.Cu")
		(net 187)
	)
	(segment
		(start 96.9465 154.129197)
		(end 96.9465 154.229197)
		(width 0.202)
		(layer "F.Cu")
		(net 187)
	)
	(segment
		(start 97.1465 153.429197)
		(end 97.240443 153.429197)
		(width 0.202)
		(layer "F.Cu")
		(net 187)
	)
	(segment
		(start 97.240443 153.929197)
		(end 97.1465 153.929197)
		(width 0.202)
		(layer "F.Cu")
		(net 187)
	)
	(segment
		(start 97.002 150.7)
		(end 97.002 150.287499)
		(width 0.202)
		(layer "F.Cu")
		(net 187)
	)
	(segment
		(start 96.9465 155.021618)
		(end 96.9465 157.458566)
		(width 0.202)
		(layer "F.Cu")
		(net 187)
	)
	(segment
		(start 96.9465 149.508565)
		(end 97.379851 149.075214)
		(width 0.202)
		(layer "F.Cu")
		(net 187)
	)
	(segment
		(start 98.906 165.6605)
		(end 99.03 165.5365)
		(width 0.202)
		(layer "F.Cu")
		(net 187)
	)
	(segment
		(start 96.9465 157.458566)
		(end 96.3745 158.030566)
		(width 0.202)
		(layer "F.Cu")
		(net 187)
	)
	(segment
		(start 96.9465 154.229197)
		(end 96.9465 155.021618)
		(width 0.202)
		(layer "F.Cu")
		(net 187)
	)
	(segment
		(start 97.002 151.884501)
		(end 96.9465 151.940001)
		(width 0.202)
		(layer "F.Cu")
		(net 187)
	)
	(segment
		(start 97.915566 165.6605)
		(end 98.906 165.6605)
		(width 0.202)
		(layer "F.Cu")
		(net 187)
	)
	(segment
		(start 97.002 151.472)
		(end 97.002 151.884501)
		(width 0.202)
		(layer "F.Cu")
		(net 187)
	)
	(segment
		(start 96.9465 151.940001)
		(end 96.9465 153.229197)
		(width 0.202)
		(layer "F.Cu")
		(net 187)
	)
	(segment
		(start 96.3745 164.119434)
		(end 97.915566 165.6605)
		(width 0.202)
		(layer "F.Cu")
		(net 187)
	)
	(segment
		(start 97.440443 153.629197)
		(end 97.440443 153.729197)
		(width 0.202)
		(layer "F.Cu")
		(net 187)
	)
	(segment
		(start 97.002 150.287499)
		(end 96.9465 150.231999)
		(width 0.202)
		(layer "F.Cu")
		(net 187)
	)
	(via
		(at 99.03 165.5365)
		(size 0.45)
		(drill 0.1)
		(layers "F.Cu" "B.Cu")
		(teardrops
			(best_length_ratio 0.4)
			(max_length 1)
			(best_width_ratio 0.9)
			(max_width 2)
			(curved_edges yes)
			(filter_ratio 0.9)
			(enabled yes)
			(allow_two_segments yes)
			(prefer_zone_connections yes)
		)
		(net 187)
	)
	(via
		(at 97.555214 149.075214)
		(size 0.45)
		(drill 0.1)
		(layers "F.Cu" "B.Cu")
		(teardrops
			(best_length_ratio 0.4)
			(max_length 1)
			(best_width_ratio 0.9)
			(max_width 2)
			(curved_edges yes)
			(filter_ratio 0.9)
			(enabled yes)
			(allow_two_segments yes)
			(prefer_zone_connections yes)
		)
		(net 187)
	)
	(arc
		(start 96.9465 153.229197)
		(mid 97.005079 153.370618)
		(end 97.1465 153.429197)
		(width 0.202)
		(layer "F.Cu")
		(net 187)
	)
	(arc
		(start 97.440443 153.729197)
		(mid 97.381864 153.870618)
		(end 97.240443 153.929197)
		(width 0.202)
		(layer "F.Cu")
		(net 187)
	)
	(arc
		(start 97.1465 153.929197)
		(mid 97.005079 153.987776)
		(end 96.9465 154.129197)
		(width 0.202)
		(layer "F.Cu")
		(net 187)
	)
	(arc
		(start 97.240443 153.429197)
		(mid 97.381864 153.487776)
		(end 97.440443 153.629197)
		(width 0.202)
		(layer "F.Cu")
		(net 187)
	)
	(segment
		(start 173.760566 129.7055)
		(end 190.81072 129.7055)
		(width 0.202)
		(layer "B.Cu")
		(net 187)
	)
	(segment
		(start 105.9855 128.719434)
		(end 117.949434 116.7555)
		(width 0.202)
		(layer "B.Cu")
		(net 187)
	)
	(segment
		(start 193.19261 132.08739)
		(end 193.19261 132.087394)
		(width 0.202)
		(layer "B.Cu")
		(net 187)
	)
	(segment
		(start 95.6355 148.780566)
		(end 95.6355 147.619434)
		(width 0.202)
		(layer "B.Cu")
		(net 187)
	)
	(segment
		(start 95.6355 147.619434)
		(end 97.0355 146.219434)
		(width 0.202)
		(layer "B.Cu")
		(net 187)
	)
	(segment
		(start 97.0355 144.119434)
		(end 105.9855 135.169434)
		(width 0.202)
		(layer "B.Cu")
		(net 187)
	)
	(segment
		(start 160.810566 116.7555)
		(end 173.760566 129.7055)
		(width 0.202)
		(layer "B.Cu")
		(net 187)
	)
	(segment
		(start 190.81072 129.7055)
		(end 193.19261 132.08739)
		(width 0.202)
		(layer "B.Cu")
		(net 187)
	)
	(segment
		(start 97.0355 146.219434)
		(end 97.0355 144.119434)
		(width 0.202)
		(layer "B.Cu")
		(net 187)
	)
	(segment
		(start 96.249434 149.3945)
		(end 95.6355 148.780566)
		(width 0.202)
		(layer "B.Cu")
		(net 187)
	)
	(segment
		(start 100.275 165.605)
		(end 99.975 165.605)
		(width 0.202)
		(layer "B.Cu")
		(net 187)
	)
	(segment
		(start 193.19261 132.087394)
		(end 194.087539 132.982323)
		(width 0.202)
		(layer "B.Cu")
		(net 187)
	)
	(segment
		(start 117.949434 116.7555)
		(end 160.810566 116.7555)
		(width 0.202)
		(layer "B.Cu")
		(net 187)
	)
	(segment
		(start 105.9855 135.169434)
		(end 105.9855 128.719434)
		(width 0.202)
		(layer "B.Cu")
		(net 187)
	)
	(segment
		(start 97.060565 149.3945)
		(end 96.249434 149.3945)
		(width 0.202)
		(layer "B.Cu")
		(net 187)
	)
	(segment
		(start 97.555214 149.075214)
		(end 97.379851 149.075214)
		(width 0.202)
		(layer "B.Cu")
		(net 187)
	)
	(segment
		(start 99.975 165.605)
		(end 99.9195 165.6605)
		(width 0.202)
		(layer "B.Cu")
		(net 187)
	)
	(segment
		(start 99.154 165.6605)
		(end 99.03 165.5365)
		(width 0.202)
		(layer "B.Cu")
		(net 187)
	)
	(segment
		(start 97.379851 149.075214)
		(end 97.060565 149.3945)
		(width 0.202)
		(layer "B.Cu")
		(net 187)
	)
	(segment
		(start 194.087539 132.982323)
		(end 194.166028 132.982323)
		(width 0.202)
		(layer "B.Cu")
		(net 187)
	)
	(segment
		(start 99.9195 165.6605)
		(end 99.154 165.6605)
		(width 0.202)
		(layer "B.Cu")
		(net 187)
	)
	(segment
		(start 98.599434 149.1055)
		(end 99.476 149.1055)
		(width 0.202)
		(layer "F.Cu")
		(net 188)
	)
	(segment
		(start 98.0555 151.940001)
		(end 98.0555 157.349434)
		(width 0.202)
		(layer "F.Cu")
		(net 188)
	)
	(segment
		(start 98 150.287499)
		(end 98.0555 150.231999)
		(width 0.202)
		(layer "F.Cu")
		(net 188)
	)
	(segment
		(start 97.1855 163.430566)
		(end 98.304434 164.5495)
		(width 0.202)
		(layer "F.Cu")
		(net 188)
	)
	(segment
		(start 99.476 149.1055)
		(end 99.6 148.9815)
		(width 0.202)
		(layer "F.Cu")
		(net 188)
	)
	(segment
		(start 98 151.472)
		(end 98 151.884501)
		(width 0.202)
		(layer "F.Cu")
		(net 188)
	)
	(segment
		(start 98.0555 149.649434)
		(end 98.599434 149.1055)
		(width 0.202)
		(layer "F.Cu")
		(net 188)
	)
	(segment
		(start 98.906 164.5495)
		(end 99.03 164.6735)
		(width 0.202)
		(layer "F.Cu")
		(net 188)
	)
	(segment
		(start 98 150.7)
		(end 98 150.287499)
		(width 0.202)
		(layer "F.Cu")
		(net 188)
	)
	(segment
		(start 98.304434 164.5495)
		(end 98.906 164.5495)
		(width 0.202)
		(layer "F.Cu")
		(net 188)
	)
	(segment
		(start 98 150.7)
		(end 98 151.472)
		(width 0.202)
		(layer "F.Cu")
		(net 188)
	)
	(segment
		(start 97.1855 158.219434)
		(end 97.1855 163.430566)
		(width 0.202)
		(layer "F.Cu")
		(net 188)
	)
	(segment
		(start 98 151.884501)
		(end 98.0555 151.940001)
		(width 0.202)
		(layer "F.Cu")
		(net 188)
	)
	(segment
		(start 98.0555 157.349434)
		(end 97.1855 158.219434)
		(width 0.202)
		(layer "F.Cu")
		(net 188)
	)
	(segment
		(start 98.0555 150.231999)
		(end 98.0555 149.649434)
		(width 0.202)
		(layer "F.Cu")
		(net 188)
	)
	(via
		(at 99.6 148.9815)
		(size 0.45)
		(drill 0.1)
		(layers "F.Cu" "B.Cu")
		(teardrops
			(best_length_ratio 0.4)
			(max_length 1)
			(best_width_ratio 0.9)
			(max_width 2)
			(curved_edges yes)
			(filter_ratio 0.9)
			(enabled yes)
			(allow_two_segments yes)
			(prefer_zone_connections yes)
		)
		(net 188)
	)
	(via
		(at 99.03 164.6735)
		(size 0.45)
		(drill 0.1)
		(layers "F.Cu" "B.Cu")
		(teardrops
			(best_length_ratio 0.4)
			(max_length 1)
			(best_width_ratio 0.9)
			(max_width 2)
			(curved_edges yes)
			(filter_ratio 0.9)
			(enabled yes)
			(allow_two_segments yes)
			(prefer_zone_connections yes)
		)
		(net 188)
	)
	(segment
		(start 99.9195 164.5495)
		(end 99.154 164.5495)
		(width 0.202)
		(layer "B.Cu")
		(net 188)
	)
	(segment
		(start 98.7945 148.515)
		(end 98.7945 148.819434)
		(width 0.202)
		(layer "B.Cu")
		(net 188)
	)
	(segment
		(start 99.0025 147.683)
		(end 99.248438 147.683)
		(width 0.202)
		(layer "B.Cu")
		(net 188)
	)
	(segment
		(start 98.7945 148.411)
		(end 98.7945 148.515)
		(width 0.202)
		(layer "B.Cu")
		(net 188)
	)
	(segment
		(start 107.4945 130.380566)
		(end 107.4945 138.480566)
		(width 0.202)
		(layer "B.Cu")
		(net 188)
	)
	(segment
		(start 107.4945 138.480566)
		(end 98.7945 147.180566)
		(width 0.202)
		(layer "B.Cu")
		(net 188)
	)
	(segment
		(start 189.928266 131.4945)
		(end 172.719434 131.4945)
		(width 0.202)
		(layer "B.Cu")
		(net 188)
	)
	(segment
		(start 99.154 164.5495)
		(end 99.03 164.6735)
		(width 0.202)
		(layer "B.Cu")
		(net 188)
	)
	(segment
		(start 99.248438 148.203)
		(end 99.0025 148.203)
		(width 0.202)
		(layer "B.Cu")
		(net 188)
	)
	(segment
		(start 119.080566 118.7945)
		(end 107.4945 130.380566)
		(width 0.202)
		(layer "B.Cu")
		(net 188)
	)
	(segment
		(start 98.7945 147.180566)
		(end 98.7945 147.475)
		(width 0.202)
		(layer "B.Cu")
		(net 188)
	)
	(segment
		(start 99.476 149.1055)
		(end 99.6 148.9815)
		(width 0.202)
		(layer "B.Cu")
		(net 188)
	)
	(segment
		(start 100.275 164.605)
		(end 99.975 164.605)
		(width 0.202)
		(layer "B.Cu")
		(net 188)
	)
	(segment
		(start 99.080566 149.1055)
		(end 99.476 149.1055)
		(width 0.202)
		(layer "B.Cu")
		(net 188)
	)
	(segment
		(start 98.7945 148.819434)
		(end 99.080566 149.1055)
		(width 0.202)
		(layer "B.Cu")
		(net 188)
	)
	(segment
		(start 99.975 164.605)
		(end 99.9195 164.5495)
		(width 0.202)
		(layer "B.Cu")
		(net 188)
	)
	(segment
		(start 192.751814 134.396536)
		(end 192.751814 134.318048)
		(width 0.202)
		(layer "B.Cu")
		(net 188)
	)
	(segment
		(start 172.719434 131.4945)
		(end 160.019434 118.7945)
		(width 0.202)
		(layer "B.Cu")
		(net 188)
	)
	(segment
		(start 192.751814 134.318048)
		(end 189.928266 131.4945)
		(width 0.202)
		(layer "B.Cu")
		(net 188)
	)
	(segment
		(start 99.456438 147.891)
		(end 99.456438 147.995)
		(width 0.202)
		(layer "B.Cu")
		(net 188)
	)
	(segment
		(start 160.019434 118.7945)
		(end 119.080566 118.7945)
		(width 0.202)
		(layer "B.Cu")
		(net 188)
	)
	(arc
		(start 99.456438 147.995)
		(mid 99.395516 148.142078)
		(end 99.248438 148.203)
		(width 0.202)
		(layer "B.Cu")
		(net 188)
	)
	(arc
		(start 98.7945 147.475)
		(mid 98.855422 147.622078)
		(end 99.0025 147.683)
		(width 0.202)
		(layer "B.Cu")
		(net 188)
	)
	(arc
		(start 99.0025 148.203)
		(mid 98.855422 148.263922)
		(end 98.7945 148.411)
		(width 0.202)
		(layer "B.Cu")
		(net 188)
	)
	(arc
		(start 99.248438 147.683)
		(mid 99.395516 147.743922)
		(end 99.456438 147.891)
		(width 0.202)
		(layer "B.Cu")
		(net 188)
	)
	(segment
		(start 98.4445 154.516079)
		(end 98.4445 155.335265)
		(width 0.202)
		(layer "F.Cu")
		(net 189)
	)
	(segment
		(start 98.5 151.472)
		(end 98.5 150.7)
		(width 0.202)
		(layer "F.Cu")
		(net 189)
	)
	(segment
		(start 98.732746 154.156079)
		(end 98.6845 154.156079)
		(width 0.202)
		(layer "F.Cu")
		(net 189)
	)
	(segment
		(start 98.5 150.287499)
		(end 98.4445 150.231999)
		(width 0.202)
		(layer "F.Cu")
		(net 189)
	)
	(segment
		(start 98.4445 155.335265)
		(end 98.4445 157.510566)
		(width 0.202)
		(layer "F.Cu")
		(net 189)
	)
	(segment
		(start 99.476 149.4945)
		(end 99.6 149.6185)
		(width 0.202)
		(layer "F.Cu")
		(net 189)
	)
	(segment
		(start 98.972746 153.796079)
		(end 98.972746 153.916079)
		(width 0.202)
		(layer "F.Cu")
		(net 189)
	)
	(segment
		(start 98.4445 154.396079)
		(end 98.4445 154.516079)
		(width 0.202)
		(layer "F.Cu")
		(net 189)
	)
	(segment
		(start 98.5 151.884501)
		(end 98.4445 151.940001)
		(width 0.202)
		(layer "F.Cu")
		(net 189)
	)
	(segment
		(start 97.5745 158.380566)
		(end 97.5745 163.269434)
		(width 0.202)
		(layer "F.Cu")
		(net 189)
	)
	(segment
		(start 98.5 150.7)
		(end 98.5 150.287499)
		(width 0.202)
		(layer "F.Cu")
		(net 189)
	)
	(segment
		(start 98.6845 153.556079)
		(end 98.732746 153.556079)
		(width 0.202)
		(layer "F.Cu")
		(net 189)
	)
	(segment
		(start 98.4445 149.810566)
		(end 98.760566 149.4945)
		(width 0.202)
		(layer "F.Cu")
		(net 189)
	)
	(segment
		(start 97.5745 163.269434)
		(end 98.465566 164.1605)
		(width 0.202)
		(layer "F.Cu")
		(net 189)
	)
	(segment
		(start 98.4445 151.940001)
		(end 98.4445 153.316079)
		(width 0.202)
		(layer "F.Cu")
		(net 189)
	)
	(segment
		(start 98.465566 164.1605)
		(end 98.906 164.1605)
		(width 0.202)
		(layer "F.Cu")
		(net 189)
	)
	(segment
		(start 98.760566 149.4945)
		(end 99.476 149.4945)
		(width 0.202)
		(layer "F.Cu")
		(net 189)
	)
	(segment
		(start 98.4445 157.510566)
		(end 97.5745 158.380566)
		(width 0.202)
		(layer "F.Cu")
		(net 189)
	)
	(segment
		(start 98.4445 150.231999)
		(end 98.4445 149.810566)
		(width 0.202)
		(layer "F.Cu")
		(net 189)
	)
	(segment
		(start 98.906 164.1605)
		(end 99.03 164.0365)
		(width 0.202)
		(layer "F.Cu")
		(net 189)
	)
	(segment
		(start 98.5 151.472)
		(end 98.5 151.884501)
		(width 0.202)
		(layer "F.Cu")
		(net 189)
	)
	(via
		(at 99.03 164.0365)
		(size 0.45)
		(drill 0.1)
		(layers "F.Cu" "B.Cu")
		(teardrops
			(best_length_ratio 0.4)
			(max_length 1)
			(best_width_ratio 0.9)
			(max_width 2)
			(curved_edges yes)
			(filter_ratio 0.9)
			(enabled yes)
			(allow_two_segments yes)
			(prefer_zone_connections yes)
		)
		(net 189)
	)
	(via
		(at 99.6 149.6185)
		(size 0.45)
		(drill 0.1)
		(layers "F.Cu" "B.Cu")
		(teardrops
			(best_length_ratio 0.4)
			(max_length 1)
			(best_width_ratio 0.9)
			(max_width 2)
			(curved_edges yes)
			(filter_ratio 0.9)
			(enabled yes)
			(allow_two_segments yes)
			(prefer_zone_connections yes)
		)
		(net 189)
	)
	(arc
		(start 98.732746 153.556079)
		(mid 98.902452 153.626373)
		(end 98.972746 153.796079)
		(width 0.202)
		(layer "F.Cu")
		(net 189)
	)
	(arc
		(start 98.972746 153.916079)
		(mid 98.902452 154.085785)
		(end 98.732746 154.156079)
		(width 0.202)
		(layer "F.Cu")
		(net 189)
	)
	(arc
		(start 98.4445 153.316079)
		(mid 98.514794 153.485785)
		(end 98.6845 153.556079)
		(width 0.202)
		(layer "F.Cu")
		(net 189)
	)
	(arc
		(start 98.6845 154.156079)
		(mid 98.514794 154.226373)
		(end 98.4445 154.396079)
		(width 0.202)
		(layer "F.Cu")
		(net 189)
	)
	(segment
		(start 99.975 164.105)
		(end 99.9195 164.1605)
		(width 0.202)
		(layer "B.Cu")
		(net 189)
	)
	(segment
		(start 118.919434 118.4055)
		(end 160.180566 118.4055)
		(width 0.202)
		(layer "B.Cu")
		(net 189)
	)
	(segment
		(start 160.180566 118.4055)
		(end 172.880566 131.1055)
		(width 0.202)
		(layer "B.Cu")
		(net 189)
	)
	(segment
		(start 190.089396 131.1055)
		(end 193.026879 134.042983)
		(width 0.202)
		(layer "B.Cu")
		(net 189)
	)
	(segment
		(start 107.1055 138.319434)
		(end 107.1055 130.219434)
		(width 0.202)
		(layer "B.Cu")
		(net 189)
	)
	(segment
		(start 99.154 164.1605)
		(end 99.03 164.0365)
		(width 0.202)
		(layer "B.Cu")
		(net 189)
	)
	(segment
		(start 99.6 149.6185)
		(end 99.476 149.4945)
		(width 0.202)
		(layer "B.Cu")
		(net 189)
	)
	(segment
		(start 98.919434 149.4945)
		(end 98.4055 148.980566)
		(width 0.202)
		(layer "B.Cu")
		(net 189)
	)
	(segment
		(start 98.4055 147.019434)
		(end 107.1055 138.319434)
		(width 0.202)
		(layer "B.Cu")
		(net 189)
	)
	(segment
		(start 99.476 149.4945)
		(end 98.919434 149.4945)
		(width 0.202)
		(layer "B.Cu")
		(net 189)
	)
	(segment
		(start 172.880566 131.1055)
		(end 190.089396 131.1055)
		(width 0.202)
		(layer "B.Cu")
		(net 189)
	)
	(segment
		(start 100.275 164.105)
		(end 99.975 164.105)
		(width 0.202)
		(layer "B.Cu")
		(net 189)
	)
	(segment
		(start 107.1055 130.219434)
		(end 118.919434 118.4055)
		(width 0.202)
		(layer "B.Cu")
		(net 189)
	)
	(segment
		(start 99.9195 164.1605)
		(end 99.154 164.1605)
		(width 0.202)
		(layer "B.Cu")
		(net 189)
	)
	(segment
		(start 98.4055 148.980566)
		(end 98.4055 147.019434)
		(width 0.202)
		(layer "B.Cu")
		(net 189)
	)
	(segment
		(start 193.026879 134.042983)
		(end 193.105368 134.042983)
		(width 0.202)
		(layer "B.Cu")
		(net 189)
	)
	(segment
		(start 110.8695 149.844434)
		(end 110.8695 143.630566)
		(width 0.202)
		(layer "F.Cu")
		(net 192)
	)
	(segment
		(start 99.152706 161.5445)
		(end 99.028706 161.6685)
		(width 0.202)
		(layer "F.Cu")
		(net 192)
	)
	(segment
		(start 111.6445 156.544434)
		(end 111.9945 156.894434)
		(width 0.202)
		(layer "F.Cu")
		(net 192)
	)
	(segment
		(start 111.7 151.813)
		(end 111.7 151.400499)
		(width 0.202)
		(layer "F.Cu")
		(net 192)
	)
	(segment
		(start 115.430566 141.3695)
		(end 121.3445 135.455566)
		(width 0.202)
		(layer "F.Cu")
		(net 192)
	)
	(segment
		(start 111.9945 156.894434)
		(end 111.9945 158.655566)
		(width 0.202)
		(layer "F.Cu")
		(net 192)
	)
	(segment
		(start 121.3445 135.455566)
		(end 121.3445 131.880566)
		(width 0.202)
		(layer "F.Cu")
		(net 192)
	)
	(segment
		(start 101.944434 163.4695)
		(end 100.019434 161.5445)
		(width 0.202)
		(layer "F.Cu")
		(net 192)
	)
	(segment
		(start 150.801 113.9695)
		(end 150.925 114.0935)
		(width 0.202)
		(layer "F.Cu")
		(net 192)
	)
	(segment
		(start 110.8695 143.630566)
		(end 113.130566 141.3695)
		(width 0.202)
		(layer "F.Cu")
		(net 192)
	)
	(segment
		(start 111.7 152.585)
		(end 111.7 152.997501)
		(width 0.202)
		(layer "F.Cu")
		(net 192)
	)
	(segment
		(start 210.4695 130.1195)
		(end 207.494 130.1195)
		(width 0.202)
		(layer "F.Cu")
		(net 192)
	)
	(segment
		(start 111.6445 150.619434)
		(end 110.8695 149.844434)
		(width 0.202)
		(layer "F.Cu")
		(net 192)
	)
	(segment
		(start 100.019434 161.5445)
		(end 99.152706 161.5445)
		(width 0.202)
		(layer "F.Cu")
		(net 192)
	)
	(segment
		(start 111.6445 151.344999)
		(end 111.6445 150.619434)
		(width 0.202)
		(layer "F.Cu")
		(net 192)
	)
	(segment
		(start 111.7 151.813)
		(end 111.7 152.585)
		(width 0.202)
		(layer "F.Cu")
		(net 192)
	)
	(segment
		(start 111.7 151.400499)
		(end 111.6445 151.344999)
		(width 0.202)
		(layer "F.Cu")
		(net 192)
	)
	(segment
		(start 207.494 130.1195)
		(end 207.37 130.2435)
		(width 0.202)
		(layer "F.Cu")
		(net 192)
	)
	(segment
		(start 107.180566 163.4695)
		(end 101.944434 163.4695)
		(width 0.202)
		(layer "F.Cu")
		(net 192)
	)
	(segment
		(start 111.9945 158.655566)
		(end 107.180566 163.4695)
		(width 0.202)
		(layer "F.Cu")
		(net 192)
	)
	(segment
		(start 111.6445 153.053001)
		(end 111.6445 156.544434)
		(width 0.202)
		(layer "F.Cu")
		(net 192)
	)
	(segment
		(start 121.3445 131.880566)
		(end 139.255566 113.9695)
		(width 0.202)
		(layer "F.Cu")
		(net 192)
	)
	(segment
		(start 111.7 152.997501)
		(end 111.6445 153.053001)
		(width 0.202)
		(layer "F.Cu")
		(net 192)
	)
	(segment
		(start 113.130566 141.3695)
		(end 115.430566 141.3695)
		(width 0.202)
		(layer "F.Cu")
		(net 192)
	)
	(segment
		(start 210.775 130.425)
		(end 210.4695 130.1195)
		(width 0.202)
		(layer "F.Cu")
		(net 192)
	)
	(segment
		(start 139.255566 113.9695)
		(end 150.801 113.9695)
		(width 0.202)
		(layer "F.Cu")
		(net 192)
	)
	(via
		(at 99.028706 161.6685)
		(size 0.45)
		(drill 0.1)
		(layers "F.Cu" "B.Cu")
		(remove_unused_layers yes)
		(keep_end_layers yes)
		(zone_layer_connections)
		(teardrops
			(best_length_ratio 0.4)
			(max_length 1)
			(best_width_ratio 0.9)
			(max_width 2)
			(curved_edges yes)
			(filter_ratio 0.9)
			(enabled yes)
			(allow_two_segments yes)
			(prefer_zone_connections yes)
		)
		(net 192)
	)
	(via
		(at 150.925 114.0935)
		(size 0.45)
		(drill 0.1)
		(layers "F.Cu" "B.Cu")
		(teardrops
			(best_length_ratio 0.4)
			(max_length 1)
			(best_width_ratio 0.9)
			(max_width 2)
			(curved_edges yes)
			(filter_ratio 0.9)
			(enabled yes)
			(allow_two_segments yes)
			(prefer_zone_connections yes)
		)
		(net 192)
	)
	(via
		(at 207.37 130.2435)
		(size 0.45)
		(drill 0.1)
		(layers "F.Cu" "B.Cu")
		(remove_unused_layers yes)
		(keep_end_layers yes)
		(zone_layer_connections)
		(teardrops
			(best_length_ratio 0.4)
			(max_length 1)
			(best_width_ratio 0.9)
			(max_width 2)
			(curved_edges yes)
			(filter_ratio 0.9)
			(enabled yes)
			(allow_two_segments yes)
			(prefer_zone_connections yes)
		)
		(net 192)
	)
	(segment
		(start 198.694434 130.1195)
		(end 207.246 130.1195)
		(width 0.202)
		(layer "B.Cu")
		(net 192)
	)
	(segment
		(start 150.925 114.0935)
		(end 151.049 113.9695)
		(width 0.202)
		(layer "B.Cu")
		(net 192)
	)
	(segment
		(start 156.130188 114.1895)
		(end 156.130188 114.260587)
		(width 0.202)
		(layer "B.Cu")
		(net 192)
	)
	(segment
		(start 189.819434 121.2445)
		(end 198.694434 130.1195)
		(width 0.202)
		(layer "B.Cu")
		(net 192)
	)
	(segment
		(start 99.028706 161.6685)
		(end 99.152706 161.5445)
		(width 0.202)
		(layer "B.Cu")
		(net 192)
	)
	(segment
		(start 151.049 113.9695)
		(end 155.910188 113.9695)
		(width 0.202)
		(layer "B.Cu")
		(net 192)
	)
	(segment
		(start 156.900188 113.9695)
		(end 157.010188 113.9695)
		(width 0.202)
		(layer "B.Cu")
		(net 192)
	)
	(segment
		(start 173.869434 121.2445)
		(end 189.819434 121.2445)
		(width 0.202)
		(layer "B.Cu")
		(net 192)
	)
	(segment
		(start 156.680188 114.260587)
		(end 156.680188 114.1895)
		(width 0.202)
		(layer "B.Cu")
		(net 192)
	)
	(segment
		(start 100.2145 161.5445)
		(end 100.275 161.605)
		(width 0.202)
		(layer "B.Cu")
		(net 192)
	)
	(segment
		(start 99.152706 161.5445)
		(end 100.2145 161.5445)
		(width 0.202)
		(layer "B.Cu")
		(net 192)
	)
	(segment
		(start 159.104214 113.9695)
		(end 166.594434 113.9695)
		(width 0.202)
		(layer "B.Cu")
		(net 192)
	)
	(segment
		(start 157.010188 113.9695)
		(end 159.104214 113.9695)
		(width 0.202)
		(layer "B.Cu")
		(net 192)
	)
	(segment
		(start 166.594434 113.9695)
		(end 173.869434 121.2445)
		(width 0.202)
		(layer "B.Cu")
		(net 192)
	)
	(segment
		(start 207.246 130.1195)
		(end 207.37 130.2435)
		(width 0.202)
		(layer "B.Cu")
		(net 192)
	)
	(segment
		(start 156.350188 114.480587)
		(end 156.460188 114.480587)
		(width 0.202)
		(layer "B.Cu")
		(net 192)
	)
	(arc
		(start 156.460188 114.480587)
		(mid 156.615751 114.41615)
		(end 156.680188 114.260587)
		(width 0.202)
		(layer "B.Cu")
		(net 192)
	)
	(arc
		(start 156.680188 114.1895)
		(mid 156.744625 114.033937)
		(end 156.900188 113.9695)
		(width 0.202)
		(layer "B.Cu")
		(net 192)
	)
	(arc
		(start 155.910188 113.9695)
		(mid 156.065751 114.033937)
		(end 156.130188 114.1895)
		(width 0.202)
		(layer "B.Cu")
		(net 192)
	)
	(arc
		(start 156.130188 114.260587)
		(mid 156.194625 114.41615)
		(end 156.350188 114.480587)
		(width 0.202)
		(layer "B.Cu")
		(net 192)
	)
	(segment
		(start 112.969434 140.9805)
		(end 115.269434 140.9805)
		(width 0.202)
		(layer "F.Cu")
		(net 193)
	)
	(segment
		(start 111.2555 150.780566)
		(end 110.4805 150.005566)
		(width 0.202)
		(layer "F.Cu")
		(net 193)
	)
	(segment
		(start 120.9555 131.719434)
		(end 139.094434 113.5805)
		(width 0.202)
		(layer "F.Cu")
		(net 193)
	)
	(segment
		(start 139.094434 113.5805)
		(end 150.801 113.5805)
		(width 0.202)
		(layer "F.Cu")
		(net 193)
	)
	(segment
		(start 111.2555 153.053001)
		(end 111.2 152.997501)
		(width 0.202)
		(layer "F.Cu")
		(net 193)
	)
	(segment
		(start 111.2555 151.344999)
		(end 111.2555 150.780566)
		(width 0.202)
		(layer "F.Cu")
		(net 193)
	)
	(segment
		(start 106.576285 163.0805)
		(end 107.019434 163.0805)
		(width 0.202)
		(layer "F.Cu")
		(net 193)
	)
	(segment
		(start 102.105566 163.0805)
		(end 104.949758 163.0805)
		(width 0.202)
		(layer "F.Cu")
		(net 193)
	)
	(segment
		(start 111.6055 158.494434)
		(end 111.6055 157.055566)
		(width 0.202)
		(layer "F.Cu")
		(net 193)
	)
	(segment
		(start 105.649758 162.784549)
		(end 105.649758 162.8805)
		(width 0.202)
		(layer "F.Cu")
		(net 193)
	)
	(segment
		(start 111.2 151.813)
		(end 111.2 151.400499)
		(width 0.202)
		(layer "F.Cu")
		(net 193)
	)
	(segment
		(start 210.775 129.425)
		(end 210.4695 129.7305)
		(width 0.202)
		(layer "F.Cu")
		(net 193)
	)
	(segment
		(start 150.801 113.5805)
		(end 150.925 113.4565)
		(width 0.202)
		(layer "F.Cu")
		(net 193)
	)
	(segment
		(start 110.4805 143.469434)
		(end 112.969434 140.9805)
		(width 0.202)
		(layer "F.Cu")
		(net 193)
	)
	(segment
		(start 111.2555 156.705566)
		(end 111.2555 153.053001)
		(width 0.202)
		(layer "F.Cu")
		(net 193)
	)
	(segment
		(start 210.4695 129.7305)
		(end 207.494 129.7305)
		(width 0.202)
		(layer "F.Cu")
		(net 193)
	)
	(segment
		(start 105.349758 162.584549)
		(end 105.449758 162.584549)
		(width 0.202)
		(layer "F.Cu")
		(net 193)
	)
	(segment
		(start 207.494 129.7305)
		(end 207.37 129.6065)
		(width 0.202)
		(layer "F.Cu")
		(net 193)
	)
	(segment
		(start 105.949758 163.0805)
		(end 106.576285 163.0805)
		(width 0.202)
		(layer "F.Cu")
		(net 193)
	)
	(segment
		(start 105.149758 162.8805)
		(end 105.149758 162.784549)
		(width 0.202)
		(layer "F.Cu")
		(net 193)
	)
	(segment
		(start 115.269434 140.9805)
		(end 120.9555 135.294434)
		(width 0.202)
		(layer "F.Cu")
		(net 193)
	)
	(segment
		(start 105.849758 163.0805)
		(end 105.949758 163.0805)
		(width 0.202)
		(layer "F.Cu")
		(net 193)
	)
	(segment
		(start 111.2 152.997501)
		(end 111.2 152.585)
		(width 0.202)
		(layer "F.Cu")
		(net 193)
	)
	(segment
		(start 111.6055 157.055566)
		(end 111.2555 156.705566)
		(width 0.202)
		(layer "F.Cu")
		(net 193)
	)
	(segment
		(start 99.028706 161.0315)
		(end 99.152706 161.1555)
		(width 0.202)
		(layer "F.Cu")
		(net 193)
	)
	(segment
		(start 120.9555 135.294434)
		(end 120.9555 131.719434)
		(width 0.202)
		(layer "F.Cu")
		(net 193)
	)
	(segment
		(start 100.180566 161.1555)
		(end 102.105566 163.0805)
		(width 0.202)
		(layer "F.Cu")
		(net 193)
	)
	(segment
		(start 110.4805 150.005566)
		(end 110.4805 143.469434)
		(width 0.202)
		(layer "F.Cu")
		(net 193)
	)
	(segment
		(start 107.019434 163.0805)
		(end 111.6055 158.494434)
		(width 0.202)
		(layer "F.Cu")
		(net 193)
	)
	(segment
		(start 99.152706 161.1555)
		(end 100.180566 161.1555)
		(width 0.202)
		(layer "F.Cu")
		(net 193)
	)
	(segment
		(start 111.2 151.400499)
		(end 111.2555 151.344999)
		(width 0.202)
		(layer "F.Cu")
		(net 193)
	)
	(segment
		(start 111.2 151.813)
		(end 111.2 152.585)
		(width 0.202)
		(layer "F.Cu")
		(net 193)
	)
	(via
		(at 99.028706 161.0315)
		(size 0.45)
		(drill 0.1)
		(layers "F.Cu" "B.Cu")
		(remove_unused_layers yes)
		(keep_end_layers yes)
		(zone_layer_connections)
		(teardrops
			(best_length_ratio 0.4)
			(max_length 1)
			(best_width_ratio 0.9)
			(max_width 2)
			(curved_edges yes)
			(filter_ratio 0.9)
			(enabled yes)
			(allow_two_segments yes)
			(prefer_zone_connections yes)
		)
		(net 193)
	)
	(via
		(at 150.925 113.4565)
		(size 0.45)
		(drill 0.1)
		(layers "F.Cu" "B.Cu")
		(teardrops
			(best_length_ratio 0.4)
			(max_length 1)
			(best_width_ratio 0.9)
			(max_width 2)
			(curved_edges yes)
			(filter_ratio 0.9)
			(enabled yes)
			(allow_two_segments yes)
			(prefer_zone_connections yes)
		)
		(net 193)
	)
	(via
		(at 207.37 129.6065)
		(size 0.45)
		(drill 0.1)
		(layers "F.Cu" "B.Cu")
		(remove_unused_layers yes)
		(keep_end_layers yes)
		(zone_layer_connections)
		(teardrops
			(best_length_ratio 0.4)
			(max_length 1)
			(best_width_ratio 0.9)
			(max_width 2)
			(curved_edges yes)
			(filter_ratio 0.9)
			(enabled yes)
			(allow_two_segments yes)
			(prefer_zone_connections yes)
		)
		(net 193)
	)
	(arc
		(start 105.449758 162.584549)
		(mid 105.591179 162.643128)
		(end 105.649758 162.784549)
		(width 0.202)
		(layer "F.Cu")
		(net 193)
	)
	(arc
		(start 105.649758 162.8805)
		(mid 105.708337 163.021921)
		(end 105.849758 163.0805)
		(width 0.202)
		(layer "F.Cu")
		(net 193)
	)
	(arc
		(start 104.949758 163.0805)
		(mid 105.091179 163.021921)
		(end 105.149758 162.8805)
		(width 0.202)
		(layer "F.Cu")
		(net 193)
	)
	(arc
		(start 105.149758 162.784549)
		(mid 105.208337 162.643128)
		(end 105.349758 162.584549)
		(width 0.202)
		(layer "F.Cu")
		(net 193)
	)
	(segment
		(start 166.755566 113.5805)
		(end 151.049 113.5805)
		(width 0.202)
		(layer "B.Cu")
		(net 193)
	)
	(segment
		(start 198.855566 129.7305)
		(end 189.980566 120.8555)
		(width 0.202)
		(layer "B.Cu")
		(net 193)
	)
	(segment
		(start 189.980566 120.8555)
		(end 174.030566 120.8555)
		(width 0.202)
		(layer "B.Cu")
		(net 193)
	)
	(segment
		(start 207.246 129.7305)
		(end 198.855566 129.7305)
		(width 0.202)
		(layer "B.Cu")
		(net 193)
	)
	(segment
		(start 151.049 113.5805)
		(end 150.925 113.4565)
		(width 0.202)
		(layer "B.Cu")
		(net 193)
	)
	(segment
		(start 100.2245 161.1555)
		(end 100.275 161.105)
		(width 0.202)
		(layer "B.Cu")
		(net 193)
	)
	(segment
		(start 174.030566 120.8555)
		(end 166.755566 113.5805)
		(width 0.202)
		(layer "B.Cu")
		(net 193)
	)
	(segment
		(start 99.152706 161.1555)
		(end 100.2245 161.1555)
		(width 0.202)
		(layer "B.Cu")
		(net 193)
	)
	(segment
		(start 207.37 129.6065)
		(end 207.246 129.7305)
		(width 0.202)
		(layer "B.Cu")
		(net 193)
	)
	(segment
		(start 99.028706 161.0315)
		(end 99.152706 161.1555)
		(width 0.202)
		(layer "B.Cu")
		(net 193)
	)
	(segment
		(start 100.544434 160.5945)
		(end 99.994434 160.0445)
		(width 0.202)
		(layer "F.Cu")
		(net 194)
	)
	(segment
		(start 108.880566 153.5055)
		(end 109.455566 153.5055)
		(width 0.202)
		(layer "F.Cu")
		(net 194)
	)
	(segment
		(start 106.880566 160.5945)
		(end 100.544434 160.5945)
		(width 0.202)
		(layer "F.Cu")
		(net 194)
	)
	(segment
		(start 110.1945 154.244434)
		(end 110.1945 157.280566)
		(width 0.202)
		(layer "F.Cu")
		(net 194)
	)
	(segment
		(start 108.6 151.400499)
		(end 108.5445 151.344999)
		(width 0.202)
		(layer "F.Cu")
		(net 194)
	)
	(segment
		(start 108.6 152.585)
		(end 108.6 152.997501)
		(width 0.202)
		(layer "F.Cu")
		(net 194)
	)
	(segment
		(start 108.6 152.997501)
		(end 108.5445 153.053001)
		(width 0.202)
		(layer "F.Cu")
		(net 194)
	)
	(segment
		(start 108.5445 153.053001)
		(end 108.5445 153.169434)
		(width 0.202)
		(layer "F.Cu")
		(net 194)
	)
	(segment
		(start 108.5445 153.169434)
		(end 108.880566 153.5055)
		(width 0.202)
		(layer "F.Cu")
		(net 194)
	)
	(segment
		(start 109.2945 148.924)
		(end 109.4185 148.8)
		(width 0.202)
		(layer "F.Cu")
		(net 194)
	)
	(segment
		(start 108.5445 151.344999)
		(end 108.5445 150.630566)
		(width 0.202)
		(layer "F.Cu")
		(net 194)
	)
	(segment
		(start 99.149 160.0445)
		(end 99.025 160.1685)
		(width 0.202)
		(layer "F.Cu")
		(net 194)
	)
	(segment
		(start 110.1945 157.280566)
		(end 106.880566 160.5945)
		(width 0.202)
		(layer "F.Cu")
		(net 194)
	)
	(segment
		(start 109.2945 149.880566)
		(end 109.2945 148.924)
		(width 0.202)
		(layer "F.Cu")
		(net 194)
	)
	(segment
		(start 108.6 151.813)
		(end 108.6 151.400499)
		(width 0.202)
		(layer "F.Cu")
		(net 194)
	)
	(segment
		(start 99.994434 160.0445)
		(end 99.149 160.0445)
		(width 0.202)
		(layer "F.Cu")
		(net 194)
	)
	(segment
		(start 108.6 152.585)
		(end 108.6 151.813)
		(width 0.202)
		(layer "F.Cu")
		(net 194)
	)
	(segment
		(start 109.455566 153.5055)
		(end 110.1945 154.244434)
		(width 0.202)
		(layer "F.Cu")
		(net 194)
	)
	(segment
		(start 108.5445 150.630566)
		(end 109.2945 149.880566)
		(width 0.202)
		(layer "F.Cu")
		(net 194)
	)
	(via
		(at 99.025 160.1685)
		(size 0.45)
		(drill 0.1)
		(layers "F.Cu" "B.Cu")
		(remove_unused_layers yes)
		(keep_end_layers yes)
		(zone_layer_connections)
		(teardrops
			(best_length_ratio 0.4)
			(max_length 1)
			(best_width_ratio 0.9)
			(max_width 2)
			(curved_edges yes)
			(filter_ratio 0.9)
			(enabled yes)
			(allow_two_segments yes)
			(prefer_zone_connections yes)
		)
		(net 194)
	)
	(via
		(at 109.4185 148.8)
		(size 0.45)
		(drill 0.1)
		(layers "F.Cu" "B.Cu")
		(teardrops
			(best_length_ratio 0.4)
			(max_length 1)
			(best_width_ratio 0.9)
			(max_width 2)
			(curved_edges yes)
			(filter_ratio 0.9)
			(enabled yes)
			(allow_two_segments yes)
			(prefer_zone_connections yes)
		)
		(net 194)
	)
	(segment
		(start 109.4185 148.8)
		(end 109.2945 148.676)
		(width 0.202)
		(layer "B.Cu")
		(net 194)
	)
	(segment
		(start 189.506946 133.1945)
		(end 191.691154 135.378708)
		(width 0.202)
		(layer "B.Cu")
		(net 194)
	)
	(segment
		(start 109.2945 148.676)
		(end 109.2945 130.880566)
		(width 0.202)
		(layer "B.Cu")
		(net 194)
	)
	(segment
		(start 171.519434 133.1945)
		(end 189.506946 133.1945)
		(width 0.202)
		(layer "B.Cu")
		(net 194)
	)
	(segment
		(start 109.2945 130.880566)
		(end 119.780566 120.3945)
		(width 0.202)
		(layer "B.Cu")
		(net 194)
	)
	(segment
		(start 100.2145 160.0445)
		(end 100.275 160.105)
		(width 0.202)
		(layer "B.Cu")
		(net 194)
	)
	(segment
		(start 159.133493 121.14797)
		(end 158.985422 121.29604)
		(width 0.202)
		(layer "B.Cu")
		(net 194)
	)
	(segment
		(start 158.985422 121.635452)
		(end 159.070274 121.720304)
		(width 0.202)
		(layer "B.Cu")
		(net 194)
	)
	(segment
		(start 99.149 160.0445)
		(end 100.2145 160.0445)
		(width 0.202)
		(layer "B.Cu")
		(net 194)
	)
	(segment
		(start 99.025 160.1685)
		(end 99.149 160.0445)
		(width 0.202)
		(layer "B.Cu")
		(net 194)
	)
	(segment
		(start 159.409686 121.720304)
		(end 159.557756 121.572233)
		(width 0.202)
		(layer "B.Cu")
		(net 194)
	)
	(segment
		(start 191.691154 135.378708)
		(end 191.691154 135.457197)
		(width 0.202)
		(layer "B.Cu")
		(net 194)
	)
	(segment
		(start 159.897168 121.572233)
		(end 171.519434 133.1945)
		(width 0.202)
		(layer "B.Cu")
		(net 194)
	)
	(segment
		(start 158.719434 120.3945)
		(end 159.133493 120.808559)
		(width 0.202)
		(layer "B.Cu")
		(net 194)
	)
	(segment
		(start 119.780566 120.3945)
		(end 158.719434 120.3945)
		(width 0.202)
		(layer "B.Cu")
		(net 194)
	)
	(arc
		(start 159.133493 120.808559)
		(mid 159.203787 120.978265)
		(end 159.133493 121.14797)
		(width 0.202)
		(layer "B.Cu")
		(net 194)
	)
	(arc
		(start 159.070274 121.720304)
		(mid 159.23998 121.790599)
		(end 159.409686 121.720304)
		(width 0.202)
		(layer "B.Cu")
		(net 194)
	)
	(arc
		(start 158.985422 121.29604)
		(mid 158.915127 121.465746)
		(end 158.985422 121.635452)
		(width 0.202)
		(layer "B.Cu")
		(net 194)
	)
	(arc
		(start 159.557756 121.572233)
		(mid 159.727462 121.501938)
		(end 159.897168 121.572233)
		(width 0.202)
		(layer "B.Cu")
		(net 194)
	)
	(segment
		(start 103.690439 159.709441)
		(end 103.790439 159.709441)
		(width 0.202)
		(layer "F.Cu")
		(net 195)
	)
	(segment
		(start 108.1 151.813)
		(end 108.1 151.400499)
		(width 0.202)
		(layer "F.Cu")
		(net 195)
	)
	(segment
		(start 106.719434 160.2055)
		(end 109.8055 157.119434)
		(width 0.202)
		(layer "F.Cu")
		(net 195)
	)
	(segment
		(start 99.149 159.6555)
		(end 100.155566 159.6555)
		(width 0.202)
		(layer "F.Cu")
		(net 195)
	)
	(segment
		(start 108.1 152.997501)
		(end 108.1 152.585)
		(width 0.202)
		(layer "F.Cu")
		(net 195)
	)
	(segment
		(start 108.9055 149.719434)
		(end 108.9055 148.924)
		(width 0.202)
		(layer "F.Cu")
		(net 195)
	)
	(segment
		(start 108.1555 153.053001)
		(end 108.1 152.997501)
		(width 0.202)
		(layer "F.Cu")
		(net 195)
	)
	(segment
		(start 109.294434 153.8945)
		(end 108.719434 153.8945)
		(width 0.202)
		(layer "F.Cu")
		(net 195)
	)
	(segment
		(start 108.1555 151.344999)
		(end 108.1555 150.469434)
		(width 0.202)
		(layer "F.Cu")
		(net 195)
	)
	(segment
		(start 104.190439 160.2055)
		(end 104.290439 160.2055)
		(width 0.202)
		(layer "F.Cu")
		(net 195)
	)
	(segment
		(start 108.719434 153.8945)
		(end 108.1555 153.330566)
		(width 0.202)
		(layer "F.Cu")
		(net 195)
	)
	(segment
		(start 100.705566 160.2055)
		(end 103.290439 160.2055)
		(width 0.202)
		(layer "F.Cu")
		(net 195)
	)
	(segment
		(start 109.8055 154.405566)
		(end 109.294434 153.8945)
		(width 0.202)
		(layer "F.Cu")
		(net 195)
	)
	(segment
		(start 108.1555 150.469434)
		(end 108.9055 149.719434)
		(width 0.202)
		(layer "F.Cu")
		(net 195)
	)
	(segment
		(start 100.155566 159.6555)
		(end 100.705566 160.2055)
		(width 0.202)
		(layer "F.Cu")
		(net 195)
	)
	(segment
		(start 105.487562 160.2055)
		(end 106.719434 160.2055)
		(width 0.202)
		(layer "F.Cu")
		(net 195)
	)
	(segment
		(start 103.990439 159.909441)
		(end 103.990439 160.0055)
		(width 0.202)
		(layer "F.Cu")
		(net 195)
	)
	(segment
		(start 108.1555 153.330566)
		(end 108.1555 153.053001)
		(width 0.202)
		(layer "F.Cu")
		(net 195)
	)
	(segment
		(start 104.290439 160.2055)
		(end 105.487562 160.2055)
		(width 0.202)
		(layer "F.Cu")
		(net 195)
	)
	(segment
		(start 108.1 151.400499)
		(end 108.1555 151.344999)
		(width 0.202)
		(layer "F.Cu")
		(net 195)
	)
	(segment
		(start 109.8055 157.119434)
		(end 109.8055 154.405566)
		(width 0.202)
		(layer "F.Cu")
		(net 195)
	)
	(segment
		(start 108.1 151.813)
		(end 108.1 152.585)
		(width 0.202)
		(layer "F.Cu")
		(net 195)
	)
	(segment
		(start 103.490439 160.0055)
		(end 103.490439 159.909441)
		(width 0.202)
		(layer "F.Cu")
		(net 195)
	)
	(segment
		(start 99.025 159.5315)
		(end 99.149 159.6555)
		(width 0.202)
		(layer "F.Cu")
		(net 195)
	)
	(segment
		(start 108.9055 148.924)
		(end 108.7815 148.8)
		(width 0.202)
		(layer "F.Cu")
		(net 195)
	)
	(via
		(at 99.025 159.5315)
		(size 0.45)
		(drill 0.1)
		(layers "F.Cu" "B.Cu")
		(remove_unused_layers yes)
		(keep_end_layers yes)
		(zone_layer_connections)
		(teardrops
			(best_length_ratio 0.4)
			(max_length 1)
			(best_width_ratio 0.9)
			(max_width 2)
			(curved_edges yes)
			(filter_ratio 0.9)
			(enabled yes)
			(allow_two_segments yes)
			(prefer_zone_connections yes)
		)
		(net 195)
	)
	(via
		(at 108.7815 148.8)
		(size 0.45)
		(drill 0.1)
		(layers "F.Cu" "B.Cu")
		(teardrops
			(best_length_ratio 0.4)
			(max_length 1)
			(best_width_ratio 0.9)
			(max_width 2)
			(curved_edges yes)
			(filter_ratio 0.9)
			(enabled yes)
			(allow_two_segments yes)
			(prefer_zone_connections yes)
		)
		(net 195)
	)
	(arc
		(start 103.990439 160.0055)
		(mid 104.049018 160.146921)
		(end 104.190439 160.2055)
		(width 0.202)
		(layer "F.Cu")
		(net 195)
	)
	(arc
		(start 103.790439 159.709441)
		(mid 103.93186 159.76802)
		(end 103.990439 159.909441)
		(width 0.202)
		(layer "F.Cu")
		(net 195)
	)
	(arc
		(start 103.490439 159.909441)
		(mid 103.549018 159.76802)
		(end 103.690439 159.709441)
		(width 0.202)
		(layer "F.Cu")
		(net 195)
	)
	(arc
		(start 103.290439 160.2055)
		(mid 103.43186 160.146921)
		(end 103.490439 160.0055)
		(width 0.202)
		(layer "F.Cu")
		(net 195)
	)
	(segment
		(start 158.880566 120.0055)
		(end 171.680566 132.8055)
		(width 0.202)
		(layer "B.Cu")
		(net 195)
	)
	(segment
		(start 171.680566 132.8055)
		(end 189.668076 132.8055)
		(width 0.202)
		(layer "B.Cu")
		(net 195)
	)
	(segment
		(start 99.149 159.6555)
		(end 100.2245 159.6555)
		(width 0.202)
		(layer "B.Cu")
		(net 195)
	)
	(segment
		(start 108.9055 148.676)
		(end 108.9055 130.719434)
		(width 0.202)
		(layer "B.Cu")
		(net 195)
	)
	(segment
		(start 108.9055 130.719434)
		(end 119.619434 120.0055)
		(width 0.202)
		(layer "B.Cu")
		(net 195)
	)
	(segment
		(start 99.025 159.5315)
		(end 99.149 159.6555)
		(width 0.202)
		(layer "B.Cu")
		(net 195)
	)
	(segment
		(start 191.966219 135.103643)
		(end 192.044707 135.103643)
		(width 0.202)
		(layer "B.Cu")
		(net 195)
	)
	(segment
		(start 119.619434 120.0055)
		(end 158.880566 120.0055)
		(width 0.202)
		(layer "B.Cu")
		(net 195)
	)
	(segment
		(start 108.7815 148.8)
		(end 108.9055 148.676)
		(width 0.202)
		(layer "B.Cu")
		(net 195)
	)
	(segment
		(start 100.2245 159.6555)
		(end 100.275 159.605)
		(width 0.202)
		(layer "B.Cu")
		(net 195)
	)
	(segment
		(start 189.668076 132.8055)
		(end 191.966219 135.103643)
		(width 0.202)
		(layer "B.Cu")
		(net 195)
	)
	(segment
		(start 107.102 151.813)
		(end 107.102 151.400499)
		(width 0.202)
		(layer "F.Cu")
		(net 196)
	)
	(segment
		(start 107.0465 151.344999)
		(end 107.0465 150.924)
		(width 0.202)
		(layer "F.Cu")
		(net 196)
	)
	(segment
		(start 100.794434 159.0195)
		(end 104.805566 159.0195)
		(width 0.202)
		(layer "F.Cu")
		(net 196)
	)
	(segment
		(start 99.149 158.5445)
		(end 100.319434 158.5445)
		(width 0.202)
		(layer "F.Cu")
		(net 196)
	)
	(segment
		(start 107.102 152.997501)
		(end 107.102 152.585)
		(width 0.202)
		(layer "F.Cu")
		(net 196)
	)
	(segment
		(start 104.805566 159.0195)
		(end 107.0465 156.778566)
		(width 0.202)
		(layer "F.Cu")
		(net 196)
	)
	(segment
		(start 107.102 152.585)
		(end 107.102 151.813)
		(width 0.202)
		(layer "F.Cu")
		(net 196)
	)
	(segment
		(start 107.0465 150.924)
		(end 107.1705 150.8)
		(width 0.202)
		(layer "F.Cu")
		(net 196)
	)
	(segment
		(start 107.0465 156.778566)
		(end 107.0465 153.053001)
		(width 0.202)
		(layer "F.Cu")
		(net 196)
	)
	(segment
		(start 100.319434 158.5445)
		(end 100.794434 159.0195)
		(width 0.202)
		(layer "F.Cu")
		(net 196)
	)
	(segment
		(start 107.0465 153.053001)
		(end 107.102 152.997501)
		(width 0.202)
		(layer "F.Cu")
		(net 196)
	)
	(segment
		(start 99.025 158.6685)
		(end 99.149 158.5445)
		(width 0.202)
		(layer "F.Cu")
		(net 196)
	)
	(segment
		(start 107.102 151.400499)
		(end 107.0465 151.344999)
		(width 0.202)
		(layer "F.Cu")
		(net 196)
	)
	(via
		(at 99.025 158.6685)
		(size 0.45)
		(drill 0.1)
		(layers "F.Cu" "B.Cu")
		(remove_unused_layers yes)
		(keep_end_layers yes)
		(zone_layer_connections)
		(teardrops
			(best_length_ratio 0.4)
			(max_length 1)
			(best_width_ratio 0.9)
			(max_width 2)
			(curved_edges yes)
			(filter_ratio 0.9)
			(enabled yes)
			(allow_two_segments yes)
			(prefer_zone_connections yes)
		)
		(net 196)
	)
	(via
		(at 107.1705 150.8)
		(size 0.45)
		(drill 0.1)
		(layers "F.Cu" "B.Cu")
		(teardrops
			(best_length_ratio 0.4)
			(max_length 1)
			(best_width_ratio 0.9)
			(max_width 2)
			(curved_edges yes)
			(filter_ratio 0.9)
			(enabled yes)
			(allow_two_segments yes)
			(prefer_zone_connections yes)
		)
		(net 196)
	)
	(segment
		(start 108.29519 150.3825)
		(end 108.29519 150.651252)
		(width 0.202)
		(layer "B.Cu")
		(net 196)
	)
	(segment
		(start 108.95319 150.1945)
		(end 109.04719 150.1945)
		(width 0.202)
		(layer "B.Cu")
		(net 196)
	)
	(segment
		(start 190.630494 136.439368)
		(end 190.630494 136.517857)
		(width 0.202)
		(layer "B.Cu")
		(net 196)
	)
	(segment
		(start 120.680566 122.0945)
		(end 158.019434 122.0945)
		(width 0.202)
		(layer "B.Cu")
		(net 196)
	)
	(segment
		(start 158.019434 122.0945)
		(end 171.019434 135.0945)
		(width 0.202)
		(layer "B.Cu")
		(net 196)
	)
	(segment
		(start 110.9945 149.580566)
		(end 110.9945 131.780566)
		(width 0.202)
		(layer "B.Cu")
		(net 196)
	)
	(segment
		(start 107.1705 150.8)
		(end 107.0465 150.676)
		(width 0.202)
		(layer "B.Cu")
		(net 196)
	)
	(segment
		(start 109.04719 150.1945)
		(end 110.350638 150.1945)
		(width 0.202)
		(layer "B.Cu")
		(net 196)
	)
	(segment
		(start 99.149 158.5445)
		(end 100.2145 158.5445)
		(width 0.202)
		(layer "B.Cu")
		(net 196)
	)
	(segment
		(start 108.76519 150.651252)
		(end 108.76519 150.3825)
		(width 0.202)
		(layer "B.Cu")
		(net 196)
	)
	(segment
		(start 107.0465 150.428566)
		(end 107.280566 150.1945)
		(width 0.202)
		(layer "B.Cu")
		(net 196)
	)
	(segment
		(start 171.019434 135.0945)
		(end 189.285626 135.0945)
		(width 0.202)
		(layer "B.Cu")
		(net 196)
	)
	(segment
		(start 99.025 158.6685)
		(end 99.149 158.5445)
		(width 0.202)
		(layer "B.Cu")
		(net 196)
	)
	(segment
		(start 107.0465 150.676)
		(end 107.0465 150.428566)
		(width 0.202)
		(layer "B.Cu")
		(net 196)
	)
	(segment
		(start 107.280566 150.1945)
		(end 108.10719 150.1945)
		(width 0.202)
		(layer "B.Cu")
		(net 196)
	)
	(segment
		(start 110.9945 131.780566)
		(end 120.680566 122.0945)
		(width 0.202)
		(layer "B.Cu")
		(net 196)
	)
	(segment
		(start 110.380566 150.1945)
		(end 110.9945 149.580566)
		(width 0.202)
		(layer "B.Cu")
		(net 196)
	)
	(segment
		(start 189.285626 135.0945)
		(end 190.630494 136.439368)
		(width 0.202)
		(layer "B.Cu")
		(net 196)
	)
	(segment
		(start 110.350638 150.1945)
		(end 110.380566 150.1945)
		(width 0.202)
		(layer "B.Cu")
		(net 196)
	)
	(segment
		(start 108.48319 150.839252)
		(end 108.57719 150.839252)
		(width 0.202)
		(layer "B.Cu")
		(net 196)
	)
	(segment
		(start 100.2145 158.5445)
		(end 100.275 158.605)
		(width 0.202)
		(layer "B.Cu")
		(net 196)
	)
	(arc
		(start 108.29519 150.651252)
		(mid 108.350254 150.784188)
		(end 108.48319 150.839252)
		(width 0.202)
		(layer "B.Cu")
		(net 196)
	)
	(arc
		(start 108.10719 150.1945)
		(mid 108.240126 150.249564)
		(end 108.29519 150.3825)
		(width 0.202)
		(layer "B.Cu")
		(net 196)
	)
	(arc
		(start 108.76519 150.3825)
		(mid 108.820254 150.249564)
		(end 108.95319 150.1945)
		(width 0.202)
		(layer "B.Cu")
		(net 196)
	)
	(arc
		(start 108.57719 150.839252)
		(mid 108.710126 150.784188)
		(end 108.76519 150.651252)
		(width 0.202)
		(layer "B.Cu")
		(net 196)
	)
	(segment
		(start 106.602 152.997501)
		(end 106.602 152.585)
		(width 0.202)
		(layer "F.Cu")
		(net 197)
	)
	(segment
		(start 102.70341 158.4305)
		(end 102.70341 158.334464)
		(width 0.202)
		(layer "F.Cu")
		(net 197)
	)
	(segment
		(start 102.90341 158.134464)
		(end 103.00341 158.134464)
		(width 0.202)
		(layer "F.Cu")
		(net 197)
	)
	(segment
		(start 99.025 158.0315)
		(end 99.149 158.1555)
		(width 0.202)
		(layer "F.Cu")
		(net 197)
	)
	(segment
		(start 103.50341 158.6305)
		(end 104.644434 158.6305)
		(width 0.202)
		(layer "F.Cu")
		(net 197)
	)
	(segment
		(start 103.40341 158.6305)
		(end 103.50341 158.6305)
		(width 0.202)
		(layer "F.Cu")
		(net 197)
	)
	(segment
		(start 105.104857 158.170077)
		(end 106.6575 156.617434)
		(width 0.202)
		(layer "F.Cu")
		(net 197)
	)
	(segment
		(start 104.644434 158.6305)
		(end 105.104857 158.170077)
		(width 0.202)
		(layer "F.Cu")
		(net 197)
	)
	(segment
		(start 106.602 151.813)
		(end 106.602 151.400499)
		(width 0.202)
		(layer "F.Cu")
		(net 197)
	)
	(segment
		(start 99.149 158.1555)
		(end 100.480566 158.1555)
		(width 0.202)
		(layer "F.Cu")
		(net 197)
	)
	(segment
		(start 100.480566 158.1555)
		(end 100.955566 158.6305)
		(width 0.202)
		(layer "F.Cu")
		(net 197)
	)
	(segment
		(start 106.6575 156.617434)
		(end 106.6575 153.053001)
		(width 0.202)
		(layer "F.Cu")
		(net 197)
	)
	(segment
		(start 106.6575 150.924)
		(end 106.5335 150.8)
		(width 0.202)
		(layer "F.Cu")
		(net 197)
	)
	(segment
		(start 106.6575 151.344999)
		(end 106.6575 150.924)
		(width 0.202)
		(layer "F.Cu")
		(net 197)
	)
	(segment
		(start 103.20341 158.334464)
		(end 103.20341 158.4305)
		(width 0.202)
		(layer "F.Cu")
		(net 197)
	)
	(segment
		(start 106.602 151.813)
		(end 106.602 152.585)
		(width 0.202)
		(layer "F.Cu")
		(net 197)
	)
	(segment
		(start 106.602 151.400499)
		(end 106.6575 151.344999)
		(width 0.202)
		(layer "F.Cu")
		(net 197)
	)
	(segment
		(start 106.6575 153.053001)
		(end 106.602 152.997501)
		(width 0.202)
		(layer "F.Cu")
		(net 197)
	)
	(segment
		(start 100.955566 158.6305)
		(end 102.50341 158.6305)
		(width 0.202)
		(layer "F.Cu")
		(net 197)
	)
	(via
		(at 106.5335 150.8)
		(size 0.45)
		(drill 0.1)
		(layers "F.Cu" "B.Cu")
		(teardrops
			(best_length_ratio 0.4)
			(max_length 1)
			(best_width_ratio 0.9)
			(max_width 2)
			(curved_edges yes)
			(filter_ratio 0.9)
			(enabled yes)
			(allow_two_segments yes)
			(prefer_zone_connections yes)
		)
		(net 197)
	)
	(via
		(at 99.025 158.0315)
		(size 0.45)
		(drill 0.1)
		(layers "F.Cu" "B.Cu")
		(remove_unused_layers yes)
		(keep_end_layers yes)
		(zone_layer_connections)
		(teardrops
			(best_length_ratio 0.4)
			(max_length 1)
			(best_width_ratio 0.9)
			(max_width 2)
			(curved_edges yes)
			(filter_ratio 0.9)
			(enabled yes)
			(allow_two_segments yes)
			(prefer_zone_connections yes)
		)
		(net 197)
	)
	(arc
		(start 103.20341 158.4305)
		(mid 103.261989 158.571921)
		(end 103.40341 158.6305)
		(width 0.202)
		(layer "F.Cu")
		(net 197)
	)
	(arc
		(start 102.70341 158.334464)
		(mid 102.761989 158.193043)
		(end 102.90341 158.134464)
		(width 0.202)
		(layer "F.Cu")
		(net 197)
	)
	(arc
		(start 103.00341 158.134464)
		(mid 103.144831 158.193043)
		(end 103.20341 158.334464)
		(width 0.202)
		(layer "F.Cu")
		(net 197)
	)
	(arc
		(start 102.50341 158.6305)
		(mid 102.644831 158.571921)
		(end 102.70341 158.4305)
		(width 0.202)
		(layer "F.Cu")
		(net 197)
	)
	(segment
		(start 106.6575 150.267434)
		(end 107.119434 149.8055)
		(width 0.202)
		(layer "B.Cu")
		(net 197)
	)
	(segment
		(start 190.905559 136.164303)
		(end 190.984047 136.164303)
		(width 0.202)
		(layer "B.Cu")
		(net 197)
	)
	(segment
		(start 99.025 158.0315)
		(end 99.149 158.1555)
		(width 0.202)
		(layer "B.Cu")
		(net 197)
	)
	(segment
		(start 99.149 158.1555)
		(end 100.2245 158.1555)
		(width 0.202)
		(layer "B.Cu")
		(net 197)
	)
	(segment
		(start 110.6055 149.419434)
		(end 110.6055 131.619434)
		(width 0.202)
		(layer "B.Cu")
		(net 197)
	)
	(segment
		(start 171.180566 134.7055)
		(end 189.446756 134.7055)
		(width 0.202)
		(layer "B.Cu")
		(net 197)
	)
	(segment
		(start 106.5335 150.8)
		(end 106.6575 150.676)
		(width 0.202)
		(layer "B.Cu")
		(net 197)
	)
	(segment
		(start 120.519434 121.7055)
		(end 158.180566 121.7055)
		(width 0.202)
		(layer "B.Cu")
		(net 197)
	)
	(segment
		(start 110.219434 149.8055)
		(end 110.6055 149.419434)
		(width 0.202)
		(layer "B.Cu")
		(net 197)
	)
	(segment
		(start 100.2245 158.1555)
		(end 100.275 158.105)
		(width 0.202)
		(layer "B.Cu")
		(net 197)
	)
	(segment
		(start 106.6575 150.676)
		(end 106.6575 150.267434)
		(width 0.202)
		(layer "B.Cu")
		(net 197)
	)
	(segment
		(start 189.446756 134.7055)
		(end 190.905559 136.164303)
		(width 0.202)
		(layer "B.Cu")
		(net 197)
	)
	(segment
		(start 107.119434 149.8055)
		(end 110.219434 149.8055)
		(width 0.202)
		(layer "B.Cu")
		(net 197)
	)
	(segment
		(start 158.180566 121.7055)
		(end 171.180566 134.7055)
		(width 0.202)
		(layer "B.Cu")
		(net 197)
	)
	(segment
		(start 110.6055 131.619434)
		(end 120.519434 121.7055)
		(width 0.202)
		(layer "B.Cu")
		(net 197)
	)
	(segment
		(start 107.02 163.01)
		(end 106.18 163.01)
		(width 0.125)
		(layer "B.Cu")
		(net 198)
	)
	(segment
		(start 105.58 163.61)
		(end 102.49 163.61)
		(width 0.125)
		(layer "B.Cu")
		(net 198)
	)
	(segment
		(start 106.18 163.01)
		(end 105.58 163.61)
		(width 0.125)
		(layer "B.Cu")
		(net 198)
	)
	(segment
		(start 106.61 162.06)
		(end 105.56 163.11)
		(width 0.125)
		(layer "B.Cu")
		(net 199)
	)
	(segment
		(start 107.02 162.06)
		(end 106.61 162.06)
		(width 0.125)
		(layer "B.Cu")
		(net 199)
	)
	(segment
		(start 105.56 163.11)
		(end 102.49 163.11)
		(width 0.125)
		(layer "B.Cu")
		(net 199)
	)
	(via
		(at 120.35 162.56)
		(size 0.45)
		(drill 0.1)
		(layers "F.Cu" "B.Cu")
		(remove_unused_layers yes)
		(keep_end_layers yes)
		(zone_layer_connections "In5.Cu")
		(teardrops
			(best_length_ratio 0.4)
			(max_length 1)
			(best_width_ratio 0.9)
			(max_width 2)
			(curved_edges yes)
			(filter_ratio 0.9)
			(enabled yes)
			(allow_two_segments yes)
			(prefer_zone_connections yes)
		)
		(net 200)
	)
	(via
		(at 103.62 162.12)
		(size 0.45)
		(drill 0.1)
		(layers "F.Cu" "B.Cu")
		(remove_unused_layers yes)
		(keep_end_layers yes)
		(zone_layer_connections "In5.Cu")
		(teardrops
			(best_length_ratio 0.4)
			(max_length 1)
			(best_width_ratio 0.9)
			(max_width 2)
			(curved_edges yes)
			(filter_ratio 0.9)
			(enabled yes)
			(allow_two_segments yes)
			(prefer_zone_connections yes)
		)
		(net 200)
	)
	(segment
		(start 103.62 162.12)
		(end 104.360689 162.12)
		(width 0.125)
		(layer "B.Cu")
		(net 200)
	)
	(segment
		(start 120.35 162.56)
		(end 121.22 162.56)
		(width 0.125)
		(layer "B.Cu")
		(net 200)
	)
	(segment
		(start 121.22 162.56)
		(end 121.22 163.56)
		(width 0.125)
		(layer "B.Cu")
		(net 200)
	)
	(segment
		(start 103.61 162.11)
		(end 102.49 162.11)
		(width 0.125)
		(layer "B.Cu")
		(net 200)
	)
	(segment
		(start 104.380002 162.112)
		(end 105.152002 162.112)
		(width 0.125)
		(layer "B.Cu")
		(net 200)
	)
	(segment
		(start 119.6 161.81)
		(end 120.35 162.56)
		(width 0.125)
		(layer "In5.Cu")
		(net 200)
	)
	(segment
		(start 103.64 162.12)
		(end 103.95 161.81)
		(width 0.125)
		(layer "In5.Cu")
		(net 200)
	)
	(segment
		(start 103.95 161.81)
		(end 119.6 161.81)
		(width 0.125)
		(layer "In5.Cu")
		(net 200)
	)
	(via
		(at 120.35 161.56)
		(size 0.45)
		(drill 0.1)
		(layers "F.Cu" "B.Cu")
		(remove_unused_layers yes)
		(keep_end_layers yes)
		(zone_layer_connections "In5.Cu")
		(teardrops
			(best_length_ratio 0.4)
			(max_length 1)
			(best_width_ratio 0.9)
			(max_width 2)
			(curved_edges yes)
			(filter_ratio 0.9)
			(enabled yes)
			(allow_two_segments yes)
			(prefer_zone_connections yes)
		)
		(net 201)
	)
	(via
		(at 103.616022 161.545011)
		(size 0.45)
		(drill 0.1)
		(layers "F.Cu" "B.Cu")
		(remove_unused_layers yes)
		(keep_end_layers yes)
		(zone_layer_connections "In5.Cu")
		(teardrops
			(best_length_ratio 0.4)
			(max_length 1)
			(best_width_ratio 0.9)
			(max_width 2)
			(curved_edges yes)
			(filter_ratio 0.9)
			(enabled yes)
			(allow_two_segments yes)
			(prefer_zone_connections yes)
		)
		(net 201)
	)
	(segment
		(start 103.304989 161.545011)
		(end 103.616022 161.545011)
		(width 0.125)
		(layer "B.Cu")
		(net 201)
	)
	(segment
		(start 103.893011 161.545011)
		(end 103.96 161.612)
		(width 0.125)
		(layer "B.Cu")
		(net 201)
	)
	(segment
		(start 103.96 161.612)
		(end 104.380002 161.612)
		(width 0.125)
		(layer "B.Cu")
		(net 201)
	)
	(segment
		(start 121.22 161.56)
		(end 121.22 160.56)
		(width 0.125)
		(layer "B.Cu")
		(net 201)
	)
	(segment
		(start 103.616022 161.545011)
		(end 103.893011 161.545011)
		(width 0.125)
		(layer "B.Cu")
		(net 201)
	)
	(segment
		(start 103.24 161.61)
		(end 102.49 161.61)
		(width 0.125)
		(layer "B.Cu")
		(net 201)
	)
	(segment
		(start 120.35 161.56)
		(end 121.22 161.56)
		(width 0.125)
		(layer "B.Cu")
		(net 201)
	)
	(segment
		(start 103.24 161.61)
		(end 103.304989 161.545011)
		(width 0.125)
		(layer "B.Cu")
		(net 201)
	)
	(segment
		(start 104.380002 161.612)
		(end 105.152002 161.612)
		(width 0.125)
		(layer "B.Cu")
		(net 201)
	)
	(segment
		(start 103.631011 161.56)
		(end 120.35 161.56)
		(width 0.125)
		(layer "In5.Cu")
		(net 201)
	)
	(segment
		(start 103.616022 161.545011)
		(end 103.631011 161.56)
		(width 0.125)
		(layer "In5.Cu")
		(net 201)
	)
	(segment
		(start 258.670566 138.5045)
		(end 259.0945 138.080566)
		(width 0.202)
		(layer "F.Cu")
		(net 203)
	)
	(segment
		(start 220.239434 138.5045)
		(end 258.670566 138.5045)
		(width 0.202)
		(layer "F.Cu")
		(net 203)
	)
	(segment
		(start 259.0945 138.080566)
		(end 259.0945 137.2285)
		(width 0.202)
		(layer "F.Cu")
		(net 203)
	)
	(segment
		(start 259.0945 137.2285)
		(end 259.223 137.1)
		(width 0.202)
		(layer "F.Cu")
		(net 203)
	)
	(segment
		(start 216.2855 133.9305)
		(end 216.2855 134.041214)
		(width 0.202)
		(layer "F.Cu")
		(net 203)
	)
	(segment
		(start 215.98 133.625)
		(end 216.2855 133.9305)
		(width 0.202)
		(layer "F.Cu")
		(net 203)
	)
	(segment
		(start 216.645667 134.910733)
		(end 220.239434 138.5045)
		(width 0.202)
		(layer "F.Cu")
		(net 203)
	)
	(via
		(at 259.223 137.1)
		(size 0.45)
		(drill 0.1)
		(layers "F.Cu" "B.Cu")
		(teardrops
			(best_length_ratio 0.4)
			(max_length 1)
			(best_width_ratio 0.9)
			(max_width 2)
			(curved_edges yes)
			(filter_ratio 0.9)
			(enabled yes)
			(allow_two_segments yes)
			(prefer_zone_connections yes)
		)
		(net 203)
	)
	(via
		(at 312.025214 164.034786)
		(size 0.45)
		(drill 0.1)
		(layers "F.Cu" "B.Cu")
		(remove_unused_layers yes)
		(keep_end_layers yes)
		(zone_layer_connections)
		(teardrops
			(best_length_ratio 0.4)
			(max_length 1)
			(best_width_ratio 0.9)
			(max_width 2)
			(curved_edges yes)
			(filter_ratio 0.9)
			(enabled yes)
			(allow_two_segments yes)
			(prefer_zone_connections yes)
		)
		(net 203)
	)
	(arc
		(start 216.2855 134.041214)
		(mid 216.379105 134.511794)
		(end 216.645667 134.910733)
		(width 0.202)
		(layer "F.Cu")
		(net 203)
	)
	(segment
		(start 312.580565 164.7655)
		(end 314.1595 164.7655)
		(width 0.202)
		(layer "B.Cu")
		(net 203)
	)
	(segment
		(start 315.576013 164.708921)
		(end 315.681359 164.603575)
		(width 0.202)
		(layer "B.Cu")
		(net 203)
	)
	(segment
		(start 312.025214 164.034786)
		(end 312.025214 164.210149)
		(width 0.202)
		(layer "B.Cu")
		(net 203)
	)
	(segment
		(start 316.376834 164.3155)
		(end 318.0195 164.3155)
		(width 0.202)
		(layer "B.Cu")
		(net 203)
	)
	(segment
		(start 315.3425 164.7675)
		(end 315.434591 164.7675)
		(width 0.202)
		(layer "B.Cu")
		(net 203)
	)
	(segment
		(start 315.137 164.71)
		(end 314.365 164.71)
		(width 0.202)
		(layer "B.Cu")
		(net 203)
	)
	(segment
		(start 314.1595 164.7655)
		(end 314.215 164.71)
		(width 0.202)
		(layer "B.Cu")
		(net 203)
	)
	(segment
		(start 315.287 164.712)
		(end 315.3425 164.7675)
		(width 0.202)
		(layer "B.Cu")
		(net 203)
	)
	(segment
		(start 318.0195 164.3155)
		(end 318.225 164.11)
		(width 0.202)
		(layer "B.Cu")
		(net 203)
	)
	(segment
		(start 312.025214 164.210149)
		(end 312.580565 164.7655)
		(width 0.202)
		(layer "B.Cu")
		(net 203)
	)
	(arc
		(start 315.576013 164.708921)
		(mid 315.511128 164.752276)
		(end 315.434591 164.7675)
		(width 0.202)
		(layer "B.Cu")
		(net 203)
	)
	(arc
		(start 315.681359 164.603575)
		(mid 316.000446 164.390368)
		(end 316.376834 164.3155)
		(width 0.202)
		(layer "B.Cu")
		(net 203)
	)
	(segment
		(start 311.839244 164.034786)
		(end 312.025214 164.034786)
		(width 0.178)
		(layer "In5.Cu")
		(net 203)
	)
	(segment
		(start 288.127458 162.273)
		(end 310.077458 162.273)
		(width 0.178)
		(layer "In5.Cu")
		(net 203)
	)
	(segment
		(start 263.867458 138.013)
		(end 288.127458 162.273)
		(width 0.178)
		(layer "In5.Cu")
		(net 203)
	)
	(segment
		(start 310.077458 162.273)
		(end 311.839244 164.034786)
		(width 0.178)
		(layer "In5.Cu")
		(net 203)
	)
	(segment
		(start 259.087 137.522542)
		(end 259.577458 138.013)
		(width 0.178)
		(layer "In5.Cu")
		(net 203)
	)
	(segment
		(start 259.087 137.236)
		(end 259.087 137.522542)
		(width 0.178)
		(layer "In5.Cu")
		(net 203)
	)
	(segment
		(start 259.223 137.1)
		(end 259.087 137.236)
		(width 0.178)
		(layer "In5.Cu")
		(net 203)
	)
	(segment
		(start 259.577458 138.013)
		(end 263.867458 138.013)
		(width 0.178)
		(layer "In5.Cu")
		(net 203)
	)
	(segment
		(start 225.671298 147.06)
		(end 226.11 146.621298)
		(width 0.185)
		(layer "F.Cu")
		(net 204)
	)
	(segment
		(start 212.56 148.963)
		(end 212.56 147.821298)
		(width 0.185)
		(layer "F.Cu")
		(net 204)
	)
	(segment
		(start 212.56 147.821298)
		(end 213.321298 147.06)
		(width 0.185)
		(layer "F.Cu")
		(net 204)
	)
	(segment
		(start 198.025 169.997501)
		(end 198.085 170.057501)
		(width 0.185)
		(layer "F.Cu")
		(net 204)
	)
	(segment
		(start 212.423 149.1)
		(end 212.56 148.963)
		(width 0.185)
		(layer "F.Cu")
		(net 204)
	)
	(segment
		(start 225.859341 145.378042)
		(end 225.671958 145.378042)
		(width 0.185)
		(layer "F.Cu")
		(net 204)
	)
	(segment
		(start 198.025 168.685)
		(end 198.025 169.997501)
		(width 0.185)
		(layer "F.Cu")
		(net 204)
	)
	(segment
		(start 226.11 146.621298)
		(end 226.11 145.628701)
		(width 0.185)
		(layer "F.Cu")
		(net 204)
	)
	(segment
		(start 213.321298 147.06)
		(end 225.671298 147.06)
		(width 0.185)
		(layer "F.Cu")
		(net 204)
	)
	(segment
		(start 226.11 145.628701)
		(end 225.859341 145.378042)
		(width 0.185)
		(layer "F.Cu")
		(net 204)
	)
	(segment
		(start 198.085 170.3675)
		(end 197.9525 170.5)
		(width 0.185)
		(layer "F.Cu")
		(net 204)
	)
	(segment
		(start 198.085 170.057501)
		(end 198.085 170.3675)
		(width 0.185)
		(layer "F.Cu")
		(net 204)
	)
	(via
		(at 212.423 149.1)
		(size 0.45)
		(drill 0.1)
		(layers "F.Cu" "B.Cu")
		(teardrops
			(best_length_ratio 0.4)
			(max_length 1)
			(best_width_ratio 0.9)
			(max_width 2)
			(curved_edges yes)
			(filter_ratio 0.9)
			(enabled yes)
			(allow_two_segments yes)
			(prefer_zone_connections yes)
		)
		(net 204)
	)
	(via
		(at 197.9525 170.5)
		(size 0.45)
		(drill 0.1)
		(layers "F.Cu" "B.Cu")
		(teardrops
			(best_length_ratio 0.4)
			(max_length 1)
			(best_width_ratio 0.9)
			(max_width 2)
			(curved_edges yes)
			(filter_ratio 0.9)
			(enabled yes)
			(allow_two_segments yes)
			(prefer_zone_connections yes)
		)
		(net 204)
	)
	(via
		(at 225.671958 145.378042)
		(size 0.45)
		(drill 0.1)
		(layers "F.Cu" "B.Cu")
		(teardrops
			(best_length_ratio 0.4)
			(max_length 1)
			(best_width_ratio 0.9)
			(max_width 2)
			(curved_edges yes)
			(filter_ratio 0.9)
			(enabled yes)
			(allow_two_segments yes)
			(prefer_zone_connections yes)
		)
		(net 204)
	)
	(segment
		(start 225.859341 145.378042)
		(end 225.671958 145.378042)
		(width 0.185)
		(layer "B.Cu")
		(net 204)
	)
	(segment
		(start 315.137 166.708)
		(end 314.365 166.708)
		(width 0.185)
		(layer "B.Cu")
		(net 204)
	)
	(segment
		(start 314.215 166.708)
		(end 314.155 166.648)
		(width 0.185)
		(layer "B.Cu")
		(net 204)
	)
	(segment
		(start 315.692015 166.706578)
		(end 315.705449 166.720014)
		(width 0.185)
		(layer "B.Cu")
		(net 204)
	)
	(segment
		(start 318.225 167.31)
		(end 318.015 167.1)
		(width 0.185)
		(layer "B.Cu")
		(net 204)
	)
	(segment
		(start 312.620702 166.648)
		(end 311.678702 167.59)
		(width 0.185)
		(layer "B.Cu")
		(net 204)
	)
	(segment
		(start 315.550594 166.648)
		(end 315.347 166.648)
		(width 0.185)
		(layer "B.Cu")
		(net 204)
	)
	(segment
		(start 318.015 167.1)
		(end 316.576663 167.1)
		(width 0.185)
		(layer "B.Cu")
		(net 204)
	)
	(segment
		(start 311.678702 167.59)
		(end 309.781298 167.59)
		(width 0.185)
		(layer "B.Cu")
		(net 204)
	)
	(segment
		(start 314.155 166.648)
		(end 312.620702 166.648)
		(width 0.185)
		(layer "B.Cu")
		(net 204)
	)
	(segment
		(start 288.821298 166.19)
		(end 273.071298 150.44)
		(width 0.185)
		(layer "B.Cu")
		(net 204)
	)
	(segment
		(start 230.921299 150.44)
		(end 225.859341 145.378042)
		(width 0.185)
		(layer "B.Cu")
		(net 204)
	)
	(segment
		(start 308.381298 166.19)
		(end 288.821298 166.19)
		(width 0.185)
		(layer "B.Cu")
		(net 204)
	)
	(segment
		(start 315.347 166.648)
		(end 315.287 166.708)
		(width 0.185)
		(layer "B.Cu")
		(net 204)
	)
	(segment
		(start 309.781298 167.59)
		(end 308.381298 166.19)
		(width 0.185)
		(layer "B.Cu")
		(net 204)
	)
	(segment
		(start 273.071298 150.44)
		(end 230.921299 150.44)
		(width 0.185)
		(layer "B.Cu")
		(net 204)
	)
	(segment
		(start 315.723029 166.737595)
		(end 315.738044 166.75261)
		(width 0.185)
		(layer "B.Cu")
		(net 204)
	)
	(segment
		(start 315.705449 166.720014)
		(end 315.723029 166.737595)
		(width 0.185)
		(layer "B.Cu")
		(net 204)
	)
	(arc
		(start 315.738044 166.75261)
		(mid 316.122845 167.009734)
		(end 316.576663 167.1)
		(width 0.185)
		(layer "B.Cu")
		(net 204)
	)
	(arc
		(start 315.692015 166.706578)
		(mid 315.62713 166.663224)
		(end 315.550594 166.648)
		(width 0.185)
		(layer "B.Cu")
		(net 204)
	)
	(segment
		(start 209.5685 161.97482)
		(end 209.5685 161.17482)
		(width 0.159)
		(layer "In5.Cu")
		(net 204)
	)
	(segment
		(start 208.2685 166.42482)
		(end 208.2685 163.27482)
		(width 0.159)
		(layer "In5.Cu")
		(net 204)
	)
	(segment
		(start 212.5685 149.2455)
		(end 212.423 149.1)
		(width 0.159)
		(layer "In5.Cu")
		(net 204)
	)
	(segment
		(start 212.5685 158.17482)
		(end 212.5685 149.2455)
		(width 0.159)
		(layer "In5.Cu")
		(net 204)
	)
	(segment
		(start 197.9525 170.5)
		(end 198.0935 170.359)
		(width 0.159)
		(layer "In5.Cu")
		(net 204)
	)
	(segment
		(start 199.02482 168.6685)
		(end 206.02482 168.6685)
		(width 0.159)
		(layer "In5.Cu")
		(net 204)
	)
	(segment
		(start 198.0935 169.59982)
		(end 199.02482 168.6685)
		(width 0.159)
		(layer "In5.Cu")
		(net 204)
	)
	(segment
		(start 208.2685 163.27482)
		(end 209.5685 161.97482)
		(width 0.159)
		(layer "In5.Cu")
		(net 204)
	)
	(segment
		(start 198.0935 170.359)
		(end 198.0935 169.59982)
		(width 0.159)
		(layer "In5.Cu")
		(net 204)
	)
	(segment
		(start 206.02482 168.6685)
		(end 208.2685 166.42482)
		(width 0.159)
		(layer "In5.Cu")
		(net 204)
	)
	(segment
		(start 209.5685 161.17482)
		(end 212.5685 158.17482)
		(width 0.159)
		(layer "In5.Cu")
		(net 204)
	)
	(segment
		(start 257.631328 137.589224)
		(end 257.511328 137.589224)
		(width 0.202)
		(layer "F.Cu")
		(net 205)
	)
	(segment
		(start 258.7055 137.2285)
		(end 258.7055 137.919434)
		(width 0.202)
		(layer "F.Cu")
		(net 205)
	)
	(segment
		(start 258.509434 138.1155)
		(end 258.111328 138.1155)
		(width 0.202)
		(layer "F.Cu")
		(net 205)
	)
	(segment
		(start 254.434441 138.1155)
		(end 220.400566 138.1155)
		(width 0.202)
		(layer "F.Cu")
		(net 205)
	)
	(segment
		(start 220.400566 138.1155)
		(end 216.923482 134.638416)
		(width 0.202)
		(layer "F.Cu")
		(net 205)
	)
	(segment
		(start 216.6745 134.03732)
		(end 216.6745 133.9305)
		(width 0.202)
		(layer "F.Cu")
		(net 205)
	)
	(segment
		(start 258.577 137.1)
		(end 258.7055 137.2285)
		(width 0.202)
		(layer "F.Cu")
		(net 205)
	)
	(segment
		(start 216.6745 133.9305)
		(end 216.98 133.625)
		(width 0.202)
		(layer "F.Cu")
		(net 205)
	)
	(segment
		(start 256.911328 138.1155)
		(end 254.434441 138.1155)
		(width 0.202)
		(layer "F.Cu")
		(net 205)
	)
	(segment
		(start 257.871328 137.8755)
		(end 257.871328 137.829224)
		(width 0.202)
		(layer "F.Cu")
		(net 205)
	)
	(segment
		(start 257.031328 138.1155)
		(end 256.911328 138.1155)
		(width 0.202)
		(layer "F.Cu")
		(net 205)
	)
	(segment
		(start 257.271328 137.829224)
		(end 257.271328 137.8755)
		(width 0.202)
		(layer "F.Cu")
		(net 205)
	)
	(segment
		(start 258.7055 137.919434)
		(end 258.509434 138.1155)
		(width 0.202)
		(layer "F.Cu")
		(net 205)
	)
	(via
		(at 258.577 137.1)
		(size 0.45)
		(drill 0.1)
		(layers "F.Cu" "B.Cu")
		(teardrops
			(best_length_ratio 0.4)
			(max_length 1)
			(best_width_ratio 0.9)
			(max_width 2)
			(curved_edges yes)
			(filter_ratio 0.9)
			(enabled yes)
			(allow_two_segments yes)
			(prefer_zone_connections yes)
		)
		(net 205)
	)
	(via
		(at 311.574786 164.485214)
		(size 0.45)
		(drill 0.1)
		(layers "F.Cu" "B.Cu")
		(remove_unused_layers yes)
		(keep_end_layers yes)
		(zone_layer_connections)
		(teardrops
			(best_length_ratio 0.4)
			(max_length 1)
			(best_width_ratio 0.9)
			(max_width 2)
			(curved_edges yes)
			(filter_ratio 0.9)
			(enabled yes)
			(allow_two_segments yes)
			(prefer_zone_connections yes)
		)
		(net 205)
	)
	(arc
		(start 257.511328 137.589224)
		(mid 257.341622 137.659518)
		(end 257.271328 137.829224)
		(width 0.202)
		(layer "F.Cu")
		(net 205)
	)
	(arc
		(start 257.271328 137.8755)
		(mid 257.201034 138.045206)
		(end 257.031328 138.1155)
		(width 0.202)
		(layer "F.Cu")
		(net 205)
	)
	(arc
		(start 257.871328 137.829224)
		(mid 257.801034 137.659518)
		(end 257.631328 137.589224)
		(width 0.202)
		(layer "F.Cu")
		(net 205)
	)
	(arc
		(start 216.923482 134.638416)
		(mid 216.739208 134.362631)
		(end 216.6745 134.03732)
		(width 0.202)
		(layer "F.Cu")
		(net 205)
	)
	(arc
		(start 258.111328 138.1155)
		(mid 257.941622 138.045206)
		(end 257.871328 137.8755)
		(width 0.202)
		(layer "F.Cu")
		(net 205)
	)
	(segment
		(start 315.287 165.212)
		(end 315.3425 165.1565)
		(width 0.202)
		(layer "B.Cu")
		(net 205)
	)
	(segment
		(start 315.850418 164.984648)
		(end 315.936467 164.898599)
		(width 0.202)
		(layer "B.Cu")
		(net 205)
	)
	(segment
		(start 311.574786 164.485214)
		(end 311.750149 164.485214)
		(width 0.202)
		(layer "B.Cu")
		(net 205)
	)
	(segment
		(start 315.3425 165.1565)
		(end 315.435532 165.1565)
		(width 0.202)
		(layer "B.Cu")
		(net 205)
	)
	(segment
		(start 311.750149 164.485214)
		(end 312.419435 165.1545)
		(width 0.202)
		(layer "B.Cu")
		(net 205)
	)
	(segment
		(start 315.137 165.21)
		(end 314.365 165.21)
		(width 0.202)
		(layer "B.Cu")
		(net 205)
	)
	(segment
		(start 312.419435 165.1545)
		(end 314.1595 165.1545)
		(width 0.202)
		(layer "B.Cu")
		(net 205)
	)
	(segment
		(start 314.1595 165.1545)
		(end 314.215 165.21)
		(width 0.202)
		(layer "B.Cu")
		(net 205)
	)
	(segment
		(start 318.0195 164.7045)
		(end 318.225 164.91)
		(width 0.202)
		(layer "B.Cu")
		(net 205)
	)
	(segment
		(start 316.405064 164.7045)
		(end 318.0195 164.7045)
		(width 0.202)
		(layer "B.Cu")
		(net 205)
	)
	(arc
		(start 315.936467 164.898599)
		(mid 316.151461 164.754945)
		(end 316.405064 164.7045)
		(width 0.202)
		(layer "B.Cu")
		(net 205)
	)
	(arc
		(start 315.850418 164.984648)
		(mid 315.660067 165.111837)
		(end 315.435532 165.1565)
		(width 0.202)
		(layer "B.Cu")
		(net 205)
	)
	(segment
		(start 258.713 137.236)
		(end 258.713 137.677458)
		(width 0.178)
		(layer "In5.Cu")
		(net 205)
	)
	(segment
		(start 258.577 137.1)
		(end 258.713 137.236)
		(width 0.178)
		(layer "In5.Cu")
		(net 205)
	)
	(segment
		(start 287.972542 162.647)
		(end 309.922542 162.647)
		(width 0.178)
		(layer "In5.Cu")
		(net 205)
	)
	(segment
		(start 311.574786 164.299244)
		(end 311.574786 164.485214)
		(width 0.178)
		(layer "In5.Cu")
		(net 205)
	)
	(segment
		(start 258.713 137.677458)
		(end 259.422542 138.387)
		(width 0.178)
		(layer "In5.Cu")
		(net 205)
	)
	(segment
		(start 309.922542 162.647)
		(end 311.574786 164.299244)
		(width 0.178)
		(layer "In5.Cu")
		(net 205)
	)
	(segment
		(start 263.712542 138.387)
		(end 287.972542 162.647)
		(width 0.178)
		(layer "In5.Cu")
		(net 205)
	)
	(segment
		(start 259.422542 138.387)
		(end 263.712542 138.387)
		(width 0.178)
		(layer "In5.Cu")
		(net 205)
	)
	(segment
		(start 198.465 170.3675)
		(end 198.5975 170.5)
		(width 0.185)
		(layer "F.Cu")
		(net 206)
	)
	(segment
		(start 212.94 148.963)
		(end 212.94 147.978702)
		(width 0.185)
		(layer "F.Cu")
		(net 206)
	)
	(segment
		(start 226.128042 145.109341)
		(end 226.128042 144.921958)
		(width 0.185)
		(layer "F.Cu")
		(net 206)
	)
	(segment
		(start 213.478702 147.44)
		(end 225.828702 147.44)
		(width 0.185)
		(layer "F.Cu")
		(net 206)
	)
	(segment
		(start 226.49 146.778702)
		(end 226.49 145.471299)
		(width 0.185)
		(layer "F.Cu")
		(net 206)
	)
	(segment
		(start 213.077 149.1)
		(end 212.94 148.963)
		(width 0.185)
		(layer "F.Cu")
		(net 206)
	)
	(segment
		(start 198.525 168.685)
		(end 198.525 169.997501)
		(width 0.185)
		(layer "F.Cu")
		(net 206)
	)
	(segment
		(start 226.49 145.471299)
		(end 226.128042 145.109341)
		(width 0.185)
		(layer "F.Cu")
		(net 206)
	)
	(segment
		(start 212.94 147.978702)
		(end 213.478702 147.44)
		(width 0.185)
		(layer "F.Cu")
		(net 206)
	)
	(segment
		(start 225.828702 147.44)
		(end 226.49 146.778702)
		(width 0.185)
		(layer "F.Cu")
		(net 206)
	)
	(segment
		(start 198.465 170.057501)
		(end 198.465 170.3675)
		(width 0.185)
		(layer "F.Cu")
		(net 206)
	)
	(segment
		(start 198.525 169.997501)
		(end 198.465 170.057501)
		(width 0.185)
		(layer "F.Cu")
		(net 206)
	)
	(via
		(at 226.128042 144.921958)
		(size 0.45)
		(drill 0.1)
		(layers "F.Cu" "B.Cu")
		(teardrops
			(best_length_ratio 0.4)
			(max_length 1)
			(best_width_ratio 0.9)
			(max_width 2)
			(curved_edges yes)
			(filter_ratio 0.9)
			(enabled yes)
			(allow_two_segments yes)
			(prefer_zone_connections yes)
		)
		(net 206)
	)
	(via
		(at 198.5975 170.5)
		(size 0.45)
		(drill 0.1)
		(layers "F.Cu" "B.Cu")
		(teardrops
			(best_length_ratio 0.4)
			(max_length 1)
			(best_width_ratio 0.9)
			(max_width 2)
			(curved_edges yes)
			(filter_ratio 0.9)
			(enabled yes)
			(allow_two_segments yes)
			(prefer_zone_connections yes)
		)
		(net 206)
	)
	(via
		(at 213.077 149.1)
		(size 0.45)
		(drill 0.1)
		(layers "F.Cu" "B.Cu")
		(teardrops
			(best_length_ratio 0.4)
			(max_length 1)
			(best_width_ratio 0.9)
			(max_width 2)
			(curved_edges yes)
			(filter_ratio 0.9)
			(enabled yes)
			(allow_two_segments yes)
			(prefer_zone_connections yes)
		)
		(net 206)
	)
	(segment
		(start 314.155 166.268)
		(end 312.463298 166.268)
		(width 0.185)
		(layer "B.Cu")
		(net 206)
	)
	(segment
		(start 312.463298 166.268)
		(end 311.521298 167.21)
		(width 0.185)
		(layer "B.Cu")
		(net 206)
	)
	(segment
		(start 315.996187 166.473346)
		(end 315.984159 166.461317)
		(width 0.185)
		(layer "B.Cu")
		(net 206)
	)
	(segment
		(start 226.128042 145.109341)
		(end 226.128042 144.921958)
		(width 0.185)
		(layer "B.Cu")
		(net 206)
	)
	(segment
		(start 316.024699 166.501858)
		(end 315.996187 166.473346)
		(width 0.185)
		(layer "B.Cu")
		(net 206)
	)
	(segment
		(start 288.978702 165.81)
		(end 273.228702 150.06)
		(width 0.185)
		(layer "B.Cu")
		(net 206)
	)
	(segment
		(start 318.225 166.51)
		(end 318.015 166.72)
		(width 0.185)
		(layer "B.Cu")
		(net 206)
	)
	(segment
		(start 273.228702 150.06)
		(end 231.078701 150.06)
		(width 0.185)
		(layer "B.Cu")
		(net 206)
	)
	(segment
		(start 231.078701 150.06)
		(end 226.128042 145.109341)
		(width 0.185)
		(layer "B.Cu")
		(net 206)
	)
	(segment
		(start 314.215 166.208)
		(end 314.155 166.268)
		(width 0.185)
		(layer "B.Cu")
		(net 206)
	)
	(segment
		(start 315.517474 166.268)
		(end 315.347 166.268)
		(width 0.185)
		(layer "B.Cu")
		(net 206)
	)
	(segment
		(start 318.015 166.72)
		(end 316.55134 166.72)
		(width 0.185)
		(layer "B.Cu")
		(net 206)
	)
	(segment
		(start 309.938702 167.21)
		(end 308.538702 165.81)
		(width 0.185)
		(layer "B.Cu")
		(net 206)
	)
	(segment
		(start 315.347 166.268)
		(end 315.287 166.208)
		(width 0.185)
		(layer "B.Cu")
		(net 206)
	)
	(segment
		(start 308.538702 165.81)
		(end 288.978702 165.81)
		(width 0.185)
		(layer "B.Cu")
		(net 206)
	)
	(segment
		(start 315.135 166.21)
		(end 314.367 166.21)
		(width 0.185)
		(layer "B.Cu")
		(net 206)
	)
	(segment
		(start 311.521298 167.21)
		(end 309.938702 167.21)
		(width 0.185)
		(layer "B.Cu")
		(net 206)
	)
	(arc
		(start 315.984159 166.461317)
		(mid 315.770044 166.318242)
		(end 315.517474 166.268)
		(width 0.185)
		(layer "B.Cu")
		(net 206)
	)
	(arc
		(start 316.024699 166.501858)
		(mid 316.266324 166.663307)
		(end 316.55134 166.72)
		(width 0.185)
		(layer "B.Cu")
		(net 206)
	)
	(segment
		(start 206.17518 169.0315)
		(end 208.6315 166.57518)
		(width 0.159)
		(layer "In5.Cu")
		(net 206)
	)
	(segment
		(start 198.4565 170.359)
		(end 198.4565 169.75018)
		(width 0.159)
		(layer "In5.Cu")
		(net 206)
	)
	(segment
		(start 209.9315 161.32518)
		(end 212.9315 158.32518)
		(width 0.159)
		(layer "In5.Cu")
		(net 206)
	)
	(segment
		(start 208.6315 166.57518)
		(end 208.6315 163.42518)
		(width 0.159)
		(layer "In5.Cu")
		(net 206)
	)
	(segment
		(start 198.4565 169.75018)
		(end 199.17518 169.0315)
		(width 0.159)
		(layer "In5.Cu")
		(net 206)
	)
	(segment
		(start 208.6315 163.42518)
		(end 209.9315 162.12518)
		(width 0.159)
		(layer "In5.Cu")
		(net 206)
	)
	(segment
		(start 212.9315 158.32518)
		(end 212.9315 149.2455)
		(width 0.159)
		(layer "In5.Cu")
		(net 206)
	)
	(segment
		(start 212.9315 149.2455)
		(end 213.077 149.1)
		(width 0.159)
		(layer "In5.Cu")
		(net 206)
	)
	(segment
		(start 199.17518 169.0315)
		(end 206.17518 169.0315)
		(width 0.159)
		(layer "In5.Cu")
		(net 206)
	)
	(segment
		(start 198.5975 170.5)
		(end 198.4565 170.359)
		(width 0.159)
		(layer "In5.Cu")
		(net 206)
	)
	(segment
		(start 209.9315 162.12518)
		(end 209.9315 161.32518)
		(width 0.159)
		(layer "In5.Cu")
		(net 206)
	)
	(segment
		(start 226.025 170.525)
		(end 226.4 170.9)
		(width 0.125)
		(layer "F.Cu")
		(net 207)
	)
	(segment
		(start 315.135 168.008)
		(end 314.363 168.008)
		(width 0.125)
		(layer "F.Cu")
		(net 207)
	)
	(segment
		(start 315.135 168.008)
		(end 316.402 168.008)
		(width 0.125)
		(layer "F.Cu")
		(net 207)
	)
	(segment
		(start 317.1 167.31)
		(end 319.45 167.31)
		(width 0.125)
		(layer "F.Cu")
		(net 207)
	)
	(segment
		(start 226.025 168.685)
		(end 226.025 170.525)
		(width 0.125)
		(layer "F.Cu")
		(net 207)
	)
	(segment
		(start 313.3 169.21)
		(end 313.3 168.76)
		(width 0.125)
		(layer "F.Cu")
		(net 207)
	)
	(segment
		(start 226.4 170.9)
		(end 231.2 170.9)
		(width 0.125)
		(layer "F.Cu")
		(net 207)
	)
	(segment
		(start 314.052 168.008)
		(end 314.363 168.008)
		(width 0.125)
		(layer "F.Cu")
		(net 207)
	)
	(segment
		(start 313.3 168.76)
		(end 314.052 168.008)
		(width 0.125)
		(layer "F.Cu")
		(net 207)
	)
	(segment
		(start 316.402 168.008)
		(end 317.1 167.31)
		(width 0.125)
		(layer "F.Cu")
		(net 207)
	)
	(via
		(at 313.3 169.21)
		(size 0.45)
		(drill 0.1)
		(layers "F.Cu" "B.Cu")
		(remove_unused_layers yes)
		(keep_end_layers yes)
		(zone_layer_connections "In2.Cu")
		(teardrops
			(best_length_ratio 0.4)
			(max_length 1)
			(best_width_ratio 0.9)
			(max_width 2)
			(curved_edges yes)
			(filter_ratio 0.9)
			(enabled yes)
			(allow_two_segments yes)
			(prefer_zone_connections yes)
		)
		(net 207)
	)
	(via
		(at 231.2 170.9)
		(size 0.45)
		(drill 0.1)
		(layers "F.Cu" "B.Cu")
		(teardrops
			(best_length_ratio 0.4)
			(max_length 1)
			(best_width_ratio 0.9)
			(max_width 2)
			(curved_edges yes)
			(filter_ratio 0.9)
			(enabled yes)
			(allow_two_segments yes)
			(prefer_zone_connections yes)
		)
		(net 207)
	)
	(segment
		(start 232.6 170.9)
		(end 233.9 169.6)
		(width 0.125)
		(layer "In2.Cu")
		(net 207)
	)
	(segment
		(start 312.82 169.69)
		(end 313.3 169.21)
		(width 0.125)
		(layer "In2.Cu")
		(net 207)
	)
	(segment
		(start 233.9 166.6)
		(end 236.5 164)
		(width 0.125)
		(layer "In2.Cu")
		(net 207)
	)
	(segment
		(start 275.3 162.9)
		(end 292.39 162.9)
		(width 0.125)
		(layer "In2.Cu")
		(net 207)
	)
	(segment
		(start 306.35 165.86)
		(end 310.18 169.69)
		(width 0.125)
		(layer "In2.Cu")
		(net 207)
	)
	(segment
		(start 244.6 164)
		(end 246.55 165.95)
		(width 0.125)
		(layer "In2.Cu")
		(net 207)
	)
	(segment
		(start 310.18 169.69)
		(end 312.82 169.69)
		(width 0.125)
		(layer "In2.Cu")
		(net 207)
	)
	(segment
		(start 236.5 164)
		(end 244.6 164)
		(width 0.125)
		(layer "In2.Cu")
		(net 207)
	)
	(segment
		(start 231.2 170.9)
		(end 232.6 170.9)
		(width 0.125)
		(layer "In2.Cu")
		(net 207)
	)
	(segment
		(start 295.35 165.86)
		(end 306.35 165.86)
		(width 0.125)
		(layer "In2.Cu")
		(net 207)
	)
	(segment
		(start 292.39 162.9)
		(end 295.35 165.86)
		(width 0.125)
		(layer "In2.Cu")
		(net 207)
	)
	(segment
		(start 246.55 165.95)
		(end 272.25 165.95)
		(width 0.125)
		(layer "In2.Cu")
		(net 207)
	)
	(segment
		(start 233.9 169.6)
		(end 233.9 166.6)
		(width 0.125)
		(layer "In2.Cu")
		(net 207)
	)
	(segment
		(start 272.25 165.95)
		(end 275.3 162.9)
		(width 0.125)
		(layer "In2.Cu")
		(net 207)
	)
	(segment
		(start 315.135 167.508)
		(end 314.363 167.508)
		(width 0.125)
		(layer "F.Cu")
		(net 208)
	)
	(segment
		(start 226.7 170.5)
		(end 231 170.5)
		(width 0.125)
		(layer "F.Cu")
		(net 208)
	)
	(segment
		(start 316.75 166.51)
		(end 315.752 167.508)
		(width 0.125)
		(layer "F.Cu")
		(net 208)
	)
	(segment
		(start 231 170.5)
		(end 231.2 170.3)
		(width 0.125)
		(layer "F.Cu")
		(net 208)
	)
	(segment
		(start 314.363 167.508)
		(end 314.018719 167.508)
		(width 0.125)
		(layer "F.Cu")
		(net 208)
	)
	(segment
		(start 315.752 167.508)
		(end 315.135 167.508)
		(width 0.125)
		(layer "F.Cu")
		(net 208)
	)
	(segment
		(start 312.5 169.026719)
		(end 312.5 169.185)
		(width 0.125)
		(layer "F.Cu")
		(net 208)
	)
	(segment
		(start 226.525 170.325)
		(end 226.7 170.5)
		(width 0.125)
		(layer "F.Cu")
		(net 208)
	)
	(segment
		(start 226.525 168.685)
		(end 226.525 170.325)
		(width 0.125)
		(layer "F.Cu")
		(net 208)
	)
	(segment
		(start 314.018719 167.508)
		(end 312.5 169.026719)
		(width 0.125)
		(layer "F.Cu")
		(net 208)
	)
	(segment
		(start 319.45 166.51)
		(end 316.75 166.51)
		(width 0.125)
		(layer "F.Cu")
		(net 208)
	)
	(via
		(at 312.5 169.185)
		(size 0.45)
		(drill 0.1)
		(layers "F.Cu" "B.Cu")
		(remove_unused_layers yes)
		(keep_end_layers yes)
		(zone_layer_connections "In2.Cu")
		(teardrops
			(best_length_ratio 0.4)
			(max_length 1)
			(best_width_ratio 0.9)
			(max_width 2)
			(curved_edges yes)
			(filter_ratio 0.9)
			(enabled yes)
			(allow_two_segments yes)
			(prefer_zone_connections yes)
		)
		(net 208)
	)
	(via
		(at 231.2 170.3)
		(size 0.45)
		(drill 0.1)
		(layers "F.Cu" "B.Cu")
		(teardrops
			(best_length_ratio 0.4)
			(max_length 1)
			(best_width_ratio 0.9)
			(max_width 2)
			(curved_edges yes)
			(filter_ratio 0.9)
			(enabled yes)
			(allow_two_segments yes)
			(prefer_zone_connections yes)
		)
		(net 208)
	)
	(segment
		(start 232.9 168.6)
		(end 232.9 166.8)
		(width 0.125)
		(layer "In2.Cu")
		(net 208)
	)
	(segment
		(start 295.55 165.31)
		(end 306.6 165.31)
		(width 0.125)
		(layer "In2.Cu")
		(net 208)
	)
	(segment
		(start 245 163.5)
		(end 246.6 165.1)
		(width 0.125)
		(layer "In2.Cu")
		(net 208)
	)
	(segment
		(start 246.6 165.1)
		(end 272.3 165.1)
		(width 0.125)
		(layer "In2.Cu")
		(net 208)
	)
	(segment
		(start 310.475 169.185)
		(end 312.5 169.185)
		(width 0.125)
		(layer "In2.Cu")
		(net 208)
	)
	(segment
		(start 232.9 166.8)
		(end 236.2 163.5)
		(width 0.125)
		(layer "In2.Cu")
		(net 208)
	)
	(segment
		(start 231.2 170.3)
		(end 232.9 168.6)
		(width 0.125)
		(layer "In2.Cu")
		(net 208)
	)
	(segment
		(start 272.3 165.1)
		(end 275.1 162.3)
		(width 0.125)
		(layer "In2.Cu")
		(net 208)
	)
	(segment
		(start 292.54 162.3)
		(end 295.55 165.31)
		(width 0.125)
		(layer "In2.Cu")
		(net 208)
	)
	(segment
		(start 275.1 162.3)
		(end 292.54 162.3)
		(width 0.125)
		(layer "In2.Cu")
		(net 208)
	)
	(segment
		(start 306.6 165.31)
		(end 310.475 169.185)
		(width 0.125)
		(layer "In2.Cu")
		(net 208)
	)
	(segment
		(start 236.2 163.5)
		(end 245 163.5)
		(width 0.125)
		(layer "In2.Cu")
		(net 208)
	)
	(segment
		(start 205.025 163.135)
		(end 205.025 162.41)
		(width 0.202)
		(layer "F.Cu")
		(net 209)
	)
	(segment
		(start 205.025 162.41)
		(end 204.9695 162.3545)
		(width 0.202)
		(layer "F.Cu")
		(net 209)
	)
	(segment
		(start 204.9695 162.3545)
		(end 204.9695 161.524)
		(width 0.202)
		(layer "F.Cu")
		(net 209)
	)
	(segment
		(start 204.9695 161.524)
		(end 205.0935 161.4)
		(width 0.202)
		(layer "F.Cu")
		(net 209)
	)
	(via
		(at 205.0935 161.4)
		(size 0.45)
		(drill 0.1)
		(layers "F.Cu" "B.Cu")
		(teardrops
			(best_length_ratio 0.4)
			(max_length 1)
			(best_width_ratio 0.9)
			(max_width 2)
			(curved_edges yes)
			(filter_ratio 0.9)
			(enabled yes)
			(allow_two_segments yes)
			(prefer_zone_connections yes)
		)
		(net 209)
	)
	(segment
		(start 205.0935 161.4)
		(end 204.9695 161.276)
		(width 0.202)
		(layer "B.Cu")
		(net 209)
	)
	(segment
		(start 197.054557 142.313303)
		(end 197.054557 141.881262)
		(width 0.202)
		(layer "B.Cu")
		(net 209)
	)
	(segment
		(start 204.9695 150.228246)
		(end 197.054557 142.313303)
		(width 0.202)
		(layer "B.Cu")
		(net 209)
	)
	(segment
		(start 204.9695 161.276)
		(end 204.9695 150.228246)
		(width 0.202)
		(layer "B.Cu")
		(net 209)
	)
	(segment
		(start 204.525 163.135)
		(end 204.525 162.41)
		(width 0.202)
		(layer "F.Cu")
		(net 210)
	)
	(segment
		(start 204.5805 162.3545)
		(end 204.5805 161.524)
		(width 0.202)
		(layer "F.Cu")
		(net 210)
	)
	(segment
		(start 204.5805 161.524)
		(end 204.4565 161.4)
		(width 0.202)
		(layer "F.Cu")
		(net 210)
	)
	(segment
		(start 204.525 162.41)
		(end 204.5805 162.3545)
		(width 0.202)
		(layer "F.Cu")
		(net 210)
	)
	(via
		(at 204.4565 161.4)
		(size 0.45)
		(drill 0.1)
		(layers "F.Cu" "B.Cu")
		(teardrops
			(best_length_ratio 0.4)
			(max_length 1)
			(best_width_ratio 0.9)
			(max_width 2)
			(curved_edges yes)
			(filter_ratio 0.9)
			(enabled yes)
			(allow_two_segments yes)
			(prefer_zone_connections yes)
		)
		(net 210)
	)
	(segment
		(start 196.779492 142.588368)
		(end 197.379175 143.188051)
		(width 0.202)
		(layer "B.Cu")
		(net 210)
	)
	(segment
		(start 198.003038 143.811913)
		(end 204.5805 150.389376)
		(width 0.202)
		(layer "B.Cu")
		(net 210)
	)
	(segment
		(start 196.347451 142.588368)
		(end 196.779492 142.588368)
		(width 0.202)
		(layer "B.Cu")
		(net 210)
	)
	(segment
		(start 204.5805 161.276)
		(end 204.4565 161.4)
		(width 0.202)
		(layer "B.Cu")
		(net 210)
	)
	(segment
		(start 197.379175 143.587249)
		(end 197.603839 143.811913)
		(width 0.202)
		(layer "B.Cu")
		(net 210)
	)
	(segment
		(start 204.5805 150.389376)
		(end 204.5805 161.276)
		(width 0.202)
		(layer "B.Cu")
		(net 210)
	)
	(arc
		(start 197.803439 143.811913)
		(mid 197.903238 143.770575)
		(end 198.003038 143.811913)
		(width 0.202)
		(layer "B.Cu")
		(net 210)
	)
	(arc
		(start 197.603839 143.811913)
		(mid 197.703639 143.853252)
		(end 197.803439 143.811913)
		(width 0.202)
		(layer "B.Cu")
		(net 210)
	)
	(arc
		(start 197.379175 143.188051)
		(mid 197.420513 143.287851)
		(end 197.379175 143.38765)
		(width 0.202)
		(layer "B.Cu")
		(net 210)
	)
	(arc
		(start 197.379175 143.38765)
		(mid 197.337837 143.487449)
		(end 197.379175 143.587249)
		(width 0.202)
		(layer "B.Cu")
		(net 210)
	)
	(segment
		(start 204.9695 165.424)
		(end 205.0935 165.3)
		(width 0.202)
		(layer "F.Cu")
		(net 211)
	)
	(segment
		(start 205.025 168.685)
		(end 205.025 167.96)
		(width 0.202)
		(layer "F.Cu")
		(net 211)
	)
	(segment
		(start 205.025 167.96)
		(end 204.9695 167.9045)
		(width 0.202)
		(layer "F.Cu")
		(net 211)
	)
	(segment
		(start 204.9695 167.9045)
		(end 204.9695 165.424)
		(width 0.202)
		(layer "F.Cu")
		(net 211)
	)
	(via
		(at 205.0935 165.3)
		(size 0.45)
		(drill 0.1)
		(layers "F.Cu" "B.Cu")
		(teardrops
			(best_length_ratio 0.4)
			(max_length 1)
			(best_width_ratio 0.9)
			(max_width 2)
			(curved_edges yes)
			(filter_ratio 0.9)
			(enabled yes)
			(allow_two_segments yes)
			(prefer_zone_connections yes)
		)
		(net 211)
	)
	(segment
		(start 157.400566 123.8655)
		(end 170.540566 137.0055)
		(width 0.202)
		(layer "B.Cu")
		(net 211)
	)
	(segment
		(start 204.9695 165.176)
		(end 205.0935 165.3)
		(width 0.202)
		(layer "B.Cu")
		(net 211)
	)
	(segment
		(start 114.901 145.3605)
		(end 114.9565 145.305)
		(width 0.202)
		(layer "B.Cu")
		(net 211)
	)
	(segment
		(start 170.540566 137.0055)
		(end 185.780566 137.0055)
		(width 0.202)
		(layer "B.Cu")
		(net 211)
	)
	(segment
		(start 196.480566 144.1055)
		(end 203.4945 151.119434)
		(width 0.202)
		(layer "B.Cu")
		(net 211)
	)
	(segment
		(start 192.880566 144.1055)
		(end 196.480566 144.1055)
		(width 0.202)
		(layer "B.Cu")
		(net 211)
	)
	(segment
		(start 185.780566 137.0055)
		(end 192.880566 144.1055)
		(width 0.202)
		(layer "B.Cu")
		(net 211)
	)
	(segment
		(start 203.4945 162.419434)
		(end 204.9695 163.894434)
		(width 0.202)
		(layer "B.Cu")
		(net 211)
	)
	(segment
		(start 124.309434 123.8655)
		(end 157.400566 123.8655)
		(width 0.202)
		(layer "B.Cu")
		(net 211)
	)
	(segment
		(start 203.4945 151.119434)
		(end 203.4945 162.419434)
		(width 0.202)
		(layer "B.Cu")
		(net 211)
	)
	(segment
		(start 204.9695 163.894434)
		(end 204.9695 165.176)
		(width 0.202)
		(layer "B.Cu")
		(net 211)
	)
	(segment
		(start 114.9565 145.305)
		(end 114.9565 133.218434)
		(width 0.202)
		(layer "B.Cu")
		(net 211)
	)
	(segment
		(start 114.9565 133.218434)
		(end 124.309434 123.8655)
		(width 0.202)
		(layer "B.Cu")
		(net 211)
	)
	(segment
		(start 204.525 167.96)
		(end 204.5805 167.9045)
		(width 0.202)
		(layer "F.Cu")
		(net 212)
	)
	(segment
		(start 204.5805 167.9045)
		(end 204.5805 165.424)
		(width 0.202)
		(layer "F.Cu")
		(net 212)
	)
	(segment
		(start 204.5805 165.424)
		(end 204.4565 165.3)
		(width 0.202)
		(layer "F.Cu")
		(net 212)
	)
	(segment
		(start 204.525 168.685)
		(end 204.525 167.96)
		(width 0.202)
		(layer "F.Cu")
		(net 212)
	)
	(via
		(at 204.4565 165.3)
		(size 0.45)
		(drill 0.1)
		(layers "F.Cu" "B.Cu")
		(teardrops
			(best_length_ratio 0.4)
			(max_length 1)
			(best_width_ratio 0.9)
			(max_width 2)
			(curved_edges yes)
			(filter_ratio 0.9)
			(enabled yes)
			(allow_two_segments yes)
			(prefer_zone_connections yes)
		)
		(net 212)
	)
	(segment
		(start 204.5805 165.176)
		(end 204.4565 165.3)
		(width 0.202)
		(layer "B.Cu")
		(net 212)
	)
	(segment
		(start 192.719434 144.4945)
		(end 196.319434 144.4945)
		(width 0.202)
		(layer "B.Cu")
		(net 212)
	)
	(segment
		(start 170.379434 137.3945)
		(end 185.619434 137.3945)
		(width 0.202)
		(layer "B.Cu")
		(net 212)
	)
	(segment
		(start 187.08059 140.019628)
		(end 187.154129 140.093167)
		(width 0.202)
		(layer "B.Cu")
		(net 212)
	)
	(segment
		(start 203.1055 151.280566)
		(end 203.1055 162.580566)
		(width 0.202)
		(layer "B.Cu")
		(net 212)
	)
	(segment
		(start 188.030271 139.805337)
		(end 188.103811 139.878877)
		(width 0.202)
		(layer "B.Cu")
		(net 212)
	)
	(segment
		(start 157.239434 124.2545)
		(end 170.379434 137.3945)
		(width 0.202)
		(layer "B.Cu")
		(net 212)
	)
	(segment
		(start 204.5805 164.055566)
		(end 204.5805 165.176)
		(width 0.202)
		(layer "B.Cu")
		(net 212)
	)
	(segment
		(start 185.619434 137.3945)
		(end 187.36842 139.143486)
		(width 0.202)
		(layer "B.Cu")
		(net 212)
	)
	(segment
		(start 188.103811 139.878877)
		(end 190.259253 142.034319)
		(width 0.202)
		(layer "B.Cu")
		(net 212)
	)
	(segment
		(start 115.401 145.3605)
		(end 115.3455 145.305)
		(width 0.202)
		(layer "B.Cu")
		(net 212)
	)
	(segment
		(start 187.36842 139.437642)
		(end 187.08059 139.725471)
		(width 0.202)
		(layer "B.Cu")
		(net 212)
	)
	(segment
		(start 124.470566 124.2545)
		(end 157.239434 124.2545)
		(width 0.202)
		(layer "B.Cu")
		(net 212)
	)
	(segment
		(start 196.319434 144.4945)
		(end 203.1055 151.280566)
		(width 0.202)
		(layer "B.Cu")
		(net 212)
	)
	(segment
		(start 115.3455 133.379566)
		(end 124.470566 124.2545)
		(width 0.202)
		(layer "B.Cu")
		(net 212)
	)
	(segment
		(start 187.448285 140.093167)
		(end 187.736114 139.805337)
		(width 0.202)
		(layer "B.Cu")
		(net 212)
	)
	(segment
		(start 190.259253 142.034319)
		(end 192.719434 144.4945)
		(width 0.202)
		(layer "B.Cu")
		(net 212)
	)
	(segment
		(start 115.3455 145.305)
		(end 115.3455 133.379566)
		(width 0.202)
		(layer "B.Cu")
		(net 212)
	)
	(segment
		(start 203.1055 162.580566)
		(end 204.5805 164.055566)
		(width 0.202)
		(layer "B.Cu")
		(net 212)
	)
	(arc
		(start 187.36842 139.143486)
		(mid 187.429342 139.290564)
		(end 187.36842 139.437642)
		(width 0.202)
		(layer "B.Cu")
		(net 212)
	)
	(arc
		(start 187.736114 139.805337)
		(mid 187.883192 139.744415)
		(end 188.030271 139.805337)
		(width 0.202)
		(layer "B.Cu")
		(net 212)
	)
	(arc
		(start 187.154129 140.093167)
		(mid 187.301207 140.154089)
		(end 187.448285 140.093167)
		(width 0.202)
		(layer "B.Cu")
		(net 212)
	)
	(arc
		(start 187.08059 139.725471)
		(mid 187.019668 139.872549)
		(end 187.08059 140.019628)
		(width 0.202)
		(layer "B.Cu")
		(net 212)
	)
	(segment
		(start 206.4695 161.524)
		(end 206.5935 161.4)
		(width 0.202)
		(layer "F.Cu")
		(net 213)
	)
	(segment
		(start 206.525 161.822499)
		(end 206.4695 161.766999)
		(width 0.202)
		(layer "F.Cu")
		(net 213)
	)
	(segment
		(start 206.4695 161.766999)
		(end 206.4695 161.524)
		(width 0.202)
		(layer "F.Cu")
		(net 213)
	)
	(segment
		(start 206.525 163.135)
		(end 206.525 161.822499)
		(width 0.202)
		(layer "F.Cu")
		(net 213)
	)
	(via
		(at 206.5935 161.4)
		(size 0.45)
		(drill 0.1)
		(layers "F.Cu" "B.Cu")
		(teardrops
			(best_length_ratio 0.4)
			(max_length 1)
			(best_width_ratio 0.9)
			(max_width 2)
			(curved_edges yes)
			(filter_ratio 0.9)
			(enabled yes)
			(allow_two_segments yes)
			(prefer_zone_connections yes)
		)
		(net 213)
	)
	(segment
		(start 206.4695 149.613996)
		(end 196.764644 139.90914)
		(width 0.202)
		(layer "B.Cu")
		(net 213)
	)
	(segment
		(start 206.5935 161.4)
		(end 206.4695 161.276)
		(width 0.202)
		(layer "B.Cu")
		(net 213)
	)
	(segment
		(start 196.764644 139.90914)
		(end 196.764644 139.470027)
		(width 0.202)
		(layer "B.Cu")
		(net 213)
	)
	(segment
		(start 206.4695 161.276)
		(end 206.4695 149.613996)
		(width 0.202)
		(layer "B.Cu")
		(net 213)
	)
	(segment
		(start 206.025 161.822499)
		(end 206.0805 161.766999)
		(width 0.202)
		(layer "F.Cu")
		(net 214)
	)
	(segment
		(start 206.0805 161.524)
		(end 205.9565 161.4)
		(width 0.202)
		(layer "F.Cu")
		(net 214)
	)
	(segment
		(start 206.0805 161.766999)
		(end 206.0805 161.524)
		(width 0.202)
		(layer "F.Cu")
		(net 214)
	)
	(segment
		(start 206.025 163.135)
		(end 206.025 161.822499)
		(width 0.202)
		(layer "F.Cu")
		(net 214)
	)
	(via
		(at 205.9565 161.4)
		(size 0.45)
		(drill 0.1)
		(layers "F.Cu" "B.Cu")
		(teardrops
			(best_length_ratio 0.4)
			(max_length 1)
			(best_width_ratio 0.9)
			(max_width 2)
			(curved_edges yes)
			(filter_ratio 0.9)
			(enabled yes)
			(allow_two_segments yes)
			(prefer_zone_connections yes)
		)
		(net 214)
	)
	(segment
		(start 206.0805 149.775126)
		(end 206.0805 161.276)
		(width 0.202)
		(layer "B.Cu")
		(net 214)
	)
	(segment
		(start 198.652016 142.745856)
		(end 198.876672 142.970512)
		(width 0.202)
		(layer "B.Cu")
		(net 214)
	)
	(segment
		(start 196.489579 140.184205)
		(end 198.652016 142.346642)
		(width 0.202)
		(layer "B.Cu")
		(net 214)
	)
	(segment
		(start 196.050466 140.184205)
		(end 196.489579 140.184205)
		(width 0.202)
		(layer "B.Cu")
		(net 214)
	)
	(segment
		(start 206.0805 161.276)
		(end 205.9565 161.4)
		(width 0.202)
		(layer "B.Cu")
		(net 214)
	)
	(segment
		(start 199.275887 142.970512)
		(end 206.0805 149.775126)
		(width 0.202)
		(layer "B.Cu")
		(net 214)
	)
	(arc
		(start 198.876672 142.970512)
		(mid 198.976476 143.011852)
		(end 199.07628 142.970512)
		(width 0.202)
		(layer "B.Cu")
		(net 214)
	)
	(arc
		(start 199.07628 142.970512)
		(mid 199.176083 142.929172)
		(end 199.275887 142.970512)
		(width 0.202)
		(layer "B.Cu")
		(net 214)
	)
	(arc
		(start 198.652016 142.546249)
		(mid 198.610676 142.646052)
		(end 198.652016 142.745856)
		(width 0.202)
		(layer "B.Cu")
		(net 214)
	)
	(arc
		(start 198.652016 142.346642)
		(mid 198.693355 142.446446)
		(end 198.652016 142.546249)
		(width 0.202)
		(layer "B.Cu")
		(net 214)
	)
	(segment
		(start 206.525 167.96)
		(end 206.4695 167.9045)
		(width 0.202)
		(layer "F.Cu")
		(net 215)
	)
	(segment
		(start 206.4695 166.494435)
		(end 206.225214 166.250149)
		(width 0.202)
		(layer "F.Cu")
		(net 215)
	)
	(segment
		(start 206.225214 166.250149)
		(end 206.225214 166.074786)
		(width 0.202)
		(layer "F.Cu")
		(net 215)
	)
	(segment
		(start 206.525 168.685)
		(end 206.525 167.96)
		(width 0.202)
		(layer "F.Cu")
		(net 215)
	)
	(segment
		(start 206.4695 167.9045)
		(end 206.4695 166.494435)
		(width 0.202)
		(layer "F.Cu")
		(net 215)
	)
	(via
		(at 206.225214 166.074786)
		(size 0.45)
		(drill 0.1)
		(layers "F.Cu" "B.Cu")
		(teardrops
			(best_length_ratio 0.4)
			(max_length 1)
			(best_width_ratio 0.9)
			(max_width 2)
			(curved_edges yes)
			(filter_ratio 0.9)
			(enabled yes)
			(allow_two_segments yes)
			(prefer_zone_connections yes)
		)
		(net 215)
	)
	(segment
		(start 116.401 145.3605)
		(end 116.4565 145.305)
		(width 0.202)
		(layer "B.Cu")
		(net 215)
	)
	(segment
		(start 170.020566 138.6055)
		(end 184.680566 138.6055)
		(width 0.202)
		(layer "B.Cu")
		(net 215)
	)
	(segment
		(start 202.0945 151.719434)
		(end 202.0945 165.119434)
		(width 0.202)
		(layer "B.Cu")
		(net 215)
	)
	(segment
		(start 156.780566 125.3655)
		(end 170.020566 138.6055)
		(width 0.202)
		(layer "B.Cu")
		(net 215)
	)
	(segment
		(start 116.4565 133.838434)
		(end 124.929434 125.3655)
		(width 0.202)
		(layer "B.Cu")
		(net 215)
	)
	(segment
		(start 206.049851 166.074786)
		(end 206.225214 166.074786)
		(width 0.202)
		(layer "B.Cu")
		(net 215)
	)
	(segment
		(start 191.380566 145.3055)
		(end 195.680566 145.3055)
		(width 0.202)
		(layer "B.Cu")
		(net 215)
	)
	(segment
		(start 205.880565 165.9055)
		(end 206.049851 166.074786)
		(width 0.202)
		(layer "B.Cu")
		(net 215)
	)
	(segment
		(start 184.680566 138.6055)
		(end 191.380566 145.3055)
		(width 0.202)
		(layer "B.Cu")
		(net 215)
	)
	(segment
		(start 202.0945 165.119434)
		(end 202.880566 165.9055)
		(width 0.202)
		(layer "B.Cu")
		(net 215)
	)
	(segment
		(start 124.929434 125.3655)
		(end 156.780566 125.3655)
		(width 0.202)
		(layer "B.Cu")
		(net 215)
	)
	(segment
		(start 195.680566 145.3055)
		(end 202.0945 151.719434)
		(width 0.202)
		(layer "B.Cu")
		(net 215)
	)
	(segment
		(start 116.4565 145.305)
		(end 116.4565 133.838434)
		(width 0.202)
		(layer "B.Cu")
		(net 215)
	)
	(segment
		(start 202.880566 165.9055)
		(end 205.880565 165.9055)
		(width 0.202)
		(layer "B.Cu")
		(net 215)
	)
	(segment
		(start 206.025 168.685)
		(end 206.025 167.96)
		(width 0.202)
		(layer "F.Cu")
		(net 216)
	)
	(segment
		(start 205.950149 166.525214)
		(end 205.774786 166.525214)
		(width 0.202)
		(layer "F.Cu")
		(net 216)
	)
	(segment
		(start 206.0805 166.655565)
		(end 205.950149 166.525214)
		(width 0.202)
		(layer "F.Cu")
		(net 216)
	)
	(segment
		(start 206.025 167.96)
		(end 206.0805 167.9045)
		(width 0.202)
		(layer "F.Cu")
		(net 216)
	)
	(segment
		(start 206.0805 167.9045)
		(end 206.0805 166.655565)
		(width 0.202)
		(layer "F.Cu")
		(net 216)
	)
	(via
		(at 205.774786 166.525214)
		(size 0.45)
		(drill 0.1)
		(layers "F.Cu" "B.Cu")
		(teardrops
			(best_length_ratio 0.4)
			(max_length 1)
			(best_width_ratio 0.9)
			(max_width 2)
			(curved_edges yes)
			(filter_ratio 0.9)
			(enabled yes)
			(allow_two_segments yes)
			(prefer_zone_connections yes)
		)
		(net 216)
	)
	(segment
		(start 205.22 166.2945)
		(end 205.309921 166.2945)
		(width 0.202)
		(layer "B.Cu")
		(net 216)
	)
	(segment
		(start 169.859434 138.9945)
		(end 184.519434 138.9945)
		(width 0.202)
		(layer "B.Cu")
		(net 216)
	)
	(segment
		(start 202.719434 166.2945)
		(end 204.1 166.2945)
		(width 0.202)
		(layer "B.Cu")
		(net 216)
	)
	(segment
		(start 116.8455 133.999566)
		(end 125.090566 125.7545)
		(width 0.202)
		(layer "B.Cu")
		(net 216)
	)
	(segment
		(start 116.8455 145.305)
		(end 116.8455 133.999566)
		(width 0.202)
		(layer "B.Cu")
		(net 216)
	)
	(segment
		(start 204.548 167.1313)
		(end 204.66 167.1313)
		(width 0.202)
		(layer "B.Cu")
		(net 216)
	)
	(segment
		(start 125.090566 125.7545)
		(end 156.619434 125.7545)
		(width 0.202)
		(layer "B.Cu")
		(net 216)
	)
	(segment
		(start 184.519434 138.9945)
		(end 191.219434 145.6945)
		(width 0.202)
		(layer "B.Cu")
		(net 216)
	)
	(segment
		(start 205.774786 166.349851)
		(end 205.774786 166.525214)
		(width 0.202)
		(layer "B.Cu")
		(net 216)
	)
	(segment
		(start 201.7055 151.880566)
		(end 201.7055 165.280566)
		(width 0.202)
		(layer "B.Cu")
		(net 216)
	)
	(segment
		(start 204.324 166.5185)
		(end 204.324 166.9073)
		(width 0.202)
		(layer "B.Cu")
		(net 216)
	)
	(segment
		(start 205.309921 166.2945)
		(end 205.719435 166.2945)
		(width 0.202)
		(layer "B.Cu")
		(net 216)
	)
	(segment
		(start 116.901 145.3605)
		(end 116.8455 145.305)
		(width 0.202)
		(layer "B.Cu")
		(net 216)
	)
	(segment
		(start 205.108 166.2945)
		(end 205.22 166.2945)
		(width 0.202)
		(layer "B.Cu")
		(net 216)
	)
	(segment
		(start 191.219434 145.6945)
		(end 195.519434 145.6945)
		(width 0.202)
		(layer "B.Cu")
		(net 216)
	)
	(segment
		(start 156.619434 125.7545)
		(end 169.859434 138.9945)
		(width 0.202)
		(layer "B.Cu")
		(net 216)
	)
	(segment
		(start 204.884 166.9073)
		(end 204.884 166.5185)
		(width 0.202)
		(layer "B.Cu")
		(net 216)
	)
	(segment
		(start 205.719435 166.2945)
		(end 205.774786 166.349851)
		(width 0.202)
		(layer "B.Cu")
		(net 216)
	)
	(segment
		(start 195.519434 145.6945)
		(end 201.7055 151.880566)
		(width 0.202)
		(layer "B.Cu")
		(net 216)
	)
	(segment
		(start 201.7055 165.280566)
		(end 202.719434 166.2945)
		(width 0.202)
		(layer "B.Cu")
		(net 216)
	)
	(arc
		(start 204.1 166.2945)
		(mid 204.258392 166.360108)
		(end 204.324 166.5185)
		(width 0.202)
		(layer "B.Cu")
		(net 216)
	)
	(arc
		(start 204.66 167.1313)
		(mid 204.818392 167.065692)
		(end 204.884 166.9073)
		(width 0.202)
		(layer "B.Cu")
		(net 216)
	)
	(arc
		(start 204.884 166.5185)
		(mid 204.949608 166.360108)
		(end 205.108 166.2945)
		(width 0.202)
		(layer "B.Cu")
		(net 216)
	)
	(arc
		(start 204.324 166.9073)
		(mid 204.389608 167.065692)
		(end 204.548 167.1313)
		(width 0.202)
		(layer "B.Cu")
		(net 216)
	)
	(segment
		(start 207.9695 161.766999)
		(end 207.9695 161.524)
		(width 0.202)
		(layer "F.Cu")
		(net 217)
	)
	(segment
		(start 208.025 161.822499)
		(end 207.9695 161.766999)
		(width 0.202)
		(layer "F.Cu")
		(net 217)
	)
	(segment
		(start 207.9695 161.524)
		(end 208.0935 161.4)
		(width 0.202)
		(layer "F.Cu")
		(net 217)
	)
	(segment
		(start 208.025 163.135)
		(end 208.025 161.822499)
		(width 0.202)
		(layer "F.Cu")
		(net 217)
	)
	(via
		(at 208.0935 161.4)
		(size 0.45)
		(drill 0.1)
		(layers "F.Cu" "B.Cu")
		(teardrops
			(best_length_ratio 0.4)
			(max_length 1)
			(best_width_ratio 0.9)
			(max_width 2)
			(curved_edges yes)
			(filter_ratio 0.9)
			(enabled yes)
			(allow_two_segments yes)
			(prefer_zone_connections yes)
		)
		(net 217)
	)
	(segment
		(start 199.175878 139.759941)
		(end 199.175878 140.191983)
		(width 0.202)
		(layer "B.Cu")
		(net 217)
	)
	(segment
		(start 199.175878 140.191983)
		(end 207.9695 148.985605)
		(width 0.202)
		(layer "B.Cu")
		(net 217)
	)
	(segment
		(start 207.9695 161.276)
		(end 208.0935 161.4)
		(width 0.202)
		(layer "B.Cu")
		(net 217)
	)
	(segment
		(start 207.9695 148.985605)
		(end 207.9695 161.276)
		(width 0.202)
		(layer "B.Cu")
		(net 217)
	)
	(segment
		(start 207.525 161.822499)
		(end 207.5805 161.766999)
		(width 0.202)
		(layer "F.Cu")
		(net 218)
	)
	(segment
		(start 207.5805 161.766999)
		(end 207.5805 161.524)
		(width 0.202)
		(layer "F.Cu")
		(net 218)
	)
	(segment
		(start 207.5805 161.524)
		(end 207.4565 161.4)
		(width 0.202)
		(layer "F.Cu")
		(net 218)
	)
	(segment
		(start 207.525 163.135)
		(end 207.525 161.822499)
		(width 0.202)
		(layer "F.Cu")
		(net 218)
	)
	(via
		(at 207.4565 161.4)
		(size 0.45)
		(drill 0.1)
		(layers "F.Cu" "B.Cu")
		(teardrops
			(best_length_ratio 0.4)
			(max_length 1)
			(best_width_ratio 0.9)
			(max_width 2)
			(curved_edges yes)
			(filter_ratio 0.9)
			(enabled yes)
			(allow_two_segments yes)
			(prefer_zone_connections yes)
		)
		(net 218)
	)
	(segment
		(start 198.900813 140.467048)
		(end 199.665879 141.232114)
		(width 0.202)
		(layer "B.Cu")
		(net 218)
	)
	(segment
		(start 207.5805 149.146735)
		(end 207.5805 161.276)
		(width 0.202)
		(layer "B.Cu")
		(net 218)
	)
	(segment
		(start 198.468771 140.467048)
		(end 198.900813 140.467048)
		(width 0.202)
		(layer "B.Cu")
		(net 218)
	)
	(segment
		(start 199.665879 141.63136)
		(end 199.890519 141.856)
		(width 0.202)
		(layer "B.Cu")
		(net 218)
	)
	(segment
		(start 207.5805 161.276)
		(end 207.4565 161.4)
		(width 0.202)
		(layer "B.Cu")
		(net 218)
	)
	(segment
		(start 200.289766 141.856)
		(end 207.5805 149.146735)
		(width 0.202)
		(layer "B.Cu")
		(net 218)
	)
	(arc
		(start 199.665879 141.232114)
		(mid 199.707222 141.331926)
		(end 199.665879 141.431737)
		(width 0.202)
		(layer "B.Cu")
		(net 218)
	)
	(arc
		(start 199.890519 141.856)
		(mid 199.990331 141.897343)
		(end 200.090143 141.856)
		(width 0.202)
		(layer "B.Cu")
		(net 218)
	)
	(arc
		(start 200.090143 141.856)
		(mid 200.189954 141.814657)
		(end 200.289766 141.856)
		(width 0.202)
		(layer "B.Cu")
		(net 218)
	)
	(arc
		(start 199.665879 141.431737)
		(mid 199.624536 141.531548)
		(end 199.665879 141.63136)
		(width 0.202)
		(layer "B.Cu")
		(net 218)
	)
	(segment
		(start 207.9695 167.305566)
		(end 208.9695 166.305566)
		(width 0.202)
		(layer "F.Cu")
		(net 219)
	)
	(segment
		(start 208.9695 165.469434)
		(end 208.530566 165.0305)
		(width 0.202)
		(layer "F.Cu")
		(net 219)
	)
	(segment
		(start 208.530566 165.0305)
		(end 207.694435 165.0305)
		(width 0.202)
		(layer "F.Cu")
		(net 219)
	)
	(segment
		(start 207.9695 167.9045)
		(end 207.9695 167.305566)
		(width 0.202)
		(layer "F.Cu")
		(net 219)
	)
	(segment
		(start 207.694435 165.0305)
		(end 207.450149 165.274786)
		(width 0.202)
		(layer "F.Cu")
		(net 219)
	)
	(segment
		(start 208.025 168.685)
		(end 208.025 167.96)
		(width 0.202)
		(layer "F.Cu")
		(net 219)
	)
	(segment
		(start 207.450149 165.274786)
		(end 207.274786 165.274786)
		(width 0.202)
		(layer "F.Cu")
		(net 219)
	)
	(segment
		(start 208.9695 166.305566)
		(end 208.9695 165.469434)
		(width 0.202)
		(layer "F.Cu")
		(net 219)
	)
	(segment
		(start 208.025 167.96)
		(end 207.9695 167.9045)
		(width 0.202)
		(layer "F.Cu")
		(net 219)
	)
	(via
		(at 207.274786 165.274786)
		(size 0.45)
		(drill 0.1)
		(layers "F.Cu" "B.Cu")
		(teardrops
			(best_length_ratio 0.4)
			(max_length 1)
			(best_width_ratio 0.9)
			(max_width 2)
			(curved_edges yes)
			(filter_ratio 0.9)
			(enabled yes)
			(allow_two_segments yes)
			(prefer_zone_connections yes)
		)
		(net 219)
	)
	(segment
		(start 117.9545 134.455434)
		(end 125.544434 126.8655)
		(width 0.202)
		(layer "B.Cu")
		(net 219)
	)
	(segment
		(start 202.380566 168.2055)
		(end 205.469434 168.2055)
		(width 0.202)
		(layer "B.Cu")
		(net 219)
	)
	(segment
		(start 183.680566 140.3055)
		(end 190.180566 146.8055)
		(width 0.202)
		(layer "B.Cu")
		(net 219)
	)
	(segment
		(start 205.469434 168.2055)
		(end 206.7805 166.894434)
		(width 0.202)
		(layer "B.Cu")
		(net 219)
	)
	(segment
		(start 117.899 145.3605)
		(end 117.9545 145.305)
		(width 0.202)
		(layer "B.Cu")
		(net 219)
	)
	(segment
		(start 190.180566 146.8055)
		(end 195.580566 146.8055)
		(width 0.202)
		(layer "B.Cu")
		(net 219)
	)
	(segment
		(start 200.3945 151.619434)
		(end 200.3945 166.219434)
		(width 0.202)
		(layer "B.Cu")
		(net 219)
	)
	(segment
		(start 206.7805 166.894434)
		(end 206.7805 165.944435)
		(width 0.202)
		(layer "B.Cu")
		(net 219)
	)
	(segment
		(start 156.160566 126.8655)
		(end 169.600566 140.3055)
		(width 0.202)
		(layer "B.Cu")
		(net 219)
	)
	(segment
		(start 195.580566 146.8055)
		(end 200.3945 151.619434)
		(width 0.202)
		(layer "B.Cu")
		(net 219)
	)
	(segment
		(start 207.274786 165.450149)
		(end 207.274786 165.274786)
		(width 0.202)
		(layer "B.Cu")
		(net 219)
	)
	(segment
		(start 117.9545 145.305)
		(end 117.9545 134.455434)
		(width 0.202)
		(layer "B.Cu")
		(net 219)
	)
	(segment
		(start 125.544434 126.8655)
		(end 156.160566 126.8655)
		(width 0.202)
		(layer "B.Cu")
		(net 219)
	)
	(segment
		(start 206.7805 165.944435)
		(end 207.274786 165.450149)
		(width 0.202)
		(layer "B.Cu")
		(net 219)
	)
	(segment
		(start 200.3945 166.219434)
		(end 202.380566 168.2055)
		(width 0.202)
		(layer "B.Cu")
		(net 219)
	)
	(segment
		(start 169.600566 140.3055)
		(end 183.680566 140.3055)
		(width 0.202)
		(layer "B.Cu")
		(net 219)
	)
	(segment
		(start 207.725214 165.549851)
		(end 207.725214 165.725214)
		(width 0.202)
		(layer "F.Cu")
		(net 220)
	)
	(segment
		(start 208.5805 165.630566)
		(end 208.369434 165.4195)
		(width 0.202)
		(layer "F.Cu")
		(net 220)
	)
	(segment
		(start 207.525 167.96)
		(end 207.5805 167.9045)
		(width 0.202)
		(layer "F.Cu")
		(net 220)
	)
	(segment
		(start 207.525 168.685)
		(end 207.525 167.96)
		(width 0.202)
		(layer "F.Cu")
		(net 220)
	)
	(segment
		(start 208.5805 166.144434)
		(end 208.5805 165.630566)
		(width 0.202)
		(layer "F.Cu")
		(net 220)
	)
	(segment
		(start 207.855565 165.4195)
		(end 207.725214 165.549851)
		(width 0.202)
		(layer "F.Cu")
		(net 220)
	)
	(segment
		(start 208.369434 165.4195)
		(end 207.855565 165.4195)
		(width 0.202)
		(layer "F.Cu")
		(net 220)
	)
	(segment
		(start 207.5805 167.9045)
		(end 207.5805 167.144434)
		(width 0.202)
		(layer "F.Cu")
		(net 220)
	)
	(segment
		(start 207.5805 167.144434)
		(end 208.5805 166.144434)
		(width 0.202)
		(layer "F.Cu")
		(net 220)
	)
	(via
		(at 207.725214 165.725214)
		(size 0.45)
		(drill 0.1)
		(layers "F.Cu" "B.Cu")
		(teardrops
			(best_length_ratio 0.4)
			(max_length 1)
			(best_width_ratio 0.9)
			(max_width 2)
			(curved_edges yes)
			(filter_ratio 0.9)
			(enabled yes)
			(allow_two_segments yes)
			(prefer_zone_connections yes)
		)
		(net 220)
	)
	(segment
		(start 190.019434 147.1945)
		(end 183.519434 140.6945)
		(width 0.202)
		(layer "B.Cu")
		(net 220)
	)
	(segment
		(start 205.630566 168.5945)
		(end 202.219434 168.5945)
		(width 0.202)
		(layer "B.Cu")
		(net 220)
	)
	(segment
		(start 207.300792 168.059057)
		(end 207.235739 168.124111)
		(width 0.202)
		(layer "B.Cu")
		(net 220)
	)
	(segment
		(start 202.219434 168.5945)
		(end 200.0055 166.380566)
		(width 0.202)
		(layer "B.Cu")
		(net 220)
	)
	(segment
		(start 200.0055 151.780566)
		(end 195.419434 147.1945)
		(width 0.202)
		(layer "B.Cu")
		(net 220)
	)
	(segment
		(start 207.549851 165.725214)
		(end 207.1695 166.105565)
		(width 0.202)
		(layer "B.Cu")
		(net 220)
	)
	(segment
		(start 169.439434 140.6945)
		(end 155.999434 127.2545)
		(width 0.202)
		(layer "B.Cu")
		(net 220)
	)
	(segment
		(start 206.975523 168.124112)
		(end 206.668348 167.816937)
		(width 0.202)
		(layer "B.Cu")
		(net 220)
	)
	(segment
		(start 206.993617 167.491665)
		(end 207.300793 167.798841)
		(width 0.202)
		(layer "B.Cu")
		(net 220)
	)
	(segment
		(start 118.3435 145.305)
		(end 118.399 145.3605)
		(width 0.202)
		(layer "B.Cu")
		(net 220)
	)
	(segment
		(start 183.519434 140.6945)
		(end 169.439434 140.6945)
		(width 0.202)
		(layer "B.Cu")
		(net 220)
	)
	(segment
		(start 195.419434 147.1945)
		(end 190.019434 147.1945)
		(width 0.202)
		(layer "B.Cu")
		(net 220)
	)
	(segment
		(start 125.705566 127.2545)
		(end 118.3435 134.616566)
		(width 0.202)
		(layer "B.Cu")
		(net 220)
	)
	(segment
		(start 118.3435 134.616566)
		(end 118.3435 145.305)
		(width 0.202)
		(layer "B.Cu")
		(net 220)
	)
	(segment
		(start 206.408134 167.816936)
		(end 206.343078 167.881989)
		(width 0.202)
		(layer "B.Cu")
		(net 220)
	)
	(segment
		(start 200.0055 166.380566)
		(end 200.0055 151.780566)
		(width 0.202)
		(layer "B.Cu")
		(net 220)
	)
	(segment
		(start 155.999434 127.2545)
		(end 125.705566 127.2545)
		(width 0.202)
		(layer "B.Cu")
		(net 220)
	)
	(segment
		(start 206.343078 167.881989)
		(end 205.630566 168.5945)
		(width 0.202)
		(layer "B.Cu")
		(net 220)
	)
	(segment
		(start 207.1695 166.105565)
		(end 207.1695 167.055566)
		(width 0.202)
		(layer "B.Cu")
		(net 220)
	)
	(segment
		(start 207.725214 165.725214)
		(end 207.549851 165.725214)
		(width 0.202)
		(layer "B.Cu")
		(net 220)
	)
	(segment
		(start 207.1695 167.055566)
		(end 206.993617 167.231449)
		(width 0.202)
		(layer "B.Cu")
		(net 220)
	)
	(arc
		(start 206.993617 167.231449)
		(mid 206.939725 167.361557)
		(end 206.993617 167.491665)
		(width 0.202)
		(layer "B.Cu")
		(net 220)
	)
	(arc
		(start 206.668348 167.816937)
		(mid 206.53824 167.763045)
		(end 206.408134 167.816936)
		(width 0.202)
		(layer "B.Cu")
		(net 220)
	)
	(arc
		(start 207.300793 167.798841)
		(mid 207.354686 167.928948)
		(end 207.300792 168.059057)
		(width 0.202)
		(layer "B.Cu")
		(net 220)
	)
	(arc
		(start 207.235739 168.124111)
		(mid 207.105631 168.178004)
		(end 206.975523 168.124112)
		(width 0.202)
		(layer "B.Cu")
		(net 220)
	)
	(segment
		(start 210.025 163.135)
		(end 210.025 162.41)
		(width 0.202)
		(layer "F.Cu")
		(net 221)
	)
	(segment
		(start 209.9695 162.3545)
		(end 209.9695 159.374)
		(width 0.202)
		(layer "F.Cu")
		(net 221)
	)
	(segment
		(start 209.9695 159.374)
		(end 210.0935 159.25)
		(width 0.202)
		(layer "F.Cu")
		(net 221)
	)
	(segment
		(start 210.025 162.41)
		(end 209.9695 162.3545)
		(width 0.202)
		(layer "F.Cu")
		(net 221)
	)
	(via
		(at 210.0935 159.25)
		(size 0.45)
		(drill 0.1)
		(layers "F.Cu" "B.Cu")
		(teardrops
			(best_length_ratio 0.4)
			(max_length 1)
			(best_width_ratio 0.9)
			(max_width 2)
			(curved_edges yes)
			(filter_ratio 0.9)
			(enabled yes)
			(allow_two_segments yes)
			(prefer_zone_connections yes)
		)
		(net 221)
	)
	(segment
		(start 198.900107 137.794891)
		(end 198.900107 137.362849)
		(width 0.202)
		(layer "B.Cu")
		(net 221)
	)
	(segment
		(start 209.9695 148.864284)
		(end 198.900107 137.794891)
		(width 0.202)
		(layer "B.Cu")
		(net 221)
	)
	(segment
		(start 210.0935 159.25)
		(end 209.9695 159.126)
		(width 0.202)
		(layer "B.Cu")
		(net 221)
	)
	(segment
		(start 209.9695 159.126)
		(end 209.9695 148.864284)
		(width 0.202)
		(layer "B.Cu")
		(net 221)
	)
	(segment
		(start 209.5805 162.3545)
		(end 209.5805 159.374)
		(width 0.202)
		(layer "F.Cu")
		(net 222)
	)
	(segment
		(start 209.5805 159.374)
		(end 209.4565 159.25)
		(width 0.202)
		(layer "F.Cu")
		(net 222)
	)
	(segment
		(start 209.525 162.41)
		(end 209.5805 162.3545)
		(width 0.202)
		(layer "F.Cu")
		(net 222)
	)
	(segment
		(start 209.525 163.135)
		(end 209.525 162.41)
		(width 0.202)
		(layer "F.Cu")
		(net 222)
	)
	(via
		(at 209.4565 159.25)
		(size 0.45)
		(drill 0.1)
		(layers "F.Cu" "B.Cu")
		(teardrops
			(best_length_ratio 0.4)
			(max_length 1)
			(best_width_ratio 0.9)
			(max_width 2)
			(curved_edges yes)
			(filter_ratio 0.9)
			(enabled yes)
			(allow_two_segments yes)
			(prefer_zone_connections yes)
		)
		(net 222)
	)
	(segment
		(start 201.430951 140.875865)
		(end 209.5805 149.025414)
		(width 0.202)
		(layer "B.Cu")
		(net 222)
	)
	(segment
		(start 198.625042 138.069956)
		(end 200.891921 140.336835)
		(width 0.202)
		(layer "B.Cu")
		(net 222)
	)
	(segment
		(start 209.5805 149.025414)
		(end 209.5805 159.126)
		(width 0.202)
		(layer "B.Cu")
		(net 222)
	)
	(segment
		(start 198.192999 138.069956)
		(end 198.625042 138.069956)
		(width 0.202)
		(layer "B.Cu")
		(net 222)
	)
	(segment
		(start 200.891921 140.736073)
		(end 201.031713 140.875865)
		(width 0.202)
		(layer "B.Cu")
		(net 222)
	)
	(segment
		(start 209.5805 159.126)
		(end 209.4565 159.25)
		(width 0.202)
		(layer "B.Cu")
		(net 222)
	)
	(arc
		(start 200.891921 140.336835)
		(mid 200.933263 140.436645)
		(end 200.891921 140.536454)
		(width 0.202)
		(layer "B.Cu")
		(net 222)
	)
	(arc
		(start 200.891921 140.536454)
		(mid 200.850579 140.636263)
		(end 200.891921 140.736073)
		(width 0.202)
		(layer "B.Cu")
		(net 222)
	)
	(arc
		(start 201.231332 140.875865)
		(mid 201.331141 140.834523)
		(end 201.430951 140.875865)
		(width 0.202)
		(layer "B.Cu")
		(net 222)
	)
	(arc
		(start 201.031713 140.875865)
		(mid 201.131523 140.917207)
		(end 201.231332 140.875865)
		(width 0.202)
		(layer "B.Cu")
		(net 222)
	)
	(segment
		(start 210.025 169.41)
		(end 210.025 168.685)
		(width 0.202)
		(layer "F.Cu")
		(net 225)
	)
	(segment
		(start 210.405566 170.3805)
		(end 209.9695 169.944434)
		(width 0.202)
		(layer "F.Cu")
		(net 225)
	)
	(segment
		(start 211.05 170.2565)
		(end 210.926 170.3805)
		(width 0.202)
		(layer "F.Cu")
		(net 225)
	)
	(segment
		(start 209.9695 169.4655)
		(end 210.025 169.41)
		(width 0.202)
		(layer "F.Cu")
		(net 225)
	)
	(segment
		(start 209.9695 169.944434)
		(end 209.9695 169.4655)
		(width 0.202)
		(layer "F.Cu")
		(net 225)
	)
	(segment
		(start 210.926 170.3805)
		(end 210.405566 170.3805)
		(width 0.202)
		(layer "F.Cu")
		(net 225)
	)
	(via
		(at 211.05 170.2565)
		(size 0.45)
		(drill 0.1)
		(layers "F.Cu" "B.Cu")
		(teardrops
			(best_length_ratio 0.4)
			(max_length 1)
			(best_width_ratio 0.9)
			(max_width 2)
			(curved_edges yes)
			(filter_ratio 0.9)
			(enabled yes)
			(allow_two_segments yes)
			(prefer_zone_connections yes)
		)
		(net 225)
	)
	(segment
		(start 208.955566 168.7805)
		(end 210.555566 170.3805)
		(width 0.202)
		(layer "B.Cu")
		(net 225)
	)
	(segment
		(start 182.930566 141.7555)
		(end 189.530566 148.3555)
		(width 0.202)
		(layer "B.Cu")
		(net 225)
	)
	(segment
		(start 199.0695 167.019434)
		(end 201.605566 169.5555)
		(width 0.202)
		(layer "B.Cu")
		(net 225)
	)
	(segment
		(start 119.4555 135.079434)
		(end 126.169434 128.3655)
		(width 0.202)
		(layer "B.Cu")
		(net 225)
	)
	(segment
		(start 201.605566 169.5555)
		(end 205.419434 169.5555)
		(width 0.202)
		(layer "B.Cu")
		(net 225)
	)
	(segment
		(start 210.555566 170.3805)
		(end 210.926 170.3805)
		(width 0.202)
		(layer "B.Cu")
		(net 225)
	)
	(segment
		(start 189.530566 148.3555)
		(end 195.055566 148.3555)
		(width 0.202)
		(layer "B.Cu")
		(net 225)
	)
	(segment
		(start 195.055566 148.3555)
		(end 199.0695 152.369434)
		(width 0.202)
		(layer "B.Cu")
		(net 225)
	)
	(segment
		(start 210.926 170.3805)
		(end 211.05 170.2565)
		(width 0.202)
		(layer "B.Cu")
		(net 225)
	)
	(segment
		(start 206.194434 168.7805)
		(end 208.955566 168.7805)
		(width 0.202)
		(layer "B.Cu")
		(net 225)
	)
	(segment
		(start 119.4 145.3605)
		(end 119.4555 145.305)
		(width 0.202)
		(layer "B.Cu")
		(net 225)
	)
	(segment
		(start 205.419434 169.5555)
		(end 206.194434 168.7805)
		(width 0.202)
		(layer "B.Cu")
		(net 225)
	)
	(segment
		(start 155.640566 128.3655)
		(end 169.030566 141.7555)
		(width 0.202)
		(layer "B.Cu")
		(net 225)
	)
	(segment
		(start 199.0695 152.369434)
		(end 199.0695 167.019434)
		(width 0.202)
		(layer "B.Cu")
		(net 225)
	)
	(segment
		(start 119.4555 145.305)
		(end 119.4555 135.079434)
		(width 0.202)
		(layer "B.Cu")
		(net 225)
	)
	(segment
		(start 169.030566 141.7555)
		(end 182.930566 141.7555)
		(width 0.202)
		(layer "B.Cu")
		(net 225)
	)
	(segment
		(start 126.169434 128.3655)
		(end 155.640566 128.3655)
		(width 0.202)
		(layer "B.Cu")
		(net 225)
	)
	(segment
		(start 209.5805 169.4655)
		(end 209.525 169.41)
		(width 0.202)
		(layer "F.Cu")
		(net 227)
	)
	(segment
		(start 210.244434 170.7695)
		(end 209.5805 170.105566)
		(width 0.202)
		(layer "F.Cu")
		(net 227)
	)
	(segment
		(start 211.05 170.8935)
		(end 210.926 170.7695)
		(width 0.202)
		(layer "F.Cu")
		(net 227)
	)
	(segment
		(start 210.926 170.7695)
		(end 210.244434 170.7695)
		(width 0.202)
		(layer "F.Cu")
		(net 227)
	)
	(segment
		(start 209.5805 170.105566)
		(end 209.5805 169.4655)
		(width 0.202)
		(layer "F.Cu")
		(net 227)
	)
	(segment
		(start 209.525 169.41)
		(end 209.525 168.685)
		(width 0.202)
		(layer "F.Cu")
		(net 227)
	)
	(via
		(at 211.05 170.8935)
		(size 0.45)
		(drill 0.1)
		(layers "F.Cu" "B.Cu")
		(teardrops
			(best_length_ratio 0.4)
			(max_length 1)
			(best_width_ratio 0.9)
			(max_width 2)
			(curved_edges yes)
			(filter_ratio 0.9)
			(enabled yes)
			(allow_two_segments yes)
			(prefer_zone_connections yes)
		)
		(net 227)
	)
	(segment
		(start 198.6805 152.530566)
		(end 198.6805 167.180566)
		(width 0.202)
		(layer "B.Cu")
		(net 227)
	)
	(segment
		(start 210.394434 170.7695)
		(end 210.926 170.7695)
		(width 0.202)
		(layer "B.Cu")
		(net 227)
	)
	(segment
		(start 205.580566 169.9445)
		(end 206.355566 169.1695)
		(width 0.202)
		(layer "B.Cu")
		(net 227)
	)
	(segment
		(start 168.869434 142.1445)
		(end 182.769434 142.1445)
		(width 0.202)
		(layer "B.Cu")
		(net 227)
	)
	(segment
		(start 206.355566 169.1695)
		(end 208.794434 169.1695)
		(width 0.202)
		(layer "B.Cu")
		(net 227)
	)
	(segment
		(start 208.794434 169.1695)
		(end 210.394434 170.7695)
		(width 0.202)
		(layer "B.Cu")
		(net 227)
	)
	(segment
		(start 210.926 170.7695)
		(end 211.05 170.8935)
		(width 0.202)
		(layer "B.Cu")
		(net 227)
	)
	(segment
		(start 119.9 145.3605)
		(end 119.8445 145.305)
		(width 0.202)
		(layer "B.Cu")
		(net 227)
	)
	(segment
		(start 189.369434 148.7445)
		(end 194.894434 148.7445)
		(width 0.202)
		(layer "B.Cu")
		(net 227)
	)
	(segment
		(start 198.6805 167.180566)
		(end 201.444434 169.9445)
		(width 0.202)
		(layer "B.Cu")
		(net 227)
	)
	(segment
		(start 119.8445 145.305)
		(end 119.8445 135.240566)
		(width 0.202)
		(layer "B.Cu")
		(net 227)
	)
	(segment
		(start 119.8445 135.240566)
		(end 126.330566 128.7545)
		(width 0.202)
		(layer "B.Cu")
		(net 227)
	)
	(segment
		(start 194.894434 148.7445)
		(end 198.6805 152.530566)
		(width 0.202)
		(layer "B.Cu")
		(net 227)
	)
	(segment
		(start 126.330566 128.7545)
		(end 155.479434 128.7545)
		(width 0.202)
		(layer "B.Cu")
		(net 227)
	)
	(segment
		(start 182.769434 142.1445)
		(end 189.369434 148.7445)
		(width 0.202)
		(layer "B.Cu")
		(net 227)
	)
	(segment
		(start 201.444434 169.9445)
		(end 205.580566 169.9445)
		(width 0.202)
		(layer "B.Cu")
		(net 227)
	)
	(segment
		(start 155.479434 128.7545)
		(end 168.869434 142.1445)
		(width 0.202)
		(layer "B.Cu")
		(net 227)
	)
	(segment
		(start 178.35 104.76)
		(end 178.35 104.35)
		(width 0.125)
		(layer "F.Cu")
		(net 228)
	)
	(segment
		(start 176.795923 104.864077)
		(end 176.4 105.26)
		(width 0.125)
		(layer "F.Cu")
		(net 228)
	)
	(segment
		(start 178.245923 104.864077)
		(end 178.35 104.76)
		(width 0.125)
		(layer "F.Cu")
		(net 228)
	)
	(segment
		(start 177.72973 104.864077)
		(end 176.795923 104.864077)
		(width 0.125)
		(layer "F.Cu")
		(net 228)
	)
	(segment
		(start 176.4 107.46)
		(end 176.6 107.66)
		(width 0.125)
		(layer "F.Cu")
		(net 228)
	)
	(segment
		(start 177.72973 104.864077)
		(end 178.245923 104.864077)
		(width 0.125)
		(layer "F.Cu")
		(net 228)
	)
	(segment
		(start 176.4 105.26)
		(end 176.4 107.46)
		(width 0.125)
		(layer "F.Cu")
		(net 228)
	)
	(segment
		(start 176.6 107.66)
		(end 177.04 107.66)
		(width 0.125)
		(layer "F.Cu")
		(net 228)
	)
	(via
		(at 177.72973 104.864077)
		(size 0.45)
		(drill 0.1)
		(layers "F.Cu" "B.Cu")
		(remove_unused_layers yes)
		(keep_end_layers yes)
		(zone_layer_connections)
		(teardrops
			(best_length_ratio 0.4)
			(max_length 1)
			(best_width_ratio 0.9)
			(max_width 2)
			(curved_edges yes)
			(filter_ratio 0.9)
			(enabled yes)
			(allow_two_segments yes)
			(prefer_zone_connections yes)
		)
		(net 228)
	)
	(segment
		(start 177.72973 104.864077)
		(end 177.975653 105.11)
		(width 0.125)
		(layer "B.Cu")
		(net 228)
	)
	(segment
		(start 177.975653 105.11)
		(end 178.84 105.11)
		(width 0.125)
		(layer "B.Cu")
		(net 228)
	)
	(segment
		(start 208.875 128.82)
		(end 208.5695 128.5145)
		(width 0.202)
		(layer "F.Cu")
		(net 229)
	)
	(segment
		(start 207.524 128.5145)
		(end 207.4 128.6385)
		(width 0.202)
		(layer "F.Cu")
		(net 229)
	)
	(segment
		(start 208.9 128.82)
		(end 208.875 128.82)
		(width 0.202)
		(layer "F.Cu")
		(net 229)
	)
	(segment
		(start 208.5695 128.5145)
		(end 207.524 128.5145)
		(width 0.202)
		(layer "F.Cu")
		(net 229)
	)
	(via
		(at 207.4 128.6385)
		(size 0.45)
		(drill 0.1)
		(layers "F.Cu" "B.Cu")
		(teardrops
			(best_length_ratio 0.4)
			(max_length 1)
			(best_width_ratio 0.9)
			(max_width 2)
			(curved_edges yes)
			(filter_ratio 0.9)
			(enabled yes)
			(allow_two_segments yes)
			(prefer_zone_connections yes)
		)
		(net 229)
	)
	(segment
		(start 172.1055 106.719434)
		(end 172.1055 115.080566)
		(width 0.202)
		(layer "B.Cu")
		(net 229)
	)
	(segment
		(start 172.1055 115.080566)
		(end 176.219434 119.1945)
		(width 0.202)
		(layer "B.Cu")
		(net 229)
	)
	(segment
		(start 175.074999 105.86)
		(end 175.019499 105.9155)
		(width 0.202)
		(layer "B.Cu")
		(net 229)
	)
	(segment
		(start 196.019434 119.1945)
		(end 205.339434 128.5145)
		(width 0.202)
		(layer "B.Cu")
		(net 229)
	)
	(segment
		(start 176.219434 119.1945)
		(end 196.019434 119.1945)
		(width 0.202)
		(layer "B.Cu")
		(net 229)
	)
	(segment
		(start 207.276 128.5145)
		(end 207.4 128.6385)
		(width 0.202)
		(layer "B.Cu")
		(net 229)
	)
	(segment
		(start 172.909434 105.9155)
		(end 172.1055 106.719434)
		(width 0.202)
		(layer "B.Cu")
		(net 229)
	)
	(segment
		(start 205.339434 128.5145)
		(end 207.276 128.5145)
		(width 0.202)
		(layer "B.Cu")
		(net 229)
	)
	(segment
		(start 175.019499 105.9155)
		(end 172.909434 105.9155)
		(width 0.202)
		(layer "B.Cu")
		(net 229)
	)
	(segment
		(start 176.2 105.86)
		(end 175.074999 105.86)
		(width 0.202)
		(layer "B.Cu")
		(net 229)
	)
	(segment
		(start 207.524 128.1255)
		(end 207.4 128.0015)
		(width 0.202)
		(layer "F.Cu")
		(net 231)
	)
	(segment
		(start 208.9 127.82)
		(end 208.875 127.82)
		(width 0.202)
		(layer "F.Cu")
		(net 231)
	)
	(segment
		(start 208.5695 128.1255)
		(end 207.524 128.1255)
		(width 0.202)
		(layer "F.Cu")
		(net 231)
	)
	(segment
		(start 208.875 127.82)
		(end 208.5695 128.1255)
		(width 0.202)
		(layer "F.Cu")
		(net 231)
	)
	(via
		(at 207.4 128.0015)
		(size 0.45)
		(drill 0.1)
		(layers "F.Cu" "B.Cu")
		(teardrops
			(best_length_ratio 0.4)
			(max_length 1)
			(best_width_ratio 0.9)
			(max_width 2)
			(curved_edges yes)
			(filter_ratio 0.9)
			(enabled yes)
			(allow_two_segments yes)
			(prefer_zone_connections yes)
		)
		(net 231)
	)
	(segment
		(start 207.276 128.1255)
		(end 207.4 128.0015)
		(width 0.202)
		(layer "B.Cu")
		(net 231)
	)
	(segment
		(start 173.070566 106.3045)
		(end 172.4945 106.880566)
		(width 0.202)
		(layer "B.Cu")
		(net 231)
	)
	(segment
		(start 172.4945 113.593189)
		(end 172.4945 113.693189)
		(width 0.202)
		(layer "B.Cu")
		(net 231)
	)
	(segment
		(start 172.6945 111.893189)
		(end 172.788421 111.893189)
		(width 0.202)
		(layer "B.Cu")
		(net 231)
	)
	(segment
		(start 172.4945 106.880566)
		(end 172.4945 111.693189)
		(width 0.202)
		(layer "B.Cu")
		(net 231)
	)
	(segment
		(start 172.6945 112.893189)
		(end 172.788448 112.893189)
		(width 0.202)
		(layer "B.Cu")
		(net 231)
	)
	(segment
		(start 176.380566 118.8055)
		(end 196.180566 118.8055)
		(width 0.202)
		(layer "B.Cu")
		(net 231)
	)
	(segment
		(start 172.788421 112.393189)
		(end 172.6945 112.393189)
		(width 0.202)
		(layer "B.Cu")
		(net 231)
	)
	(segment
		(start 172.788448 113.393189)
		(end 172.6945 113.393189)
		(width 0.202)
		(layer "B.Cu")
		(net 231)
	)
	(segment
		(start 172.4945 113.693189)
		(end 172.4945 113.95)
		(width 0.202)
		(layer "B.Cu")
		(net 231)
	)
	(segment
		(start 172.4945 112.593189)
		(end 172.4945 112.693189)
		(width 0.202)
		(layer "B.Cu")
		(net 231)
	)
	(segment
		(start 196.180566 118.8055)
		(end 205.500566 128.1255)
		(width 0.202)
		(layer "B.Cu")
		(net 231)
	)
	(segment
		(start 176.2 106.36)
		(end 175.074999 106.36)
		(width 0.202)
		(layer "B.Cu")
		(net 231)
	)
	(segment
		(start 175.019499 106.3045)
		(end 173.070566 106.3045)
		(width 0.202)
		(layer "B.Cu")
		(net 231)
	)
	(segment
		(start 172.4945 113.95)
		(end 172.4945 114.919434)
		(width 0.202)
		(layer "B.Cu")
		(net 231)
	)
	(segment
		(start 172.988421 112.093189)
		(end 172.988421 112.193189)
		(width 0.202)
		(layer "B.Cu")
		(net 231)
	)
	(segment
		(start 172.988448 113.093189)
		(end 172.988448 113.193189)
		(width 0.202)
		(layer "B.Cu")
		(net 231)
	)
	(segment
		(start 172.4945 114.919434)
		(end 176.380566 118.8055)
		(width 0.202)
		(layer "B.Cu")
		(net 231)
	)
	(segment
		(start 205.500566 128.1255)
		(end 207.276 128.1255)
		(width 0.202)
		(layer "B.Cu")
		(net 231)
	)
	(segment
		(start 175.074999 106.36)
		(end 175.019499 106.3045)
		(width 0.202)
		(layer "B.Cu")
		(net 231)
	)
	(arc
		(start 172.6945 112.393189)
		(mid 172.553079 112.451768)
		(end 172.4945 112.593189)
		(width 0.202)
		(layer "B.Cu")
		(net 231)
	)
	(arc
		(start 172.4945 111.693189)
		(mid 172.553079 111.83461)
		(end 172.6945 111.893189)
		(width 0.202)
		(layer "B.Cu")
		(net 231)
	)
	(arc
		(start 172.788448 112.893189)
		(mid 172.929869 112.951768)
		(end 172.988448 113.093189)
		(width 0.202)
		(layer "B.Cu")
		(net 231)
	)
	(arc
		(start 172.6945 113.393189)
		(mid 172.553079 113.451768)
		(end 172.4945 113.593189)
		(width 0.202)
		(layer "B.Cu")
		(net 231)
	)
	(arc
		(start 172.988448 113.193189)
		(mid 172.929869 113.33461)
		(end 172.788448 113.393189)
		(width 0.202)
		(layer "B.Cu")
		(net 231)
	)
	(arc
		(start 172.788421 111.893189)
		(mid 172.929842 111.951768)
		(end 172.988421 112.093189)
		(width 0.202)
		(layer "B.Cu")
		(net 231)
	)
	(arc
		(start 172.988421 112.193189)
		(mid 172.929842 112.33461)
		(end 172.788421 112.393189)
		(width 0.202)
		(layer "B.Cu")
		(net 231)
	)
	(arc
		(start 172.4945 112.693189)
		(mid 172.553079 112.83461)
		(end 172.6945 112.893189)
		(width 0.202)
		(layer "B.Cu")
		(net 231)
	)
	(segment
		(start 177.980566 127.2055)
		(end 165.8945 115.119434)
		(width 0.202)
		(layer "F.Cu")
		(net 237)
	)
	(segment
		(start 186.9695 160.705566)
		(end 187.880566 159.7945)
		(width 0.202)
		(layer "F.Cu")
		(net 237)
	)
	(segment
		(start 165.8945 108.829188)
		(end 165.8945 108.659188)
		(width 0.202)
		(layer "F.Cu")
		(net 237)
	)
	(segment
		(start 165.8945 100.780566)
		(end 172.370566 94.3045)
		(width 0.202)
		(layer "F.Cu")
		(net 237)
	)
	(segment
		(start 166.1745 109.279188)
		(end 166.1745 109.109188)
		(width 0.202)
		(layer "F.Cu")
		(net 237)
	)
	(segment
		(start 165.8945 107.15)
		(end 165.8945 100.780566)
		(width 0.202)
		(layer "F.Cu")
		(net 237)
	)
	(segment
		(start 165.8945 107.929188)
		(end 165.8945 107.759188)
		(width 0.202)
		(layer "F.Cu")
		(net 237)
	)
	(segment
		(start 172.370566 94.3045)
		(end 173.476 94.3045)
		(width 0.202)
		(layer "F.Cu")
		(net 237)
	)
	(segment
		(start 165.8945 107.759188)
		(end 165.8945 107.15)
		(width 0.202)
		(layer "F.Cu")
		(net 237)
	)
	(segment
		(start 173.476 94.3045)
		(end 173.6 94.4285)
		(width 0.202)
		(layer "F.Cu")
		(net 237)
	)
	(segment
		(start 187.025 163.135)
		(end 187.025 162.41)
		(width 0.202)
		(layer "F.Cu")
		(net 237)
	)
	(segment
		(start 187.880566 159.7945)
		(end 191.076 159.7945)
		(width 0.202)
		(layer "F.Cu")
		(net 237)
	)
	(segment
		(start 187.025 162.41)
		(end 186.9695 162.3545)
		(width 0.202)
		(layer "F.Cu")
		(net 237)
	)
	(segment
		(start 166.1745 108.379188)
		(end 166.1745 108.209188)
		(width 0.202)
		(layer "F.Cu")
		(net 237)
	)
	(segment
		(start 186.8 127.0815)
		(end 186.676 127.2055)
		(width 0.202)
		(layer "F.Cu")
		(net 237)
	)
	(segment
		(start 186.9695 162.3545)
		(end 186.9695 160.705566)
		(width 0.202)
		(layer "F.Cu")
		(net 237)
	)
	(segment
		(start 191.076 159.7945)
		(end 191.2 159.9185)
		(width 0.202)
		(layer "F.Cu")
		(net 237)
	)
	(segment
		(start 186.676 127.2055)
		(end 177.980566 127.2055)
		(width 0.202)
		(layer "F.Cu")
		(net 237)
	)
	(segment
		(start 165.8945 115.119434)
		(end 165.8945 109.559188)
		(width 0.202)
		(layer "F.Cu")
		(net 237)
	)
	(via
		(at 186.8 127.0815)
		(size 0.45)
		(drill 0.1)
		(layers "F.Cu" "B.Cu")
		(teardrops
			(best_length_ratio 0.4)
			(max_length 1)
			(best_width_ratio 0.9)
			(max_width 2)
			(curved_edges yes)
			(filter_ratio 0.9)
			(enabled yes)
			(allow_two_segments yes)
			(prefer_zone_connections yes)
		)
		(net 237)
	)
	(via
		(at 191.2 159.9185)
		(size 0.45)
		(drill 0.1)
		(layers "F.Cu" "B.Cu")
		(teardrops
			(best_length_ratio 0.4)
			(max_length 1)
			(best_width_ratio 0.9)
			(max_width 2)
			(curved_edges yes)
			(filter_ratio 0.9)
			(enabled yes)
			(allow_two_segments yes)
			(prefer_zone_connections yes)
		)
		(net 237)
	)
	(via
		(at 173.6 94.4285)
		(size 0.45)
		(drill 0.1)
		(layers "F.Cu" "B.Cu")
		(teardrops
			(best_length_ratio 0.4)
			(max_length 1)
			(best_width_ratio 0.9)
			(max_width 2)
			(curved_edges yes)
			(filter_ratio 0.9)
			(enabled yes)
			(allow_two_segments yes)
			(prefer_zone_connections yes)
		)
		(net 237)
	)
	(arc
		(start 166.1745 108.209188)
		(mid 166.133495 108.110193)
		(end 166.0345 108.069188)
		(width 0.202)
		(layer "F.Cu")
		(net 237)
	)
	(arc
		(start 166.1745 109.109188)
		(mid 166.133495 109.010193)
		(end 166.0345 108.969188)
		(width 0.202)
		(layer "F.Cu")
		(net 237)
	)
	(arc
		(start 166.0345 108.969188)
		(mid 165.935505 108.928183)
		(end 165.8945 108.829188)
		(width 0.202)
		(layer "F.Cu")
		(net 237)
	)
	(arc
		(start 166.0345 108.519188)
		(mid 166.133495 108.478183)
		(end 166.1745 108.379188)
		(width 0.202)
		(layer "F.Cu")
		(net 237)
	)
	(arc
		(start 166.0345 109.419188)
		(mid 166.133495 109.378183)
		(end 166.1745 109.279188)
		(width 0.202)
		(layer "F.Cu")
		(net 237)
	)
	(arc
		(start 165.8945 109.559188)
		(mid 165.935505 109.460193)
		(end 166.0345 109.419188)
		(width 0.202)
		(layer "F.Cu")
		(net 237)
	)
	(arc
		(start 165.8945 108.659188)
		(mid 165.935505 108.560193)
		(end 166.0345 108.519188)
		(width 0.202)
		(layer "F.Cu")
		(net 237)
	)
	(arc
		(start 166.0345 108.069188)
		(mid 165.935505 108.028183)
		(end 165.8945 107.929188)
		(width 0.202)
		(layer "F.Cu")
		(net 237)
	)
	(segment
		(start 175.074999 94.36)
		(end 175.019499 94.3045)
		(width 0.202)
		(layer "B.Cu")
		(net 237)
	)
	(segment
		(start 175.019499 94.3045)
		(end 173.724 94.3045)
		(width 0.202)
		(layer "B.Cu")
		(net 237)
	)
	(segment
		(start 173.724 94.3045)
		(end 173.6 94.4285)
		(width 0.202)
		(layer "B.Cu")
		(net 237)
	)
	(segment
		(start 176.2 94.36)
		(end 175.074999 94.36)
		(width 0.202)
		(layer "B.Cu")
		(net 237)
	)
	(segment
		(start 192.287 159.377458)
		(end 191.877458 159.787)
		(width 0.178)
		(layer "In5.Cu")
		(net 237)
	)
	(segment
		(start 192.287 145.677458)
		(end 192.287 159.377458)
		(width 0.178)
		(layer "In5.Cu")
		(net 237)
	)
	(segment
		(start 198.887 139.077458)
		(end 192.287 145.677458)
		(width 0.178)
		(layer "In5.Cu")
		(net 237)
	)
	(segment
		(start 186.9315 127.213)
		(end 193.977458 127.213)
		(width 0.178)
		(layer "In5.Cu")
		(net 237)
	)
	(segment
		(start 186.8 127.0815)
		(end 186.9315 127.213)
		(width 0.178)
		(layer "In5.Cu")
		(net 237)
	)
	(segment
		(start 193.977458 127.213)
		(end 198.887 132.122542)
		(width 0.178)
		(layer "In5.Cu")
		(net 237)
	)
	(segment
		(start 198.887 132.122542)
		(end 198.887 139.077458)
		(width 0.178)
		(layer "In5.Cu")
		(net 237)
	)
	(segment
		(start 191.3315 159.787)
		(end 191.2 159.9185)
		(width 0.178)
		(layer "In5.Cu")
		(net 237)
	)
	(segment
		(start 191.877458 159.787)
		(end 191.3315 159.787)
		(width 0.178)
		(layer "In5.Cu")
		(net 237)
	)
	(segment
		(start 177.819434 127.5945)
		(end 186.676 127.5945)
		(width 0.202)
		(layer "F.Cu")
		(net 239)
	)
	(segment
		(start 165.5055 100.619434)
		(end 165.5055 115.280566)
		(width 0.202)
		(layer "F.Cu")
		(net 239)
	)
	(segment
		(start 186.525 162.41)
		(end 186.5805 162.3545)
		(width 0.202)
		(layer "F.Cu")
		(net 239)
	)
	(segment
		(start 186.5805 162.3545)
		(end 186.5805 160.544434)
		(width 0.202)
		(layer "F.Cu")
		(net 239)
	)
	(segment
		(start 191.076 159.4055)
		(end 191.2 159.2815)
		(width 0.202)
		(layer "F.Cu")
		(net 239)
	)
	(segment
		(start 186.5805 160.544434)
		(end 187.719434 159.4055)
		(width 0.202)
		(layer "F.Cu")
		(net 239)
	)
	(segment
		(start 186.676 127.5945)
		(end 186.8 127.7185)
		(width 0.202)
		(layer "F.Cu")
		(net 239)
	)
	(segment
		(start 186.525 163.135)
		(end 186.525 162.41)
		(width 0.202)
		(layer "F.Cu")
		(net 239)
	)
	(segment
		(start 172.209434 93.9155)
		(end 165.5055 100.619434)
		(width 0.202)
		(layer "F.Cu")
		(net 239)
	)
	(segment
		(start 187.719434 159.4055)
		(end 191.076 159.4055)
		(width 0.202)
		(layer "F.Cu")
		(net 239)
	)
	(segment
		(start 165.5055 115.280566)
		(end 177.819434 127.5945)
		(width 0.202)
		(layer "F.Cu")
		(net 239)
	)
	(segment
		(start 173.476 93.9155)
		(end 172.209434 93.9155)
		(width 0.202)
		(layer "F.Cu")
		(net 239)
	)
	(segment
		(start 173.6 93.7915)
		(end 173.476 93.9155)
		(width 0.202)
		(layer "F.Cu")
		(net 239)
	)
	(via
		(at 191.2 159.2815)
		(size 0.45)
		(drill 0.1)
		(layers "F.Cu" "B.Cu")
		(teardrops
			(best_length_ratio 0.4)
			(max_length 1)
			(best_width_ratio 0.9)
			(max_width 2)
			(curved_edges yes)
			(filter_ratio 0.9)
			(enabled yes)
			(allow_two_segments yes)
			(prefer_zone_connections yes)
		)
		(net 239)
	)
	(via
		(at 186.8 127.7185)
		(size 0.45)
		(drill 0.1)
		(layers "F.Cu" "B.Cu")
		(teardrops
			(best_length_ratio 0.4)
			(max_length 1)
			(best_width_ratio 0.9)
			(max_width 2)
			(curved_edges yes)
			(filter_ratio 0.9)
			(enabled yes)
			(allow_two_segments yes)
			(prefer_zone_connections yes)
		)
		(net 239)
	)
	(via
		(at 173.6 93.7915)
		(size 0.45)
		(drill 0.1)
		(layers "F.Cu" "B.Cu")
		(teardrops
			(best_length_ratio 0.4)
			(max_length 1)
			(best_width_ratio 0.9)
			(max_width 2)
			(curved_edges yes)
			(filter_ratio 0.9)
			(enabled yes)
			(allow_two_segments yes)
			(prefer_zone_connections yes)
		)
		(net 239)
	)
	(segment
		(start 173.724 93.9155)
		(end 173.6 93.7915)
		(width 0.202)
		(layer "B.Cu")
		(net 239)
	)
	(segment
		(start 175.019499 93.9155)
		(end 173.724 93.9155)
		(width 0.202)
		(layer "B.Cu")
		(net 239)
	)
	(segment
		(start 175.074999 93.86)
		(end 175.019499 93.9155)
		(width 0.202)
		(layer "B.Cu")
		(net 239)
	)
	(segment
		(start 176.2 93.86)
		(end 175.074999 93.86)
		(width 0.202)
		(layer "B.Cu")
		(net 239)
	)
	(segment
		(start 198.513 138.922542)
		(end 191.913 145.522542)
		(width 0.178)
		(layer "In5.Cu")
		(net 239)
	)
	(segment
		(start 191.913 145.522542)
		(end 191.913 159.222542)
		(width 0.178)
		(layer "In5.Cu")
		(net 239)
	)
	(segment
		(start 191.913 159.222542)
		(end 191.722542 159.413)
		(width 0.178)
		(layer "In5.Cu")
		(net 239)
	)
	(segment
		(start 193.822542 127.587)
		(end 198.513 132.277458)
		(width 0.178)
		(layer "In5.Cu")
		(net 239)
	)
	(segment
		(start 186.8 127.7185)
		(end 186.9315 127.587)
		(width 0.178)
		(layer "In5.Cu")
		(net 239)
	)
	(segment
		(start 191.722542 159.413)
		(end 191.3315 159.413)
		(width 0.178)
		(layer "In5.Cu")
		(net 239)
	)
	(segment
		(start 198.513 132.277458)
		(end 198.513 138.922542)
		(width 0.178)
		(layer "In5.Cu")
		(net 239)
	)
	(segment
		(start 186.9315 127.587)
		(end 193.822542 127.587)
		(width 0.178)
		(layer "In5.Cu")
		(net 239)
	)
	(segment
		(start 191.3315 159.413)
		(end 191.2 159.2815)
		(width 0.178)
		(layer "In5.Cu")
		(net 239)
	)
	(segment
		(start 187.025 168.685)
		(end 187.025 167.96)
		(width 0.202)
		(layer "F.Cu")
		(net 241)
	)
	(segment
		(start 187.025 167.96)
		(end 186.9695 167.9045)
		(width 0.202)
		(layer "F.Cu")
		(net 241)
	)
	(segment
		(start 186.9695 167.124)
		(end 187.0935 167)
		(width 0.202)
		(layer "F.Cu")
		(net 241)
	)
	(segment
		(start 186.9695 167.9045)
		(end 186.9695 167.124)
		(width 0.202)
		(layer "F.Cu")
		(net 241)
	)
	(via
		(at 187.0935 167)
		(size 0.45)
		(drill 0.1)
		(layers "F.Cu" "B.Cu")
		(teardrops
			(best_length_ratio 0.4)
			(max_length 1)
			(best_width_ratio 0.9)
			(max_width 2)
			(curved_edges yes)
			(filter_ratio 0.9)
			(enabled yes)
			(allow_two_segments yes)
			(prefer_zone_connections yes)
		)
		(net 241)
	)
	(via
		(at 174.3 95.9285)
		(size 0.45)
		(drill 0.1)
		(layers "F.Cu" "B.Cu")
		(teardrops
			(best_length_ratio 0.4)
			(max_length 1)
			(best_width_ratio 0.9)
			(max_width 2)
			(curved_edges yes)
			(filter_ratio 0.9)
			(enabled yes)
			(allow_two_segments yes)
			(prefer_zone_connections yes)
		)
		(net 241)
	)
	(segment
		(start 174.424 95.8045)
		(end 174.3 95.9285)
		(width 0.202)
		(layer "B.Cu")
		(net 241)
	)
	(segment
		(start 175.019499 95.8045)
		(end 174.424 95.8045)
		(width 0.202)
		(layer "B.Cu")
		(net 241)
	)
	(segment
		(start 175.074999 95.86)
		(end 175.019499 95.8045)
		(width 0.202)
		(layer "B.Cu")
		(net 241)
	)
	(segment
		(start 176.2 95.86)
		(end 175.074999 95.86)
		(width 0.202)
		(layer "B.Cu")
		(net 241)
	)
	(segment
		(start 167.688348 108.639808)
		(end 167.688348 108.86846)
		(width 0.178)
		(layer "In5.Cu")
		(net 241)
	)
	(segment
		(start 174.1685 95.797)
		(end 172.067458 95.797)
		(width 0.178)
		(layer "In5.Cu")
		(net 241)
	)
	(segment
		(start 167.417 116.952542)
		(end 180.287 129.822542)
		(width 0.178)
		(layer "In5.Cu")
		(net 241)
	)
	(segment
		(start 180.287 129.822542)
		(end 180.287 140.522542)
		(width 0.178)
		(layer "In5.Cu")
		(net 241)
	)
	(segment
		(start 167.417 110.959042)
		(end 167.417 116.952542)
		(width 0.178)
		(layer "In5.Cu")
		(net 241)
	)
	(segment
		(start 167.688348 107.639808)
		(end 167.688348 107.86846)
		(width 0.178)
		(layer "In5.Cu")
		(net 241)
	)
	(segment
		(start 174.3 95.9285)
		(end 174.1685 95.797)
		(width 0.178)
		(layer "In5.Cu")
		(net 241)
	)
	(segment
		(start 167.417 109.139808)
		(end 167.417 109.36846)
		(width 0.178)
		(layer "In5.Cu")
		(net 241)
	)
	(segment
		(start 185.337 145.572542)
		(end 185.337 164.772542)
		(width 0.178)
		(layer "In5.Cu")
		(net 241)
	)
	(segment
		(start 186.962 166.8685)
		(end 187.0935 167)
		(width 0.178)
		(layer "In5.Cu")
		(net 241)
	)
	(segment
		(start 167.417 109.36846)
		(end 167.417 110.959042)
		(width 0.178)
		(layer "In5.Cu")
		(net 241)
	)
	(segment
		(start 180.287 140.522542)
		(end 185.337 145.572542)
		(width 0.178)
		(layer "In5.Cu")
		(net 241)
	)
	(segment
		(start 167.417 108.139808)
		(end 167.417 108.36846)
		(width 0.178)
		(layer "In5.Cu")
		(net 241)
	)
	(segment
		(start 186.962 166.397542)
		(end 186.962 166.8685)
		(width 0.178)
		(layer "In5.Cu")
		(net 241)
	)
	(segment
		(start 185.337 164.772542)
		(end 186.962 166.397542)
		(width 0.178)
		(layer "In5.Cu")
		(net 241)
	)
	(segment
		(start 172.067458 95.797)
		(end 167.417 100.447458)
		(width 0.178)
		(layer "In5.Cu")
		(net 241)
	)
	(segment
		(start 167.417 100.447458)
		(end 167.417 107.36846)
		(width 0.178)
		(layer "In5.Cu")
		(net 241)
	)
	(arc
		(start 167.552674 107.504134)
		(mid 167.64861 107.543872)
		(end 167.688348 107.639808)
		(width 0.178)
		(layer "In5.Cu")
		(net 241)
	)
	(arc
		(start 167.688348 107.86846)
		(mid 167.64861 107.964396)
		(end 167.552674 108.004134)
		(width 0.178)
		(layer "In5.Cu")
		(net 241)
	)
	(arc
		(start 167.552674 108.004134)
		(mid 167.456738 108.043872)
		(end 167.417 108.139808)
		(width 0.178)
		(layer "In5.Cu")
		(net 241)
	)
	(arc
		(start 167.552674 108.504134)
		(mid 167.64861 108.543872)
		(end 167.688348 108.639808)
		(width 0.178)
		(layer "In5.Cu")
		(net 241)
	)
	(arc
		(start 167.688348 108.86846)
		(mid 167.64861 108.964396)
		(end 167.552674 109.004134)
		(width 0.178)
		(layer "In5.Cu")
		(net 241)
	)
	(arc
		(start 167.552674 109.004134)
		(mid 167.456738 109.043872)
		(end 167.417 109.139808)
		(width 0.178)
		(layer "In5.Cu")
		(net 241)
	)
	(arc
		(start 167.417 108.36846)
		(mid 167.456738 108.464396)
		(end 167.552674 108.504134)
		(width 0.178)
		(layer "In5.Cu")
		(net 241)
	)
	(arc
		(start 167.417 107.36846)
		(mid 167.456738 107.464396)
		(end 167.552674 107.504134)
		(width 0.178)
		(layer "In5.Cu")
		(net 241)
	)
	(segment
		(start 186.525 167.96)
		(end 186.5805 167.9045)
		(width 0.202)
		(layer "F.Cu")
		(net 242)
	)
	(segment
		(start 186.5805 167.9045)
		(end 186.5805 167.124)
		(width 0.202)
		(layer "F.Cu")
		(net 242)
	)
	(segment
		(start 186.525 168.685)
		(end 186.525 167.96)
		(width 0.202)
		(layer "F.Cu")
		(net 242)
	)
	(segment
		(start 186.5805 167.124)
		(end 186.4565 167)
		(width 0.202)
		(layer "F.Cu")
		(net 242)
	)
	(via
		(at 174.3 95.2915)
		(size 0.45)
		(drill 0.1)
		(layers "F.Cu" "B.Cu")
		(teardrops
			(best_length_ratio 0.4)
			(max_length 1)
			(best_width_ratio 0.9)
			(max_width 2)
			(curved_edges yes)
			(filter_ratio 0.9)
			(enabled yes)
			(allow_two_segments yes)
			(prefer_zone_connections yes)
		)
		(net 242)
	)
	(via
		(at 186.4565 167)
		(size 0.45)
		(drill 0.1)
		(layers "F.Cu" "B.Cu")
		(teardrops
			(best_length_ratio 0.4)
			(max_length 1)
			(best_width_ratio 0.9)
			(max_width 2)
			(curved_edges yes)
			(filter_ratio 0.9)
			(enabled yes)
			(allow_two_segments yes)
			(prefer_zone_connections yes)
		)
		(net 242)
	)
	(segment
		(start 176.2 95.36)
		(end 175.074999 95.36)
		(width 0.202)
		(layer "B.Cu")
		(net 242)
	)
	(segment
		(start 175.019499 95.4155)
		(end 174.424 95.4155)
		(width 0.202)
		(layer "B.Cu")
		(net 242)
	)
	(segment
		(start 175.074999 95.36)
		(end 175.019499 95.4155)
		(width 0.202)
		(layer "B.Cu")
		(net 242)
	)
	(segment
		(start 174.424 95.4155)
		(end 174.3 95.2915)
		(width 0.202)
		(layer "B.Cu")
		(net 242)
	)
	(segment
		(start 167.043 117.107458)
		(end 167.043 100.292542)
		(width 0.178)
		(layer "In5.Cu")
		(net 242)
	)
	(segment
		(start 171.912542 95.423)
		(end 174.1685 95.423)
		(width 0.178)
		(layer "In5.Cu")
		(net 242)
	)
	(segment
		(start 186.588 166.552458)
		(end 184.963 164.927458)
		(width 0.178)
		(layer "In5.Cu")
		(net 242)
	)
	(segment
		(start 167.043 100.292542)
		(end 171.912542 95.423)
		(width 0.178)
		(layer "In5.Cu")
		(net 242)
	)
	(segment
		(start 179.913 129.977458)
		(end 167.043 117.107458)
		(width 0.178)
		(layer "In5.Cu")
		(net 242)
	)
	(segment
		(start 174.1685 95.423)
		(end 174.3 95.2915)
		(width 0.178)
		(layer "In5.Cu")
		(net 242)
	)
	(segment
		(start 179.913 140.677458)
		(end 179.913 129.977458)
		(width 0.178)
		(layer "In5.Cu")
		(net 242)
	)
	(segment
		(start 186.588 166.8685)
		(end 186.588 166.552458)
		(width 0.178)
		(layer "In5.Cu")
		(net 242)
	)
	(segment
		(start 184.963 145.727458)
		(end 179.913 140.677458)
		(width 0.178)
		(layer "In5.Cu")
		(net 242)
	)
	(segment
		(start 184.963 164.927458)
		(end 184.963 145.727458)
		(width 0.178)
		(layer "In5.Cu")
		(net 242)
	)
	(segment
		(start 186.4565 167)
		(end 186.588 166.8685)
		(width 0.178)
		(layer "In5.Cu")
		(net 242)
	)
	(segment
		(start 167.6945 109.06095)
		(end 167.6945 108.855)
		(width 0.202)
		(layer "F.Cu")
		(net 243)
	)
	(segment
		(start 186.8 125.477)
		(end 186.6715 125.6055)
		(width 0.202)
		(layer "F.Cu")
		(net 243)
	)
	(segment
		(start 167.6945 107.835)
		(end 167.6945 107.483608)
		(width 0.202)
		(layer "F.Cu")
		(net 243)
	)
	(segment
		(start 188.4695 161.505566)
		(end 188.880566 161.0945)
		(width 0.202)
		(layer "F.Cu")
		(net 243)
	)
	(segment
		(start 188.880566 161.0945)
		(end 191.876 161.0945)
		(width 0.202)
		(layer "F.Cu")
		(net 243)
	)
	(segment
		(start 167.6945 114.219434)
		(end 167.6945 109.875)
		(width 0.202)
		(layer "F.Cu")
		(net 243)
	)
	(segment
		(start 173.476 97.3045)
		(end 173.6 97.4285)
		(width 0.202)
		(layer "F.Cu")
		(net 243)
	)
	(segment
		(start 186.6715 125.6055)
		(end 179.080566 125.6055)
		(width 0.202)
		(layer "F.Cu")
		(net 243)
	)
	(segment
		(start 191.876 161.0945)
		(end 192 161.2185)
		(width 0.202)
		(layer "F.Cu")
		(net 243)
	)
	(segment
		(start 167.99855 109.57095)
		(end 167.99855 109.365)
		(width 0.202)
		(layer "F.Cu")
		(net 243)
	)
	(segment
		(start 188.4695 162.3545)
		(end 188.4695 161.505566)
		(width 0.202)
		(layer "F.Cu")
		(net 243)
	)
	(segment
		(start 167.6945 107.483608)
		(end 167.6945 101.580566)
		(width 0.202)
		(layer "F.Cu")
		(net 243)
	)
	(segment
		(start 167.6945 101.580566)
		(end 171.970566 97.3045)
		(width 0.202)
		(layer "F.Cu")
		(net 243)
	)
	(segment
		(start 188.525 163.135)
		(end 188.525 162.41)
		(width 0.202)
		(layer "F.Cu")
		(net 243)
	)
	(segment
		(start 188.525 162.41)
		(end 188.4695 162.3545)
		(width 0.202)
		(layer "F.Cu")
		(net 243)
	)
	(segment
		(start 171.970566 97.3045)
		(end 173.476 97.3045)
		(width 0.202)
		(layer "F.Cu")
		(net 243)
	)
	(segment
		(start 179.080566 125.6055)
		(end 167.6945 114.219434)
		(width 0.202)
		(layer "F.Cu")
		(net 243)
	)
	(segment
		(start 167.6945 108.040852)
		(end 167.6945 107.835)
		(width 0.202)
		(layer "F.Cu")
		(net 243)
	)
	(segment
		(start 167.998648 108.550852)
		(end 167.998648 108.345)
		(width 0.202)
		(layer "F.Cu")
		(net 243)
	)
	(via
		(at 192 161.2185)
		(size 0.45)
		(drill 0.1)
		(layers "F.Cu" "B.Cu")
		(teardrops
			(best_length_ratio 0.4)
			(max_length 1)
			(best_width_ratio 0.9)
			(max_width 2)
			(curved_edges yes)
			(filter_ratio 0.9)
			(enabled yes)
			(allow_two_segments yes)
			(prefer_zone_connections yes)
		)
		(net 243)
	)
	(via
		(at 173.6 97.4285)
		(size 0.45)
		(drill 0.1)
		(layers "F.Cu" "B.Cu")
		(teardrops
			(best_length_ratio 0.4)
			(max_length 1)
			(best_width_ratio 0.9)
			(max_width 2)
			(curved_edges yes)
			(filter_ratio 0.9)
			(enabled yes)
			(allow_two_segments yes)
			(prefer_zone_connections yes)
		)
		(net 243)
	)
	(via
		(at 186.8 125.477)
		(size 0.45)
		(drill 0.1)
		(layers "F.Cu" "B.Cu")
		(teardrops
			(best_length_ratio 0.4)
			(max_length 1)
			(best_width_ratio 0.9)
			(max_width 2)
			(curved_edges yes)
			(filter_ratio 0.9)
			(enabled yes)
			(allow_two_segments yes)
			(prefer_zone_connections yes)
		)
		(net 243)
	)
	(arc
		(start 167.6945 108.855)
		(mid 167.739041 108.747467)
		(end 167.846574 108.702926)
		(width 0.202)
		(layer "F.Cu")
		(net 243)
	)
	(arc
		(start 167.6945 109.875)
		(mid 167.739027 109.767502)
		(end 167.846525 109.722975)
		(width 0.202)
		(layer "F.Cu")
		(net 243)
	)
	(arc
		(start 167.846525 109.212975)
		(mid 167.739027 109.168448)
		(end 167.6945 109.06095)
		(width 0.202)
		(layer "F.Cu")
		(net 243)
	)
	(arc
		(start 167.846574 108.702926)
		(mid 167.954107 108.658385)
		(end 167.998648 108.550852)
		(width 0.202)
		(layer "F.Cu")
		(net 243)
	)
	(arc
		(start 167.846574 108.192926)
		(mid 167.739041 108.148385)
		(end 167.6945 108.040852)
		(width 0.202)
		(layer "F.Cu")
		(net 243)
	)
	(arc
		(start 167.99855 109.365)
		(mid 167.954023 109.257502)
		(end 167.846525 109.212975)
		(width 0.202)
		(layer "F.Cu")
		(net 243)
	)
	(arc
		(start 167.998648 108.345)
		(mid 167.954107 108.237467)
		(end 167.846574 108.192926)
		(width 0.202)
		(layer "F.Cu")
		(net 243)
	)
	(arc
		(start 167.846525 109.722975)
		(mid 167.954023 109.678448)
		(end 167.99855 109.57095)
		(width 0.202)
		(layer "F.Cu")
		(net 243)
	)
	(segment
		(start 175.074999 97.36)
		(end 175.019499 97.3045)
		(width 0.202)
		(layer "B.Cu")
		(net 243)
	)
	(segment
		(start 176.2 97.36)
		(end 175.074999 97.36)
		(width 0.202)
		(layer "B.Cu")
		(net 243)
	)
	(segment
		(start 175.019499 97.3045)
		(end 173.724 97.3045)
		(width 0.202)
		(layer "B.Cu")
		(net 243)
	)
	(segment
		(start 173.724 97.3045)
		(end 173.6 97.4285)
		(width 0.202)
		(layer "B.Cu")
		(net 243)
	)
	(segment
		(start 186.936 125.613)
		(end 186.8 125.477)
		(width 0.178)
		(layer "In5.Cu")
		(net 243)
	)
	(segment
		(start 192 161.2185)
		(end 192.1315 161.087)
		(width 0.178)
		(layer "In5.Cu")
		(net 243)
	)
	(segment
		(start 193.787 146.577458)
		(end 200.287 140.077458)
		(width 0.178)
		(layer "In5.Cu")
		(net 243)
	)
	(segment
		(start 193.787 159.877458)
		(end 193.787 146.577458)
		(width 0.178)
		(layer "In5.Cu")
		(net 243)
	)
	(segment
		(start 192.1315 161.087)
		(end 192.577458 161.087)
		(width 0.178)
		(layer "In5.Cu")
		(net 243)
	)
	(segment
		(start 200.287 131.422542)
		(end 194.477458 125.613)
		(width 0.178)
		(layer "In5.Cu")
		(net 243)
	)
	(segment
		(start 194.477458 125.613)
		(end 186.936 125.613)
		(width 0.178)
		(layer "In5.Cu")
		(net 243)
	)
	(segment
		(start 192.577458 161.087)
		(end 193.787 159.877458)
		(width 0.178)
		(layer "In5.Cu")
		(net 243)
	)
	(segment
		(start 200.287 140.077458)
		(end 200.287 131.422542)
		(width 0.178)
		(layer "In5.Cu")
		(net 243)
	)
	(segment
		(start 186.6715 125.9945)
		(end 178.919434 125.9945)
		(width 0.202)
		(layer "F.Cu")
		(net 244)
	)
	(segment
		(start 167.3055 114.380566)
		(end 167.3055 101.419434)
		(width 0.202)
		(layer "F.Cu")
		(net 244)
	)
	(segment
		(start 191.876 160.7055)
		(end 192 160.5815)
		(width 0.202)
		(layer "F.Cu")
		(net 244)
	)
	(segment
		(start 188.719434 160.7055)
		(end 191.876 160.7055)
		(width 0.202)
		(layer "F.Cu")
		(net 244)
	)
	(segment
		(start 188.025 162.41)
		(end 188.0805 162.3545)
		(width 0.202)
		(layer "F.Cu")
		(net 244)
	)
	(segment
		(start 173.476 96.9155)
		(end 173.6 96.7915)
		(width 0.202)
		(layer "F.Cu")
		(net 244)
	)
	(segment
		(start 178.919434 125.9945)
		(end 167.3055 114.380566)
		(width 0.202)
		(layer "F.Cu")
		(net 244)
	)
	(segment
		(start 188.025 163.135)
		(end 188.025 162.41)
		(width 0.202)
		(layer "F.Cu")
		(net 244)
	)
	(segment
		(start 188.0805 162.3545)
		(end 188.0805 161.344434)
		(width 0.202)
		(layer "F.Cu")
		(net 244)
	)
	(segment
		(start 167.3055 101.419434)
		(end 171.809434 96.9155)
		(width 0.202)
		(layer "F.Cu")
		(net 244)
	)
	(segment
		(start 186.8 126.123)
		(end 186.6715 125.9945)
		(width 0.202)
		(layer "F.Cu")
		(net 244)
	)
	(segment
		(start 171.809434 96.9155)
		(end 173.476 96.9155)
		(width 0.202)
		(layer "F.Cu")
		(net 244)
	)
	(segment
		(start 188.0805 161.344434)
		(end 188.719434 160.7055)
		(width 0.202)
		(layer "F.Cu")
		(net 244)
	)
	(via
		(at 173.6 96.7915)
		(size 0.45)
		(drill 0.1)
		(layers "F.Cu" "B.Cu")
		(teardrops
			(best_length_ratio 0.4)
			(max_length 1)
			(best_width_ratio 0.9)
			(max_width 2)
			(curved_edges yes)
			(filter_ratio 0.9)
			(enabled yes)
			(allow_two_segments yes)
			(prefer_zone_connections yes)
		)
		(net 244)
	)
	(via
		(at 186.8 126.123)
		(size 0.45)
		(drill 0.1)
		(layers "F.Cu" "B.Cu")
		(teardrops
			(best_length_ratio 0.4)
			(max_length 1)
			(best_width_ratio 0.9)
			(max_width 2)
			(curved_edges yes)
			(filter_ratio 0.9)
			(enabled yes)
			(allow_two_segments yes)
			(prefer_zone_connections yes)
		)
		(net 244)
	)
	(via
		(at 192 160.5815)
		(size 0.45)
		(drill 0.1)
		(layers "F.Cu" "B.Cu")
		(teardrops
			(best_length_ratio 0.4)
			(max_length 1)
			(best_width_ratio 0.9)
			(max_width 2)
			(curved_edges yes)
			(filter_ratio 0.9)
			(enabled yes)
			(allow_two_segments yes)
			(prefer_zone_connections yes)
		)
		(net 244)
	)
	(segment
		(start 176.2 96.86)
		(end 175.074999 96.86)
		(width 0.202)
		(layer "B.Cu")
		(net 244)
	)
	(segment
		(start 175.019499 96.9155)
		(end 173.724 96.9155)
		(width 0.202)
		(layer "B.Cu")
		(net 244)
	)
	(segment
		(start 175.074999 96.86)
		(end 175.019499 96.9155)
		(width 0.202)
		(layer "B.Cu")
		(net 244)
	)
	(segment
		(start 173.724 96.9155)
		(end 173.6 96.7915)
		(width 0.202)
		(layer "B.Cu")
		(net 244)
	)
	(segment
		(start 193.413 159.722542)
		(end 193.413 146.422542)
		(width 0.178)
		(layer "In5.Cu")
		(net 244)
	)
	(segment
		(start 186.936 125.987)
		(end 186.8 126.123)
		(width 0.178)
		(layer "In5.Cu")
		(net 244)
	)
	(segment
		(start 193.413 146.422542)
		(end 199.913 139.922542)
		(width 0.178)
		(layer "In5.Cu")
		(net 244)
	)
	(segment
		(start 199.913 139.922542)
		(end 199.913 131.577458)
		(width 0.178)
		(layer "In5.Cu")
		(net 244)
	)
	(segment
		(start 192.1315 160.713)
		(end 192.422542 160.713)
		(width 0.178)
		(layer "In5.Cu")
		(net 244)
	)
	(segment
		(start 192.422542 160.713)
		(end 193.413 159.722542)
		(width 0.178)
		(layer "In5.Cu")
		(net 244)
	)
	(segment
		(start 192 160.5815)
		(end 192.1315 160.713)
		(width 0.178)
		(layer "In5.Cu")
		(net 244)
	)
	(segment
		(start 194.322542 125.987)
		(end 186.936 125.987)
		(width 0.178)
		(layer "In5.Cu")
		(net 244)
	)
	(segment
		(start 199.913 131.577458)
		(end 194.322542 125.987)
		(width 0.178)
		(layer "In5.Cu")
		(net 244)
	)
	(segment
		(start 188.4695 167.124)
		(end 188.5935 167)
		(width 0.202)
		(layer "F.Cu")
		(net 247)
	)
	(segment
		(start 188.525 167.96)
		(end 188.4695 167.9045)
		(width 0.202)
		(layer "F.Cu")
		(net 247)
	)
	(segment
		(start 188.525 168.685)
		(end 188.525 167.96)
		(width 0.202)
		(layer "F.Cu")
		(net 247)
	)
	(segment
		(start 188.4695 167.9045)
		(end 188.4695 167.124)
		(width 0.202)
		(layer "F.Cu")
		(net 247)
	)
	(via
		(at 174.3 98.9285)
		(size 0.45)
		(drill 0.1)
		(layers "F.Cu" "B.Cu")
		(teardrops
			(best_length_ratio 0.4)
			(max_length 1)
			(best_width_ratio 0.9)
			(max_width 2)
			(curved_edges yes)
			(filter_ratio 0.9)
			(enabled yes)
			(allow_two_segments yes)
			(prefer_zone_connections yes)
		)
		(net 247)
	)
	(via
		(at 188.5935 167)
		(size 0.45)
		(drill 0.1)
		(layers "F.Cu" "B.Cu")
		(teardrops
			(best_length_ratio 0.4)
			(max_length 1)
			(best_width_ratio 0.9)
			(max_width 2)
			(curved_edges yes)
			(filter_ratio 0.9)
			(enabled yes)
			(allow_two_segments yes)
			(prefer_zone_connections yes)
		)
		(net 247)
	)
	(segment
		(start 175.019499 98.8045)
		(end 174.424 98.8045)
		(width 0.202)
		(layer "B.Cu")
		(net 247)
	)
	(segment
		(start 175.074999 98.86)
		(end 175.019499 98.8045)
		(width 0.202)
		(layer "B.Cu")
		(net 247)
	)
	(segment
		(start 176.2 98.86)
		(end 175.074999 98.86)
		(width 0.202)
		(layer "B.Cu")
		(net 247)
	)
	(segment
		(start 174.424 98.8045)
		(end 174.3 98.9285)
		(width 0.202)
		(layer "B.Cu")
		(net 247)
	)
	(segment
		(start 182.137 139.972542)
		(end 186.887 144.722542)
		(width 0.178)
		(layer "In5.Cu")
		(net 247)
	)
	(segment
		(start 169.327 101.187458)
		(end 169.327 107.626084)
		(width 0.178)
		(layer "In5.Cu")
		(net 247)
	)
	(segment
		(start 169.598466 108.89755)
		(end 169.598466 109.126084)
		(width 0.178)
		(layer "In5.Cu")
		(net 247)
	)
	(segment
		(start 169.327 116.312542)
		(end 182.137 129.122542)
		(width 0.178)
		(layer "In5.Cu")
		(net 247)
	)
	(segment
		(start 188.462 166.8685)
		(end 188.5935 167)
		(width 0.178)
		(layer "In5.Cu")
		(net 247)
	)
	(segment
		(start 169.598364 107.897448)
		(end 169.598364 108.126084)
		(width 0.178)
		(layer "In5.Cu")
		(net 247)
	)
	(segment
		(start 182.137 129.122542)
		(end 182.137 139.972542)
		(width 0.178)
		(layer "In5.Cu")
		(net 247)
	)
	(segment
		(start 186.887 164.672542)
		(end 188.462 166.247542)
		(width 0.178)
		(layer "In5.Cu")
		(net 247)
	)
	(segment
		(start 169.327 109.626084)
		(end 169.327 110.593126)
		(width 0.178)
		(layer "In5.Cu")
		(net 247)
	)
	(segment
		(start 171.717458 98.797)
		(end 169.327 101.187458)
		(width 0.178)
		(layer "In5.Cu")
		(net 247)
	)
	(segment
		(start 169.327 108.397448)
		(end 169.327 108.626084)
		(width 0.178)
		(layer "In5.Cu")
		(net 247)
	)
	(segment
		(start 174.1685 98.797)
		(end 171.717458 98.797)
		(width 0.178)
		(layer "In5.Cu")
		(net 247)
	)
	(segment
		(start 188.462 166.247542)
		(end 188.462 166.8685)
		(width 0.178)
		(layer "In5.Cu")
		(net 247)
	)
	(segment
		(start 169.327 109.39755)
		(end 169.327 109.626084)
		(width 0.178)
		(layer "In5.Cu")
		(net 247)
	)
	(segment
		(start 186.887 144.722542)
		(end 186.887 164.672542)
		(width 0.178)
		(layer "In5.Cu")
		(net 247)
	)
	(segment
		(start 174.3 98.9285)
		(end 174.1685 98.797)
		(width 0.178)
		(layer "In5.Cu")
		(net 247)
	)
	(segment
		(start 169.327 110.593126)
		(end 169.327 116.312542)
		(width 0.178)
		(layer "In5.Cu")
		(net 247)
	)
	(arc
		(start 169.462733 109.261817)
		(mid 169.366755 109.301572)
		(end 169.327 109.39755)
		(width 0.178)
		(layer "In5.Cu")
		(net 247)
	)
	(arc
		(start 169.598364 108.126084)
		(mid 169.558624 108.222026)
		(end 169.462682 108.261766)
		(width 0.178)
		(layer "In5.Cu")
		(net 247)
	)
	(arc
		(start 169.462682 108.261766)
		(mid 169.36674 108.301506)
		(end 169.327 108.397448)
		(width 0.178)
		(layer "In5.Cu")
		(net 247)
	)
	(arc
		(start 169.327 107.626084)
		(mid 169.36674 107.722026)
		(end 169.462682 107.761766)
		(width 0.178)
		(layer "In5.Cu")
		(net 247)
	)
	(arc
		(start 169.462682 107.761766)
		(mid 169.558624 107.801506)
		(end 169.598364 107.897448)
		(width 0.178)
		(layer "In5.Cu")
		(net 247)
	)
	(arc
		(start 169.327 108.626084)
		(mid 169.366755 108.722062)
		(end 169.462733 108.761817)
		(width 0.178)
		(layer "In5.Cu")
		(net 247)
	)
	(arc
		(start 169.462733 108.761817)
		(mid 169.558711 108.801572)
		(end 169.598466 108.89755)
		(width 0.178)
		(layer "In5.Cu")
		(net 247)
	)
	(arc
		(start 169.598466 109.126084)
		(mid 169.558711 109.222062)
		(end 169.462733 109.261817)
		(width 0.178)
		(layer "In5.Cu")
		(net 247)
	)
	(segment
		(start 188.0805 167.9045)
		(end 188.0805 167.124)
		(width 0.202)
		(layer "F.Cu")
		(net 249)
	)
	(segment
		(start 188.025 168.685)
		(end 188.025 167.96)
		(width 0.202)
		(layer "F.Cu")
		(net 249)
	)
	(segment
		(start 188.025 167.96)
		(end 188.0805 167.9045)
		(width 0.202)
		(layer "F.Cu")
		(net 249)
	)
	(segment
		(start 188.0805 167.124)
		(end 187.9565 167)
		(width 0.202)
		(layer "F.Cu")
		(net 249)
	)
	(via
		(at 187.9565 167)
		(size 0.45)
		(drill 0.1)
		(layers "F.Cu" "B.Cu")
		(teardrops
			(best_length_ratio 0.4)
			(max_length 1)
			(best_width_ratio 0.9)
			(max_width 2)
			(curved_edges yes)
			(filter_ratio 0.9)
			(enabled yes)
			(allow_two_segments yes)
			(prefer_zone_connections yes)
		)
		(net 249)
	)
	(via
		(at 174.3 98.2915)
		(size 0.45)
		(drill 0.1)
		(layers "F.Cu" "B.Cu")
		(teardrops
			(best_length_ratio 0.4)
			(max_length 1)
			(best_width_ratio 0.9)
			(max_width 2)
			(curved_edges yes)
			(filter_ratio 0.9)
			(enabled yes)
			(allow_two_segments yes)
			(prefer_zone_connections yes)
		)
		(net 249)
	)
	(segment
		(start 176.2 98.36)
		(end 175.074999 98.36)
		(width 0.202)
		(layer "B.Cu")
		(net 249)
	)
	(segment
		(start 174.424 98.4155)
		(end 174.3 98.2915)
		(width 0.202)
		(layer "B.Cu")
		(net 249)
	)
	(segment
		(start 175.074999 98.36)
		(end 175.019499 98.4155)
		(width 0.202)
		(layer "B.Cu")
		(net 249)
	)
	(segment
		(start 175.019499 98.4155)
		(end 174.424 98.4155)
		(width 0.202)
		(layer "B.Cu")
		(net 249)
	)
	(segment
		(start 186.513 144.877458)
		(end 181.763 140.127458)
		(width 0.178)
		(layer "In5.Cu")
		(net 249)
	)
	(segment
		(start 186.513 164.827458)
		(end 186.513 144.877458)
		(width 0.178)
		(layer "In5.Cu")
		(net 249)
	)
	(segment
		(start 188.088 166.8685)
		(end 188.088 166.402458)
		(width 0.178)
		(layer "In5.Cu")
		(net 249)
	)
	(segment
		(start 181.763 140.127458)
		(end 181.763 129.277458)
		(width 0.178)
		(layer "In5.Cu")
		(net 249)
	)
	(segment
		(start 174.1685 98.423)
		(end 174.3 98.2915)
		(width 0.178)
		(layer "In5.Cu")
		(net 249)
	)
	(segment
		(start 168.953 101.032542)
		(end 171.562542 98.423)
		(width 0.178)
		(layer "In5.Cu")
		(net 249)
	)
	(segment
		(start 188.088 166.402458)
		(end 186.513 164.827458)
		(width 0.178)
		(layer "In5.Cu")
		(net 249)
	)
	(segment
		(start 171.562542 98.423)
		(end 174.1685 98.423)
		(width 0.178)
		(layer "In5.Cu")
		(net 249)
	)
	(segment
		(start 187.9565 167)
		(end 188.088 166.8685)
		(width 0.178)
		(layer "In5.Cu")
		(net 249)
	)
	(segment
		(start 168.953 116.467458)
		(end 168.953 101.032542)
		(width 0.178)
		(layer "In5.Cu")
		(net 249)
	)
	(segment
		(start 181.763 129.277458)
		(end 168.953 116.467458)
		(width 0.178)
		(layer "In5.Cu")
		(net 249)
	)
	(segment
		(start 169.4945 107.55369)
		(end 169.4945 107.199067)
		(width 0.202)
		(layer "F.Cu")
		(net 252)
	)
	(segment
		(start 186.8 123.9815)
		(end 186.676 124.1055)
		(width 0.202)
		(layer "F.Cu")
		(net 252)
	)
	(segment
		(start 172.170566 100.3045)
		(end 173.476 100.3045)
		(width 0.202)
		(layer "F.Cu")
		(net 252)
	)
	(segment
		(start 180.080566 124.1055)
		(end 169.4945 113.519434)
		(width 0.202)
		(layer "F.Cu")
		(net 252)
	)
	(segment
		(start 186.676 124.1055)
		(end 180.080566 124.1055)
		(width 0.202)
		(layer "F.Cu")
		(net 252)
	)
	(segment
		(start 169.4945 107.199067)
		(end 169.4945 102.980566)
		(width 0.202)
		(layer "F.Cu")
		(net 252)
	)
	(segment
		(start 194.649851 160.125214)
		(end 194.825214 160.125214)
		(width 0.202)
		(layer "F.Cu")
		(net 252)
	)
	(segment
		(start 194.025 162.41)
		(end 193.9695 162.3545)
		(width 0.202)
		(layer "F.Cu")
		(net 252)
	)
	(segment
		(start 193.9695 162.3545)
		(end 193.9695 160.805565)
		(width 0.202)
		(layer "F.Cu")
		(net 252)
	)
	(segment
		(start 169.4945 108.785052)
		(end 169.4945 108.57369)
		(width 0.202)
		(layer "F.Cu")
		(net 252)
	)
	(segment
		(start 194.025 163.135)
		(end 194.025 162.41)
		(width 0.202)
		(layer "F.Cu")
		(net 252)
	)
	(segment
		(start 173.476 100.3045)
		(end 173.6 100.4285)
		(width 0.202)
		(layer "F.Cu")
		(net 252)
	)
	(segment
		(start 169.4945 102.980566)
		(end 172.170566 100.3045)
		(width 0.202)
		(layer "F.Cu")
		(net 252)
	)
	(segment
		(start 193.9695 160.805565)
		(end 194.649851 160.125214)
		(width 0.202)
		(layer "F.Cu")
		(net 252)
	)
	(segment
		(start 169.4945 107.76503)
		(end 169.4945 107.55369)
		(width 0.202)
		(layer "F.Cu")
		(net 252)
	)
	(segment
		(start 169.79316 108.27503)
		(end 169.79316 108.06369)
		(width 0.202)
		(layer "F.Cu")
		(net 252)
	)
	(segment
		(start 169.793138 109.295052)
		(end 169.793138 109.08369)
		(width 0.202)
		(layer "F.Cu")
		(net 252)
	)
	(segment
		(start 169.4945 113.519434)
		(end 169.4945 109.59369)
		(width 0.202)
		(layer "F.Cu")
		(net 252)
	)
	(via
		(at 173.6 100.4285)
		(size 0.45)
		(drill 0.1)
		(layers "F.Cu" "B.Cu")
		(teardrops
			(best_length_ratio 0.4)
			(max_length 1)
			(best_width_ratio 0.9)
			(max_width 2)
			(curved_edges yes)
			(filter_ratio 0.9)
			(enabled yes)
			(allow_two_segments yes)
			(prefer_zone_connections yes)
		)
		(net 252)
	)
	(via
		(at 194.825214 160.125214)
		(size 0.45)
		(drill 0.1)
		(layers "F.Cu" "B.Cu")
		(teardrops
			(best_length_ratio 0.4)
			(max_length 1)
			(best_width_ratio 0.9)
			(max_width 2)
			(curved_edges yes)
			(filter_ratio 0.9)
			(enabled yes)
			(allow_two_segments yes)
			(prefer_zone_connections yes)
		)
		(net 252)
	)
	(via
		(at 186.8 123.9815)
		(size 0.45)
		(drill 0.1)
		(layers "F.Cu" "B.Cu")
		(teardrops
			(best_length_ratio 0.4)
			(max_length 1)
			(best_width_ratio 0.9)
			(max_width 2)
			(curved_edges yes)
			(filter_ratio 0.9)
			(enabled yes)
			(allow_two_segments yes)
			(prefer_zone_connections yes)
		)
		(net 252)
	)
	(arc
		(start 169.4945 109.59369)
		(mid 169.538235 109.488106)
		(end 169.643819 109.444371)
		(width 0.202)
		(layer "F.Cu")
		(net 252)
	)
	(arc
		(start 169.79316 108.06369)
		(mid 169.749422 107.958098)
		(end 169.64383 107.91436)
		(width 0.202)
		(layer "F.Cu")
		(net 252)
	)
	(arc
		(start 169.64383 108.42436)
		(mid 169.749422 108.380622)
		(end 169.79316 108.27503)
		(width 0.202)
		(layer "F.Cu")
		(net 252)
	)
	(arc
		(start 169.793138 109.08369)
		(mid 169.749403 108.978106)
		(end 169.643819 108.934371)
		(width 0.202)
		(layer "F.Cu")
		(net 252)
	)
	(arc
		(start 169.643819 108.934371)
		(mid 169.538235 108.890636)
		(end 169.4945 108.785052)
		(width 0.202)
		(layer "F.Cu")
		(net 252)
	)
	(arc
		(start 169.64383 107.91436)
		(mid 169.538238 107.870622)
		(end 169.4945 107.76503)
		(width 0.202)
		(layer "F.Cu")
		(net 252)
	)
	(arc
		(start 169.4945 108.57369)
		(mid 169.538238 108.468098)
		(end 169.64383 108.42436)
		(width 0.202)
		(layer "F.Cu")
		(net 252)
	)
	(arc
		(start 169.643819 109.444371)
		(mid 169.749403 109.400636)
		(end 169.793138 109.295052)
		(width 0.202)
		(layer "F.Cu")
		(net 252)
	)
	(segment
		(start 175.074999 100.36)
		(end 175.019499 100.3045)
		(width 0.202)
		(layer "B.Cu")
		(net 252)
	)
	(segment
		(start 175.019499 100.3045)
		(end 173.724 100.3045)
		(width 0.202)
		(layer "B.Cu")
		(net 252)
	)
	(segment
		(start 173.724 100.3045)
		(end 173.6 100.4285)
		(width 0.202)
		(layer "B.Cu")
		(net 252)
	)
	(segment
		(start 176.2 100.36)
		(end 175.074999 100.36)
		(width 0.202)
		(layer "B.Cu")
		(net 252)
	)
	(segment
		(start 196.177458 124.113)
		(end 186.9315 124.113)
		(width 0.178)
		(layer "In5.Cu")
		(net 252)
	)
	(segment
		(start 201.687 141.277458)
		(end 201.687 130.722542)
		(width 0.178)
		(layer "In5.Cu")
		(net 252)
	)
	(segment
		(start 186.9315 124.113)
		(end 186.8 123.9815)
		(width 0.178)
		(layer "In5.Cu")
		(net 252)
	)
	(segment
		(start 200.487 142.477458)
		(end 201.687 141.277458)
		(width 0.178)
		(layer "In5.Cu")
		(net 252)
	)
	(segment
		(start 200.487 154.277458)
		(end 200.487 142.477458)
		(width 0.178)
		(layer "In5.Cu")
		(net 252)
	)
	(segment
		(start 194.825214 159.939244)
		(end 200.487 154.277458)
		(width 0.178)
		(layer "In5.Cu")
		(net 252)
	)
	(segment
		(start 201.687 130.722542)
		(end 198.787 127.822542)
		(width 0.178)
		(layer "In5.Cu")
		(net 252)
	)
	(segment
		(start 198.787 127.822542)
		(end 198.787 126.722542)
		(width 0.178)
		(layer "In5.Cu")
		(net 252)
	)
	(segment
		(start 198.787 126.722542)
		(end 196.177458 124.113)
		(width 0.178)
		(layer "In5.Cu")
		(net 252)
	)
	(segment
		(start 194.825214 160.125214)
		(end 194.825214 159.939244)
		(width 0.178)
		(layer "In5.Cu")
		(net 252)
	)
	(segment
		(start 193.5805 162.3545)
		(end 193.5805 160.644435)
		(width 0.202)
		(layer "F.Cu")
		(net 254)
	)
	(segment
		(start 193.5805 160.644435)
		(end 194.374786 159.850149)
		(width 0.202)
		(layer "F.Cu")
		(net 254)
	)
	(segment
		(start 179.919434 124.4945)
		(end 186.676 124.4945)
		(width 0.202)
		(layer "F.Cu")
		(net 254)
	)
	(segment
		(start 173.6 99.7915)
		(end 173.476 99.9155)
		(width 0.202)
		(layer "F.Cu")
		(net 254)
	)
	(segment
		(start 172.009434 99.9155)
		(end 169.1055 102.819434)
		(width 0.202)
		(layer "F.Cu")
		(net 254)
	)
	(segment
		(start 169.1055 113.680566)
		(end 179.919434 124.4945)
		(width 0.202)
		(layer "F.Cu")
		(net 254)
	)
	(segment
		(start 194.374786 159.850149)
		(end 194.374786 159.674786)
		(width 0.202)
		(layer "F.Cu")
		(net 254)
	)
	(segment
		(start 193.525 163.135)
		(end 193.525 162.41)
		(width 0.202)
		(layer "F.Cu")
		(net 254)
	)
	(segment
		(start 173.476 99.9155)
		(end 172.009434 99.9155)
		(width 0.202)
		(layer "F.Cu")
		(net 254)
	)
	(segment
		(start 169.1055 102.819434)
		(end 169.1055 113.680566)
		(width 0.202)
		(layer "F.Cu")
		(net 254)
	)
	(segment
		(start 193.525 162.41)
		(end 193.5805 162.3545)
		(width 0.202)
		(layer "F.Cu")
		(net 254)
	)
	(segment
		(start 186.676 124.4945)
		(end 186.8 124.6185)
		(width 0.202)
		(layer "F.Cu")
		(net 254)
	)
	(via
		(at 194.374786 159.674786)
		(size 0.45)
		(drill 0.1)
		(layers "F.Cu" "B.Cu")
		(teardrops
			(best_length_ratio 0.4)
			(max_length 1)
			(best_width_ratio 0.9)
			(max_width 2)
			(curved_edges yes)
			(filter_ratio 0.9)
			(enabled yes)
			(allow_two_segments yes)
			(prefer_zone_connections yes)
		)
		(net 254)
	)
	(via
		(at 173.6 99.7915)
		(size 0.45)
		(drill 0.1)
		(layers "F.Cu" "B.Cu")
		(teardrops
			(best_length_ratio 0.4)
			(max_length 1)
			(best_width_ratio 0.9)
			(max_width 2)
			(curved_edges yes)
			(filter_ratio 0.9)
			(enabled yes)
			(allow_two_segments yes)
			(prefer_zone_connections yes)
		)
		(net 254)
	)
	(via
		(at 186.8 124.6185)
		(size 0.45)
		(drill 0.1)
		(layers "F.Cu" "B.Cu")
		(teardrops
			(best_length_ratio 0.4)
			(max_length 1)
			(best_width_ratio 0.9)
			(max_width 2)
			(curved_edges yes)
			(filter_ratio 0.9)
			(enabled yes)
			(allow_two_segments yes)
			(prefer_zone_connections yes)
		)
		(net 254)
	)
	(segment
		(start 175.074999 99.86)
		(end 175.019499 99.9155)
		(width 0.202)
		(layer "B.Cu")
		(net 254)
	)
	(segment
		(start 176.2 99.86)
		(end 175.074999 99.86)
		(width 0.202)
		(layer "B.Cu")
		(net 254)
	)
	(segment
		(start 175.019499 99.9155)
		(end 173.724 99.9155)
		(width 0.202)
		(layer "B.Cu")
		(net 254)
	)
	(segment
		(start 173.724 99.9155)
		(end 173.6 99.7915)
		(width 0.202)
		(layer "B.Cu")
		(net 254)
	)
	(segment
		(start 198.413 127.977458)
		(end 198.413 126.877458)
		(width 0.178)
		(layer "In5.Cu")
		(net 254)
	)
	(segment
		(start 196.022542 124.487)
		(end 186.9315 124.487)
		(width 0.178)
		(layer "In5.Cu")
		(net 254)
	)
	(segment
		(start 201.313 141.122542)
		(end 201.313 130.877458)
		(width 0.178)
		(layer "In5.Cu")
		(net 254)
	)
	(segment
		(start 200.113 154.122542)
		(end 200.113 142.322542)
		(width 0.178)
		(layer "In5.Cu")
		(net 254)
	)
	(segment
		(start 198.413 126.877458)
		(end 196.022542 124.487)
		(width 0.178)
		(layer "In5.Cu")
		(net 254)
	)
	(segment
		(start 194.374786 159.674786)
		(end 194.560756 159.674786)
		(width 0.178)
		(layer "In5.Cu")
		(net 254)
	)
	(segment
		(start 200.113 142.322542)
		(end 201.313 141.122542)
		(width 0.178)
		(layer "In5.Cu")
		(net 254)
	)
	(segment
		(start 194.560756 159.674786)
		(end 200.113 154.122542)
		(width 0.178)
		(layer "In5.Cu")
		(net 254)
	)
	(segment
		(start 201.313 130.877458)
		(end 198.413 127.977458)
		(width 0.178)
		(layer "In5.Cu")
		(net 254)
	)
	(segment
		(start 186.9315 124.487)
		(end 186.8 124.6185)
		(width 0.178)
		(layer "In5.Cu")
		(net 254)
	)
	(segment
		(start 194.025 167.96)
		(end 193.9695 167.9045)
		(width 0.202)
		(layer "F.Cu")
		(net 257)
	)
	(segment
		(start 193.9695 167.9045)
		(end 193.9695 167.194434)
		(width 0.202)
		(layer "F.Cu")
		(net 257)
	)
	(segment
		(start 192.980566 166.2055)
		(end 190.124 166.2055)
		(width 0.202)
		(layer "F.Cu")
		(net 257)
	)
	(segment
		(start 194.025 168.685)
		(end 194.025 167.96)
		(width 0.202)
		(layer "F.Cu")
		(net 257)
	)
	(segment
		(start 190.124 166.2055)
		(end 190 166.0815)
		(width 0.202)
		(layer "F.Cu")
		(net 257)
	)
	(segment
		(start 193.9695 167.194434)
		(end 192.980566 166.2055)
		(width 0.202)
		(layer "F.Cu")
		(net 257)
	)
	(via
		(at 190 166.0815)
		(size 0.45)
		(drill 0.1)
		(layers "F.Cu" "B.Cu")
		(teardrops
			(best_length_ratio 0.4)
			(max_length 1)
			(best_width_ratio 0.9)
			(max_width 2)
			(curved_edges yes)
			(filter_ratio 0.9)
			(enabled yes)
			(allow_two_segments yes)
			(prefer_zone_connections yes)
		)
		(net 257)
	)
	(via
		(at 174.3 101.9285)
		(size 0.45)
		(drill 0.1)
		(layers "F.Cu" "B.Cu")
		(teardrops
			(best_length_ratio 0.4)
			(max_length 1)
			(best_width_ratio 0.9)
			(max_width 2)
			(curved_edges yes)
			(filter_ratio 0.9)
			(enabled yes)
			(allow_two_segments yes)
			(prefer_zone_connections yes)
		)
		(net 257)
	)
	(segment
		(start 176.2 101.86)
		(end 175.074999 101.86)
		(width 0.202)
		(layer "B.Cu")
		(net 257)
	)
	(segment
		(start 175.074999 101.86)
		(end 175.019499 101.8045)
		(width 0.202)
		(layer "B.Cu")
		(net 257)
	)
	(segment
		(start 174.424 101.8045)
		(end 174.3 101.9285)
		(width 0.202)
		(layer "B.Cu")
		(net 257)
	)
	(segment
		(start 175.019499 101.8045)
		(end 174.424 101.8045)
		(width 0.202)
		(layer "B.Cu")
		(net 257)
	)
	(segment
		(start 171.277 110.478857)
		(end 171.277 110.718451)
		(width 0.178)
		(layer "In5.Cu")
		(net 257)
	)
	(segment
		(start 189.627458 166.213)
		(end 189.8685 166.213)
		(width 0.178)
		(layer "In5.Cu")
		(net 257)
	)
	(segment
		(start 171.277 110.718451)
		(end 171.277 111.05)
		(width 0.178)
		(layer "In5.Cu")
		(net 257)
	)
	(segment
		(start 171.277 109.478873)
		(end 171.277 109.718451)
		(width 0.178)
		(layer "In5.Cu")
		(net 257)
	)
	(segment
		(start 189.8685 166.213)
		(end 190 166.0815)
		(width 0.178)
		(layer "In5.Cu")
		(net 257)
	)
	(segment
		(start 188.487 164.322542)
		(end 189.287 165.122542)
		(width 0.178)
		(layer "In5.Cu")
		(net 257)
	)
	(segment
		(start 171.277 103.517458)
		(end 171.277 108.718451)
		(width 0.178)
		(layer "In5.Cu")
		(net 257)
	)
	(segment
		(start 184.387 139.422542)
		(end 188.487 143.522542)
		(width 0.178)
		(layer "In5.Cu")
		(net 257)
	)
	(segment
		(start 171.537422 108.978873)
		(end 171.537422 109.218451)
		(width 0.178)
		(layer "In5.Cu")
		(net 257)
	)
	(segment
		(start 174.3 101.9285)
		(end 174.1685 101.797)
		(width 0.178)
		(layer "In5.Cu")
		(net 257)
	)
	(segment
		(start 174.1685 101.797)
		(end 172.997458 101.797)
		(width 0.178)
		(layer "In5.Cu")
		(net 257)
	)
	(segment
		(start 189.287 165.872542)
		(end 189.627458 166.213)
		(width 0.178)
		(layer "In5.Cu")
		(net 257)
	)
	(segment
		(start 171.537406 109.978857)
		(end 171.537406 110.218451)
		(width 0.178)
		(layer "In5.Cu")
		(net 257)
	)
	(segment
		(start 189.287 165.122542)
		(end 189.287 165.872542)
		(width 0.178)
		(layer "In5.Cu")
		(net 257)
	)
	(segment
		(start 188.487 143.522542)
		(end 188.487 164.322542)
		(width 0.178)
		(layer "In5.Cu")
		(net 257)
	)
	(segment
		(start 172.997458 101.797)
		(end 171.277 103.517458)
		(width 0.178)
		(layer "In5.Cu")
		(net 257)
	)
	(segment
		(start 184.387 128.372542)
		(end 184.387 139.422542)
		(width 0.178)
		(layer "In5.Cu")
		(net 257)
	)
	(segment
		(start 171.277 115.262542)
		(end 184.387 128.372542)
		(width 0.178)
		(layer "In5.Cu")
		(net 257)
	)
	(segment
		(start 171.277 111.05)
		(end 171.277 115.262542)
		(width 0.178)
		(layer "In5.Cu")
		(net 257)
	)
	(arc
		(start 171.537406 110.218451)
		(mid 171.49927 110.310518)
		(end 171.407203 110.348654)
		(width 0.178)
		(layer "In5.Cu")
		(net 257)
	)
	(arc
		(start 171.277 108.718451)
		(mid 171.315138 108.810524)
		(end 171.407211 108.848662)
		(width 0.178)
		(layer "In5.Cu")
		(net 257)
	)
	(arc
		(start 171.407211 108.848662)
		(mid 171.499284 108.8868)
		(end 171.537422 108.978873)
		(width 0.178)
		(layer "In5.Cu")
		(net 257)
	)
	(arc
		(start 171.407211 109.348662)
		(mid 171.315138 109.3868)
		(end 171.277 109.478873)
		(width 0.178)
		(layer "In5.Cu")
		(net 257)
	)
	(arc
		(start 171.537422 109.218451)
		(mid 171.499284 109.310524)
		(end 171.407211 109.348662)
		(width 0.178)
		(layer "In5.Cu")
		(net 257)
	)
	(arc
		(start 171.407203 109.848654)
		(mid 171.49927 109.88679)
		(end 171.537406 109.978857)
		(width 0.178)
		(layer "In5.Cu")
		(net 257)
	)
	(arc
		(start 171.277 109.718451)
		(mid 171.315136 109.810518)
		(end 171.407203 109.848654)
		(width 0.178)
		(layer "In5.Cu")
		(net 257)
	)
	(arc
		(start 171.407203 110.348654)
		(mid 171.315136 110.38679)
		(end 171.277 110.478857)
		(width 0.178)
		(layer "In5.Cu")
		(net 257)
	)
	(segment
		(start 193.5805 167.355566)
		(end 192.819434 166.5945)
		(width 0.202)
		(layer "F.Cu")
		(net 259)
	)
	(segment
		(start 193.525 167.96)
		(end 193.5805 167.9045)
		(width 0.202)
		(layer "F.Cu")
		(net 259)
	)
	(segment
		(start 192.819434 166.5945)
		(end 190.124 166.5945)
		(width 0.202)
		(layer "F.Cu")
		(net 259)
	)
	(segment
		(start 193.525 168.685)
		(end 193.525 167.96)
		(width 0.202)
		(layer "F.Cu")
		(net 259)
	)
	(segment
		(start 190.124 166.5945)
		(end 190 166.7185)
		(width 0.202)
		(layer "F.Cu")
		(net 259)
	)
	(segment
		(start 193.5805 167.9045)
		(end 193.5805 167.355566)
		(width 0.202)
		(layer "F.Cu")
		(net 259)
	)
	(via
		(at 190 166.7185)
		(size 0.45)
		(drill 0.1)
		(layers "F.Cu" "B.Cu")
		(teardrops
			(best_length_ratio 0.4)
			(max_length 1)
			(best_width_ratio 0.9)
			(max_width 2)
			(curved_edges yes)
			(filter_ratio 0.9)
			(enabled yes)
			(allow_two_segments yes)
			(prefer_zone_connections yes)
		)
		(net 259)
	)
	(via
		(at 174.3 101.2915)
		(size 0.45)
		(drill 0.1)
		(layers "F.Cu" "B.Cu")
		(teardrops
			(best_length_ratio 0.4)
			(max_length 1)
			(best_width_ratio 0.9)
			(max_width 2)
			(curved_edges yes)
			(filter_ratio 0.9)
			(enabled yes)
			(allow_two_segments yes)
			(prefer_zone_connections yes)
		)
		(net 259)
	)
	(segment
		(start 175.074999 101.36)
		(end 175.019499 101.4155)
		(width 0.202)
		(layer "B.Cu")
		(net 259)
	)
	(segment
		(start 174.424 101.4155)
		(end 174.3 101.2915)
		(width 0.202)
		(layer "B.Cu")
		(net 259)
	)
	(segment
		(start 176.2 101.36)
		(end 175.074999 101.36)
		(width 0.202)
		(layer "B.Cu")
		(net 259)
	)
	(segment
		(start 175.019499 101.4155)
		(end 174.424 101.4155)
		(width 0.202)
		(layer "B.Cu")
		(net 259)
	)
	(segment
		(start 188.913 165.277458)
		(end 188.113 164.477458)
		(width 0.178)
		(layer "In5.Cu")
		(net 259)
	)
	(segment
		(start 174.1685 101.423)
		(end 174.3 101.2915)
		(width 0.178)
		(layer "In5.Cu")
		(net 259)
	)
	(segment
		(start 188.913 166.027458)
		(end 188.913 165.277458)
		(width 0.178)
		(layer "In5.Cu")
		(net 259)
	)
	(segment
		(start 188.113 164.477458)
		(end 188.113 143.677458)
		(width 0.178)
		(layer "In5.Cu")
		(net 259)
	)
	(segment
		(start 190 166.7185)
		(end 189.8685 166.587)
		(width 0.178)
		(layer "In5.Cu")
		(net 259)
	)
	(segment
		(start 172.842542 101.423)
		(end 174.1685 101.423)
		(width 0.178)
		(layer "In5.Cu")
		(net 259)
	)
	(segment
		(start 188.113 143.677458)
		(end 184.013 139.577458)
		(width 0.178)
		(layer "In5.Cu")
		(net 259)
	)
	(segment
		(start 189.472542 166.587)
		(end 188.913 166.027458)
		(width 0.178)
		(layer "In5.Cu")
		(net 259)
	)
	(segment
		(start 189.8685 166.587)
		(end 189.472542 166.587)
		(width 0.178)
		(layer "In5.Cu")
		(net 259)
	)
	(segment
		(start 184.013 139.577458)
		(end 184.013 128.527458)
		(width 0.178)
		(layer "In5.Cu")
		(net 259)
	)
	(segment
		(start 170.903 115.417458)
		(end 170.903 103.362542)
		(width 0.178)
		(layer "In5.Cu")
		(net 259)
	)
	(segment
		(start 170.903 103.362542)
		(end 172.842542 101.423)
		(width 0.178)
		(layer "In5.Cu")
		(net 259)
	)
	(segment
		(start 184.013 128.527458)
		(end 170.903 115.417458)
		(width 0.178)
		(layer "In5.Cu")
		(net 259)
	)
	(segment
		(start 186.8 122.477)
		(end 186.6715 122.6055)
		(width 0.202)
		(layer "F.Cu")
		(net 262)
	)
	(segment
		(start 171.287726 108.310351)
		(end 171.287726 108.003577)
		(width 0.202)
		(layer "F.Cu")
		(net 262)
	)
	(segment
		(start 170.9945 104.780566)
		(end 172.470566 103.3045)
		(width 0.202)
		(layer "F.Cu")
		(net 262)
	)
	(segment
		(start 170.9945 108.910351)
		(end 170.9945 108.603577)
		(width 0.202)
		(layer "F.Cu")
		(net 262)
	)
	(segment
		(start 170.9945 107.710351)
		(end 170.9945 107.403577)
		(width 0.202)
		(layer "F.Cu")
		(net 262)
	)
	(segment
		(start 170.9945 107.403577)
		(end 170.9945 107.146596)
		(width 0.202)
		(layer "F.Cu")
		(net 262)
	)
	(segment
		(start 195.4695 161.766999)
		(end 195.4695 161.624)
		(width 0.202)
		(layer "F.Cu")
		(net 262)
	)
	(segment
		(start 181.580566 122.6055)
		(end 170.9945 112.019434)
		(width 0.202)
		(layer "F.Cu")
		(net 262)
	)
	(segment
		(start 195.525 161.822499)
		(end 195.4695 161.766999)
		(width 0.202)
		(layer "F.Cu")
		(net 262)
	)
	(segment
		(start 173.476 103.3045)
		(end 173.6 103.4285)
		(width 0.202)
		(layer "F.Cu")
		(net 262)
	)
	(segment
		(start 172.470566 103.3045)
		(end 173.476 103.3045)
		(width 0.202)
		(layer "F.Cu")
		(net 262)
	)
	(segment
		(start 195.525 163.135)
		(end 195.525 161.822499)
		(width 0.202)
		(layer "F.Cu")
		(net 262)
	)
	(segment
		(start 170.9945 112.019434)
		(end 170.9945 109.803577)
		(width 0.202)
		(layer "F.Cu")
		(net 262)
	)
	(segment
		(start 186.6715 122.6055)
		(end 181.580566 122.6055)
		(width 0.202)
		(layer "F.Cu")
		(net 262)
	)
	(segment
		(start 171.287726 109.510351)
		(end 171.287726 109.203577)
		(width 0.202)
		(layer "F.Cu")
		(net 262)
	)
	(segment
		(start 195.4695 161.624)
		(end 195.5935 161.5)
		(width 0.202)
		(layer "F.Cu")
		(net 262)
	)
	(segment
		(start 170.9945 107.146596)
		(end 170.9945 104.780566)
		(width 0.202)
		(layer "F.Cu")
		(net 262)
	)
	(via
		(at 173.6 103.4285)
		(size 0.45)
		(drill 0.1)
		(layers "F.Cu" "B.Cu")
		(teardrops
			(best_length_ratio 0.4)
			(max_length 1)
			(best_width_ratio 0.9)
			(max_width 2)
			(curved_edges yes)
			(filter_ratio 0.9)
			(enabled yes)
			(allow_two_segments yes)
			(prefer_zone_connections yes)
		)
		(net 262)
	)
	(via
		(at 195.5935 161.5)
		(size 0.45)
		(drill 0.1)
		(layers "F.Cu" "B.Cu")
		(teardrops
			(best_length_ratio 0.4)
			(max_length 1)
			(best_width_ratio 0.9)
			(max_width 2)
			(curved_edges yes)
			(filter_ratio 0.9)
			(enabled yes)
			(allow_two_segments yes)
			(prefer_zone_connections yes)
		)
		(net 262)
	)
	(via
		(at 186.8 122.477)
		(size 0.45)
		(drill 0.1)
		(layers "F.Cu" "B.Cu")
		(teardrops
			(best_length_ratio 0.4)
			(max_length 1)
			(best_width_ratio 0.9)
			(max_width 2)
			(curved_edges yes)
			(filter_ratio 0.9)
			(enabled yes)
			(allow_two_segments yes)
			(prefer_zone_connections yes)
		)
		(net 262)
	)
	(arc
		(start 171.141113 109.656964)
		(mid 171.244784 109.614022)
		(end 171.287726 109.510351)
		(width 0.202)
		(layer "F.Cu")
		(net 262)
	)
	(arc
		(start 170.9945 109.803577)
		(mid 171.037442 109.699906)
		(end 171.141113 109.656964)
		(width 0.202)
		(layer "F.Cu")
		(net 262)
	)
	(arc
		(start 171.287726 108.003577)
		(mid 171.244784 107.899906)
		(end 171.141113 107.856964)
		(width 0.202)
		(layer "F.Cu")
		(net 262)
	)
	(arc
		(start 171.141113 107.856964)
		(mid 171.037442 107.814022)
		(end 170.9945 107.710351)
		(width 0.202)
		(layer "F.Cu")
		(net 262)
	)
	(arc
		(start 171.141113 109.056964)
		(mid 171.037442 109.014022)
		(end 170.9945 108.910351)
		(width 0.202)
		(layer "F.Cu")
		(net 262)
	)
	(arc
		(start 170.9945 108.603577)
		(mid 171.037442 108.499906)
		(end 171.141113 108.456964)
		(width 0.202)
		(layer "F.Cu")
		(net 262)
	)
	(arc
		(start 171.287726 109.203577)
		(mid 171.244784 109.099906)
		(end 171.141113 109.056964)
		(width 0.202)
		(layer "F.Cu")
		(net 262)
	)
	(arc
		(start 171.141113 108.456964)
		(mid 171.244784 108.414022)
		(end 171.287726 108.310351)
		(width 0.202)
		(layer "F.Cu")
		(net 262)
	)
	(segment
		(start 175.019499 103.3045)
		(end 173.724 103.3045)
		(width 0.202)
		(layer "B.Cu")
		(net 262)
	)
	(segment
		(start 173.724 103.3045)
		(end 173.6 103.4285)
		(width 0.202)
		(layer "B.Cu")
		(net 262)
	)
	(segment
		(start 176.2 103.36)
		(end 175.074999 103.36)
		(width 0.202)
		(layer "B.Cu")
		(net 262)
	)
	(segment
		(start 175.074999 103.36)
		(end 175.019499 103.3045)
		(width 0.202)
		(layer "B.Cu")
		(net 262)
	)
	(segment
		(start 195.777458 160.687)
		(end 198.777458 160.687)
		(width 0.178)
		(layer "In5.Cu")
		(net 262)
	)
	(segment
		(start 200.487 157.127458)
		(end 202.037 155.577458)
		(width 0.178)
		(layer "In5.Cu")
		(net 262)
	)
	(segment
		(start 203.087 143.727458)
		(end 203.087 128.022542)
		(width 0.178)
		(layer "In5.Cu")
		(net 262)
	)
	(segment
		(start 203.087 128.022542)
		(end 197.677458 122.613)
		(width 0.178)
		(layer "In5.Cu")
		(net 262)
	)
	(segment
		(start 186.936 122.613)
		(end 186.8 122.477)
		(width 0.178)
		(layer "In5.Cu")
		(net 262)
	)
	(segment
		(start 202.037 155.577458)
		(end 202.037 144.777458)
		(width 0.178)
		(layer "In5.Cu")
		(net 262)
	)
	(segment
		(start 195.5935 161.5)
		(end 195.462 161.3685)
		(width 0.178)
		(layer "In5.Cu")
		(net 262)
	)
	(segment
		(start 195.462 161.3685)
		(end 195.462 161.002458)
		(width 0.178)
		(layer "In5.Cu")
		(net 262)
	)
	(segment
		(start 202.037 144.777458)
		(end 203.087 143.727458)
		(width 0.178)
		(layer "In5.Cu")
		(net 262)
	)
	(segment
		(start 197.677458 122.613)
		(end 186.936 122.613)
		(width 0.178)
		(layer "In5.Cu")
		(net 262)
	)
	(segment
		(start 198.777458 160.687)
		(end 200.487 158.977458)
		(width 0.178)
		(layer "In5.Cu")
		(net 262)
	)
	(segment
		(start 195.462 161.002458)
		(end 195.777458 160.687)
		(width 0.178)
		(layer "In5.Cu")
		(net 262)
	)
	(segment
		(start 200.487 158.977458)
		(end 200.487 157.127458)
		(width 0.178)
		(layer "In5.Cu")
		(net 262)
	)
	(segment
		(start 181.419434 122.9945)
		(end 170.6055 112.180566)
		(width 0.202)
		(layer "F.Cu")
		(net 264)
	)
	(segment
		(start 170.6055 104.619434)
		(end 172.309434 102.9155)
		(width 0.202)
		(layer "F.Cu")
		(net 264)
	)
	(segment
		(start 186.6715 122.9945)
		(end 181.419434 122.9945)
		(width 0.202)
		(layer "F.Cu")
		(net 264)
	)
	(segment
		(start 172.309434 102.9155)
		(end 173.476 102.9155)
		(width 0.202)
		(layer "F.Cu")
		(net 264)
	)
	(segment
		(start 195.0805 161.766999)
		(end 195.0805 161.624)
		(width 0.202)
		(layer "F.Cu")
		(net 264)
	)
	(segment
		(start 170.6055 112.180566)
		(end 170.6055 104.619434)
		(width 0.202)
		(layer "F.Cu")
		(net 264)
	)
	(segment
		(start 173.476 102.9155)
		(end 173.6 102.7915)
		(width 0.202)
		(layer "F.Cu")
		(net 264)
	)
	(segment
		(start 186.8 123.123)
		(end 186.6715 122.9945)
		(width 0.202)
		(layer "F.Cu")
		(net 264)
	)
	(segment
		(start 195.025 163.135)
		(end 195.025 161.822499)
		(width 0.202)
		(layer "F.Cu")
		(net 264)
	)
	(segment
		(start 195.025 161.822499)
		(end 195.0805 161.766999)
		(width 0.202)
		(layer "F.Cu")
		(net 264)
	)
	(segment
		(start 195.0805 161.624)
		(end 194.9565 161.5)
		(width 0.202)
		(layer "F.Cu")
		(net 264)
	)
	(via
		(at 186.8 123.123)
		(size 0.45)
		(drill 0.1)
		(layers "F.Cu" "B.Cu")
		(teardrops
			(best_length_ratio 0.4)
			(max_length 1)
			(best_width_ratio 0.9)
			(max_width 2)
			(curved_edges yes)
			(filter_ratio 0.9)
			(enabled yes)
			(allow_two_segments yes)
			(prefer_zone_connections yes)
		)
		(net 264)
	)
	(via
		(at 173.6 102.7915)
		(size 0.45)
		(drill 0.1)
		(layers "F.Cu" "B.Cu")
		(teardrops
			(best_length_ratio 0.4)
			(max_length 1)
			(best_width_ratio 0.9)
			(max_width 2)
			(curved_edges yes)
			(filter_ratio 0.9)
			(enabled yes)
			(allow_two_segments yes)
			(prefer_zone_connections yes)
		)
		(net 264)
	)
	(via
		(at 194.9565 161.5)
		(size 0.45)
		(drill 0.1)
		(layers "F.Cu" "B.Cu")
		(teardrops
			(best_length_ratio 0.4)
			(max_length 1)
			(best_width_ratio 0.9)
			(max_width 2)
			(curved_edges yes)
			(filter_ratio 0.9)
			(enabled yes)
			(allow_two_segments yes)
			(prefer_zone_connections yes)
		)
		(net 264)
	)
	(segment
		(start 175.019499 102.9155)
		(end 173.724 102.9155)
		(width 0.202)
		(layer "B.Cu")
		(net 264)
	)
	(segment
		(start 173.724 102.9155)
		(end 173.6 102.7915)
		(width 0.202)
		(layer "B.Cu")
		(net 264)
	)
	(segment
		(start 175.074999 102.86)
		(end 175.019499 102.9155)
		(width 0.202)
		(layer "B.Cu")
		(net 264)
	)
	(segment
		(start 176.2 102.86)
		(end 175.074999 102.86)
		(width 0.202)
		(layer "B.Cu")
		(net 264)
	)
	(segment
		(start 202.713 143.572542)
		(end 202.713 128.177458)
		(width 0.178)
		(layer "In5.Cu")
		(net 264)
	)
	(segment
		(start 195.088 161.3685)
		(end 195.088 160.847542)
		(width 0.178)
		(layer "In5.Cu")
		(net 264)
	)
	(segment
		(start 201.663 155.422542)
		(end 201.663 144.622542)
		(width 0.178)
		(layer "In5.Cu")
		(net 264)
	)
	(segment
		(start 197.522542 122.987)
		(end 186.936 122.987)
		(width 0.178)
		(layer "In5.Cu")
		(net 264)
	)
	(segment
		(start 198.622542 160.313)
		(end 200.113 158.822542)
		(width 0.178)
		(layer "In5.Cu")
		(net 264)
	)
	(segment
		(start 200.113 158.822542)
		(end 200.113 156.972542)
		(width 0.178)
		(layer "In5.Cu")
		(net 264)
	)
	(segment
		(start 201.663 144.622542)
		(end 202.713 143.572542)
		(width 0.178)
		(layer "In5.Cu")
		(net 264)
	)
	(segment
		(start 200.113 156.972542)
		(end 201.663 155.422542)
		(width 0.178)
		(layer "In5.Cu")
		(net 264)
	)
	(segment
		(start 195.088 160.847542)
		(end 195.622542 160.313)
		(width 0.178)
		(layer "In5.Cu")
		(net 264)
	)
	(segment
		(start 202.713 128.177458)
		(end 197.522542 122.987)
		(width 0.178)
		(layer "In5.Cu")
		(net 264)
	)
	(segment
		(start 195.622542 160.313)
		(end 198.622542 160.313)
		(width 0.178)
		(layer "In5.Cu")
		(net 264)
	)
	(segment
		(start 186.936 122.987)
		(end 186.8 123.123)
		(width 0.178)
		(layer "In5.Cu")
		(net 264)
	)
	(segment
		(start 194.9565 161.5)
		(end 195.088 161.3685)
		(width 0.178)
		(layer "In5.Cu")
		(net 264)
	)
	(segment
		(start 195.4695 166.894434)
		(end 193.480566 164.9055)
		(width 0.202)
		(layer "F.Cu")
		(net 267)
	)
	(segment
		(start 195.4695 167.9045)
		(end 195.4695 166.894434)
		(width 0.202)
		(layer "F.Cu")
		(net 267)
	)
	(segment
		(start 193.480566 164.9055)
		(end 191.274 164.9055)
		(width 0.202)
		(layer "F.Cu")
		(net 267)
	)
	(segment
		(start 195.525 168.685)
		(end 195.525 167.96)
		(width 0.202)
		(layer "F.Cu")
		(net 267)
	)
	(segment
		(start 195.525 167.96)
		(end 195.4695 167.9045)
		(width 0.202)
		(layer "F.Cu")
		(net 267)
	)
	(segment
		(start 191.274 164.9055)
		(end 191.15 164.7815)
		(width 0.202)
		(layer "F.Cu")
		(net 267)
	)
	(via
		(at 174.24 104.9285)
		(size 0.45)
		(drill 0.1)
		(layers "F.Cu" "B.Cu")
		(teardrops
			(best_length_ratio 0.4)
			(max_length 1)
			(best_width_ratio 0.9)
			(max_width 2)
			(curved_edges yes)
			(filter_ratio 0.9)
			(enabled yes)
			(allow_two_segments yes)
			(prefer_zone_connections yes)
		)
		(net 267)
	)
	(via
		(at 191.15 164.7815)
		(size 0.45)
		(drill 0.1)
		(layers "F.Cu" "B.Cu")
		(teardrops
			(best_length_ratio 0.4)
			(max_length 1)
			(best_width_ratio 0.9)
			(max_width 2)
			(curved_edges yes)
			(filter_ratio 0.9)
			(enabled yes)
			(allow_two_segments yes)
			(prefer_zone_connections yes)
		)
		(net 267)
	)
	(segment
		(start 175.6 104.86)
		(end 175.5445 104.8045)
		(width 0.202)
		(layer "B.Cu")
		(net 267)
	)
	(segment
		(start 175.5445 104.8045)
		(end 174.364 104.8045)
		(width 0.202)
		(layer "B.Cu")
		(net 267)
	)
	(segment
		(start 176.2 104.86)
		(end 175.6 104.86)
		(width 0.202)
		(layer "B.Cu")
		(net 267)
	)
	(segment
		(start 174.364 104.8045)
		(end 174.24 104.9285)
		(width 0.202)
		(layer "B.Cu")
		(net 267)
	)
	(segment
		(start 186.187 127.522542)
		(end 186.187 138.722542)
		(width 0.178)
		(layer "In5.Cu")
		(net 267)
	)
	(segment
		(start 172.697 110.413355)
		(end 172.697 111.262081)
		(width 0.178)
		(layer "In5.Cu")
		(net 267)
	)
	(segment
		(start 172.697 111.262081)
		(end 172.697 114.032542)
		(width 0.178)
		(layer "In5.Cu")
		(net 267)
	)
	(segment
		(start 190.187 164.672542)
		(end 190.427458 164.913)
		(width 0.178)
		(layer "In5.Cu")
		(net 267)
	)
	(segment
		(start 186.187 138.722542)
		(end 190.187 142.722542)
		(width 0.178)
		(layer "In5.Cu")
		(net 267)
	)
	(segment
		(start 172.697 110.173777)
		(end 172.697 110.413355)
		(width 0.178)
		(layer "In5.Cu")
		(net 267)
	)
	(segment
		(start 191.0185 164.913)
		(end 191.15 164.7815)
		(width 0.178)
		(layer "In5.Cu")
		(net 267)
	)
	(segment
		(start 172.697 114.032542)
		(end 186.187 127.522542)
		(width 0.178)
		(layer "In5.Cu")
		(net 267)
	)
	(segment
		(start 172.957422 108.673777)
		(end 172.957422 108.913355)
		(width 0.178)
		(layer "In5.Cu")
		(net 267)
	)
	(segment
		(start 174.24 104.9285)
		(end 174.1085 104.797)
		(width 0.178)
		(layer "In5.Cu")
		(net 267)
	)
	(segment
		(start 172.957422 109.673777)
		(end 172.957422 109.913355)
		(width 0.178)
		(layer "In5.Cu")
		(net 267)
	)
	(segment
		(start 172.697 105.237458)
		(end 172.697 108.413355)
		(width 0.178)
		(layer "In5.Cu")
		(net 267)
	)
	(segment
		(start 190.187 142.722542)
		(end 190.187 164.672542)
		(width 0.178)
		(layer "In5.Cu")
		(net 267)
	)
	(segment
		(start 173.137458 104.797)
		(end 172.697 105.237458)
		(width 0.178)
		(layer "In5.Cu")
		(net 267)
	)
	(segment
		(start 190.427458 164.913)
		(end 191.0185 164.913)
		(width 0.178)
		(layer "In5.Cu")
		(net 267)
	)
	(segment
		(start 172.697 109.173777)
		(end 172.697 109.413355)
		(width 0.178)
		(layer "In5.Cu")
		(net 267)
	)
	(segment
		(start 174.1085 104.797)
		(end 173.137458 104.797)
		(width 0.178)
		(layer "In5.Cu")
		(net 267)
	)
	(arc
		(start 172.957422 109.913355)
		(mid 172.919284 110.005428)
		(end 172.827211 110.043566)
		(width 0.178)
		(layer "In5.Cu")
		(net 267)
	)
	(arc
		(start 172.827211 108.543566)
		(mid 172.919284 108.581704)
		(end 172.957422 108.673777)
		(width 0.178)
		(layer "In5.Cu")
		(net 267)
	)
	(arc
		(start 172.697 109.413355)
		(mid 172.735138 109.505428)
		(end 172.827211 109.543566)
		(width 0.178)
		(layer "In5.Cu")
		(net 267)
	)
	(arc
		(start 172.827211 110.043566)
		(mid 172.735138 110.081704)
		(end 172.697 110.173777)
		(width 0.178)
		(layer "In5.Cu")
		(net 267)
	)
	(arc
		(start 172.827211 109.043566)
		(mid 172.735138 109.081704)
		(end 172.697 109.173777)
		(width 0.178)
		(layer "In5.Cu")
		(net 267)
	)
	(arc
		(start 172.697 108.413355)
		(mid 172.735138 108.505428)
		(end 172.827211 108.543566)
		(width 0.178)
		(layer "In5.Cu")
		(net 267)
	)
	(arc
		(start 172.827211 109.543566)
		(mid 172.919284 109.581704)
		(end 172.957422 109.673777)
		(width 0.178)
		(layer "In5.Cu")
		(net 267)
	)
	(arc
		(start 172.957422 108.913355)
		(mid 172.919284 109.005428)
		(end 172.827211 109.043566)
		(width 0.178)
		(layer "In5.Cu")
		(net 267)
	)
	(segment
		(start 193.319434 165.2945)
		(end 191.274 165.2945)
		(width 0.202)
		(layer "F.Cu")
		(net 269)
	)
	(segment
		(start 195.0805 167.055566)
		(end 193.319434 165.2945)
		(width 0.202)
		(layer "F.Cu")
		(net 269)
	)
	(segment
		(start 195.025 167.96)
		(end 195.0805 167.9045)
		(width 0.202)
		(layer "F.Cu")
		(net 269)
	)
	(segment
		(start 191.274 165.2945)
		(end 191.15 165.4185)
		(width 0.202)
		(layer "F.Cu")
		(net 269)
	)
	(segment
		(start 195.025 168.685)
		(end 195.025 167.96)
		(width 0.202)
		(layer "F.Cu")
		(net 269)
	)
	(segment
		(start 195.0805 167.9045)
		(end 195.0805 167.055566)
		(width 0.202)
		(layer "F.Cu")
		(net 269)
	)
	(via
		(at 174.24 104.2915)
		(size 0.45)
		(drill 0.1)
		(layers "F.Cu" "B.Cu")
		(teardrops
			(best_length_ratio 0.4)
			(max_length 1)
			(best_width_ratio 0.9)
			(max_width 2)
			(curved_edges yes)
			(filter_ratio 0.9)
			(enabled yes)
			(allow_two_segments yes)
			(prefer_zone_connections yes)
		)
		(net 269)
	)
	(via
		(at 191.15 165.4185)
		(size 0.45)
		(drill 0.1)
		(layers "F.Cu" "B.Cu")
		(teardrops
			(best_length_ratio 0.4)
			(max_length 1)
			(best_width_ratio 0.9)
			(max_width 2)
			(curved_edges yes)
			(filter_ratio 0.9)
			(enabled yes)
			(allow_two_segments yes)
			(prefer_zone_connections yes)
		)
		(net 269)
	)
	(segment
		(start 175.5445 104.4155)
		(end 174.364 104.4155)
		(width 0.202)
		(layer "B.Cu")
		(net 269)
	)
	(segment
		(start 176.2 104.36)
		(end 175.6 104.36)
		(width 0.202)
		(layer "B.Cu")
		(net 269)
	)
	(segment
		(start 175.6 104.36)
		(end 175.5445 104.4155)
		(width 0.202)
		(layer "B.Cu")
		(net 269)
	)
	(segment
		(start 174.364 104.4155)
		(end 174.24 104.2915)
		(width 0.202)
		(layer "B.Cu")
		(net 269)
	)
	(segment
		(start 189.813 164.827458)
		(end 190.272542 165.287)
		(width 0.178)
		(layer "In5.Cu")
		(net 269)
	)
	(segment
		(start 172.323 105.082542)
		(end 172.323 114.187458)
		(width 0.178)
		(layer "In5.Cu")
		(net 269)
	)
	(segment
		(start 190.272542 165.287)
		(end 191.0185 165.287)
		(width 0.178)
		(layer "In5.Cu")
		(net 269)
	)
	(segment
		(start 189.813 142.877458)
		(end 189.813 164.827458)
		(width 0.178)
		(layer "In5.Cu")
		(net 269)
	)
	(segment
		(start 191.0185 165.287)
		(end 191.15 165.4185)
		(width 0.178)
		(layer "In5.Cu")
		(net 269)
	)
	(segment
		(start 174.1085 104.423)
		(end 172.982542 104.423)
		(width 0.178)
		(layer "In5.Cu")
		(net 269)
	)
	(segment
		(start 174.24 104.2915)
		(end 174.1085 104.423)
		(width 0.178)
		(layer "In5.Cu")
		(net 269)
	)
	(segment
		(start 185.813 138.877458)
		(end 189.813 142.877458)
		(width 0.178)
		(layer "In5.Cu")
		(net 269)
	)
	(segment
		(start 172.982542 104.423)
		(end 172.323 105.082542)
		(width 0.178)
		(layer "In5.Cu")
		(net 269)
	)
	(segment
		(start 172.323 114.187458)
		(end 185.813 127.677458)
		(width 0.178)
		(layer "In5.Cu")
		(net 269)
	)
	(segment
		(start 185.813 127.677458)
		(end 185.813 138.877458)
		(width 0.178)
		(layer "In5.Cu")
		(net 269)
	)
	(segment
		(start 298.449 81.583)
		(end 298.449 83.281)
		(width 0.125)
		(layer "F.Cu")
		(net 270)
	)
	(segment
		(start 298.449 83.281)
		(end 298.2 83.53)
		(width 0.125)
		(layer "F.Cu")
		(net 270)
	)
	(segment
		(start 298.2 83.53)
		(end 297.22 83.53)
		(width 0.125)
		(layer "F.Cu")
		(net 270)
	)
	(segment
		(start 258.119434 135.5055)
		(end 260.580566 135.5055)
		(width 0.202)
		(layer "F.Cu")
		(net 271)
	)
	(segment
		(start 228.713879 136.123813)
		(end 229.205566 136.6155)
		(width 0.202)
		(layer "F.Cu")
		(net 271)
	)
	(segment
		(start 221.665 129.65)
		(end 221.9705 129.9555)
		(width 0.202)
		(layer "F.Cu")
		(net 271)
	)
	(segment
		(start 222.858409 130.268343)
		(end 228.713879 136.123813)
		(width 0.202)
		(layer "F.Cu")
		(net 271)
	)
	(segment
		(start 299.199 74.66)
		(end 299.254 74.715)
		(width 0.202)
		(layer "F.Cu")
		(net 271)
	)
	(segment
		(start 229.205566 136.6155)
		(end 257.009434 136.6155)
		(width 0.202)
		(layer "F.Cu")
		(net 271)
	)
	(segment
		(start 221.9705 129.9555)
		(end 222.103139 129.9555)
		(width 0.202)
		(layer "F.Cu")
		(net 271)
	)
	(segment
		(start 257.009434 136.6155)
		(end 258.119434 135.5055)
		(width 0.202)
		(layer "F.Cu")
		(net 271)
	)
	(segment
		(start 261.0945 136.019434)
		(end 261.0945 136.876)
		(width 0.202)
		(layer "F.Cu")
		(net 271)
	)
	(segment
		(start 261.0945 136.876)
		(end 261.2185 137)
		(width 0.202)
		(layer "F.Cu")
		(net 271)
	)
	(segment
		(start 260.580566 135.5055)
		(end 261.0945 136.019434)
		(width 0.202)
		(layer "F.Cu")
		(net 271)
	)
	(segment
		(start 299.254 75.370635)
		(end 299.13 75.494635)
		(width 0.202)
		(layer "F.Cu")
		(net 271)
	)
	(segment
		(start 299.254 74.715)
		(end 299.254 75.370635)
		(width 0.202)
		(layer "F.Cu")
		(net 271)
	)
	(via
		(at 299.13 75.494635)
		(size 0.45)
		(drill 0.1)
		(layers "F.Cu" "B.Cu")
		(remove_unused_layers yes)
		(keep_end_layers yes)
		(zone_layer_connections)
		(teardrops
			(best_length_ratio 0.4)
			(max_length 1)
			(best_width_ratio 0.9)
			(max_width 2)
			(curved_edges yes)
			(filter_ratio 0.9)
			(enabled yes)
			(allow_two_segments yes)
			(prefer_zone_connections yes)
		)
		(net 271)
	)
	(via
		(at 261.2185 137)
		(size 0.45)
		(drill 0.1)
		(layers "F.Cu" "B.Cu")
		(teardrops
			(best_length_ratio 0.4)
			(max_length 1)
			(best_width_ratio 0.9)
			(max_width 2)
			(curved_edges yes)
			(filter_ratio 0.9)
			(enabled yes)
			(allow_two_segments yes)
			(prefer_zone_connections yes)
		)
		(net 271)
	)
	(arc
		(start 222.103139 129.9555)
		(mid 222.511888 130.036805)
		(end 222.858409 130.268343)
		(width 0.202)
		(layer "F.Cu")
		(net 271)
	)
	(segment
		(start 261.392028 135.292742)
		(end 261.2745 135.292742)
		(width 0.202)
		(layer "B.Cu")
		(net 271)
	)
	(segment
		(start 261.572028 135.562742)
		(end 261.572028 135.472742)
		(width 0.202)
		(layer "B.Cu")
		(net 271)
	)
	(segment
		(start 261.0945 134.580566)
		(end 261.538172 134.136894)
		(width 0.202)
		(layer "B.Cu")
		(net 271)
	)
	(segment
		(start 268.6045 76.420566)
		(end 275.855566 69.1695)
		(width 0.202)
		(layer "B.Cu")
		(net 271)
	)
	(segment
		(start 299.254 73.029066)
		(end 299.254 75.370635)
		(width 0.202)
		(layer "B.Cu")
		(net 271)
	)
	(segment
		(start 295.394434 69.1695)
		(end 299.254 73.029066)
		(width 0.202)
		(layer "B.Cu")
		(net 271)
	)
	(segment
		(start 261.0945 136.876)
		(end 261.0945 135.922742)
		(width 0.202)
		(layer "B.Cu")
		(net 271)
	)
	(segment
		(start 261.2185 137)
		(end 261.0945 136.876)
		(width 0.202)
		(layer "B.Cu")
		(net 271)
	)
	(segment
		(start 261.2745 135.742742)
		(end 261.392028 135.742742)
		(width 0.202)
		(layer "B.Cu")
		(net 271)
	)
	(segment
		(start 261.0945 135.112742)
		(end 261.0945 135.022742)
		(width 0.202)
		(layer "B.Cu")
		(net 271)
	)
	(segment
		(start 299.254 75.370635)
		(end 299.13 75.494635)
		(width 0.202)
		(layer "B.Cu")
		(net 271)
	)
	(segment
		(start 268.6045 127.070566)
		(end 268.6045 76.420566)
		(width 0.202)
		(layer "B.Cu")
		(net 271)
	)
	(segment
		(start 261.0945 135.022742)
		(end 261.0945 134.580566)
		(width 0.202)
		(layer "B.Cu")
		(net 271)
	)
	(segment
		(start 261.538172 134.136894)
		(end 268.6045 127.070566)
		(width 0.202)
		(layer "B.Cu")
		(net 271)
	)
	(segment
		(start 275.855566 69.1695)
		(end 295.394434 69.1695)
		(width 0.202)
		(layer "B.Cu")
		(net 271)
	)
	(arc
		(start 261.0945 135.922742)
		(mid 261.147221 135.795463)
		(end 261.2745 135.742742)
		(width 0.202)
		(layer "B.Cu")
		(net 271)
	)
	(arc
		(start 261.392028 135.742742)
		(mid 261.519307 135.690021)
		(end 261.572028 135.562742)
		(width 0.202)
		(layer "B.Cu")
		(net 271)
	)
	(arc
		(start 261.572028 135.472742)
		(mid 261.519307 135.345463)
		(end 261.392028 135.292742)
		(width 0.202)
		(layer "B.Cu")
		(net 271)
	)
	(arc
		(start 261.2745 135.292742)
		(mid 261.147221 135.240021)
		(end 261.0945 135.112742)
		(width 0.202)
		(layer "B.Cu")
		(net 271)
	)
	(segment
		(start 260.7055 136.876)
		(end 260.5815 137)
		(width 0.202)
		(layer "F.Cu")
		(net 273)
	)
	(segment
		(start 222.591994 130.55206)
		(end 228.458648 136.418714)
		(width 0.202)
		(layer "F.Cu")
		(net 273)
	)
	(segment
		(start 258.280566 135.8945)
		(end 260.419434 135.8945)
		(width 0.202)
		(layer "F.Cu")
		(net 273)
	)
	(segment
		(start 299.643 75.370635)
		(end 299.767 75.494635)
		(width 0.202)
		(layer "F.Cu")
		(net 273)
	)
	(segment
		(start 260.419434 135.8945)
		(end 260.7055 136.180566)
		(width 0.202)
		(layer "F.Cu")
		(net 273)
	)
	(segment
		(start 299.643 74.715)
		(end 299.643 75.370635)
		(width 0.202)
		(layer "F.Cu")
		(net 273)
	)
	(segment
		(start 221.9705 130.3445)
		(end 222.0909 130.3445)
		(width 0.202)
		(layer "F.Cu")
		(net 273)
	)
	(segment
		(start 228.458648 136.418714)
		(end 229.044434 137.0045)
		(width 0.202)
		(layer "F.Cu")
		(net 273)
	)
	(segment
		(start 299.698 74.66)
		(end 299.643 74.715)
		(width 0.202)
		(layer "F.Cu")
		(net 273)
	)
	(segment
		(start 221.665 130.65)
		(end 221.9705 130.3445)
		(width 0.202)
		(layer "F.Cu")
		(net 273)
	)
	(segment
		(start 260.7055 136.180566)
		(end 260.7055 136.876)
		(width 0.202)
		(layer "F.Cu")
		(net 273)
	)
	(segment
		(start 229.044434 137.0045)
		(end 257.170566 137.0045)
		(width 0.202)
		(layer "F.Cu")
		(net 273)
	)
	(segment
		(start 257.170566 137.0045)
		(end 258.280566 135.8945)
		(width 0.202)
		(layer "F.Cu")
		(net 273)
	)
	(via
		(at 299.767 75.494635)
		(size 0.45)
		(drill 0.1)
		(layers "F.Cu" "B.Cu")
		(remove_unused_layers yes)
		(keep_end_layers yes)
		(zone_layer_connections)
		(teardrops
			(best_length_ratio 0.4)
			(max_length 1)
			(best_width_ratio 0.9)
			(max_width 2)
			(curved_edges yes)
			(filter_ratio 0.9)
			(enabled yes)
			(allow_two_segments yes)
			(prefer_zone_connections yes)
		)
		(net 273)
	)
	(via
		(at 260.5815 137)
		(size 0.45)
		(drill 0.1)
		(layers "F.Cu" "B.Cu")
		(teardrops
			(best_length_ratio 0.4)
			(max_length 1)
			(best_width_ratio 0.9)
			(max_width 2)
			(curved_edges yes)
			(filter_ratio 0.9)
			(enabled yes)
			(allow_two_segments yes)
			(prefer_zone_connections yes)
		)
		(net 273)
	)
	(arc
		(start 222.0909 130.3445)
		(mid 222.36209 130.398443)
		(end 222.591994 130.55206)
		(width 0.202)
		(layer "F.Cu")
		(net 273)
	)
	(segment
		(start 295.555566 68.7805)
		(end 275.694434 68.7805)
		(width 0.202)
		(layer "B.Cu")
		(net 273)
	)
	(segment
		(start 275.694434 68.7805)
		(end 268.2155 76.259434)
		(width 0.202)
		(layer "B.Cu")
		(net 273)
	)
	(segment
		(start 268.2155 76.259434)
		(end 268.2155 126.909434)
		(width 0.202)
		(layer "B.Cu")
		(net 273)
	)
	(segment
		(start 299.643 75.370635)
		(end 299.643 72.867934)
		(width 0.202)
		(layer "B.Cu")
		(net 273)
	)
	(segment
		(start 299.767 75.494635)
		(end 299.643 75.370635)
		(width 0.202)
		(layer "B.Cu")
		(net 273)
	)
	(segment
		(start 299.643 72.867934)
		(end 295.555566 68.7805)
		(width 0.202)
		(layer "B.Cu")
		(net 273)
	)
	(segment
		(start 260.7055 134.419434)
		(end 260.7055 136.876)
		(width 0.202)
		(layer "B.Cu")
		(net 273)
	)
	(segment
		(start 260.7055 136.876)
		(end 260.5815 137)
		(width 0.202)
		(layer "B.Cu")
		(net 273)
	)
	(segment
		(start 268.2155 126.909434)
		(end 260.7055 134.419434)
		(width 0.202)
		(layer "B.Cu")
		(net 273)
	)
	(segment
		(start 302.948 83.528)
		(end 302.948 81.583)
		(width 0.125)
		(layer "F.Cu")
		(net 277)
	)
	(segment
		(start 261.160708 71.86)
		(end 264.581708 75.281)
		(width 0.125)
		(layer "F.Cu")
		(net 279)
	)
	(segment
		(start 264.581708 75.281)
		(end 264.581708 77.123)
		(width 0.125)
		(layer "F.Cu")
		(net 279)
	)
	(segment
		(start 258.620708 76.449999)
		(end 259.293709 77.123)
		(width 0.125)
		(layer "F.Cu")
		(net 280)
	)
	(segment
		(start 259.293709 77.123)
		(end 260.282708 77.123)
		(width 0.125)
		(layer "F.Cu")
		(net 280)
	)
	(segment
		(start 258.620708 71.86)
		(end 258.620708 76.449999)
		(width 0.125)
		(layer "F.Cu")
		(net 280)
	)
	(segment
		(start 247.430709 71.86)
		(end 250.851709 75.281)
		(width 0.125)
		(layer "F.Cu")
		(net 281)
	)
	(segment
		(start 250.851709 75.281)
		(end 250.851709 77.123)
		(width 0.125)
		(layer "F.Cu")
		(net 281)
	)
	(segment
		(start 244.890709 76.449999)
		(end 245.56371 77.123)
		(width 0.125)
		(layer "F.Cu")
		(net 282)
	)
	(segment
		(start 244.890709 71.86)
		(end 244.890709 76.449999)
		(width 0.125)
		(layer "F.Cu")
		(net 282)
	)
	(segment
		(start 245.56371 77.123)
		(end 246.552709 77.123)
		(width 0.125)
		(layer "F.Cu")
		(net 282)
	)
	(segment
		(start 233.700707 71.86)
		(end 237.121707 75.281)
		(width 0.125)
		(layer "F.Cu")
		(net 283)
	)
	(segment
		(start 237.121707 75.281)
		(end 237.121707 77.123)
		(width 0.125)
		(layer "F.Cu")
		(net 283)
	)
	(segment
		(start 231.160707 71.86)
		(end 231.160707 76.449999)
		(width 0.125)
		(layer "F.Cu")
		(net 284)
	)
	(segment
		(start 231.160707 76.449999)
		(end 231.833708 77.123)
		(width 0.125)
		(layer "F.Cu")
		(net 284)
	)
	(segment
		(start 231.833708 77.123)
		(end 232.822707 77.123)
		(width 0.125)
		(layer "F.Cu")
		(net 284)
	)
	(segment
		(start 176.525 167.96)
		(end 176.6 167.885)
		(width 0.15)
		(layer "F.Cu")
		(net 285)
	)
	(segment
		(start 141.713491 99.0525)
		(end 141.713491 98.71044)
		(width 0.15)
		(layer "F.Cu")
		(net 285)
	)
	(segment
		(start 143.713491 100.19456)
		(end 143.713491 98.710445)
		(width 0.15)
		(layer "F.Cu")
		(net 285)
	)
	(segment
		(start 145.288491 99.2775)
		(end 147.724988 99.2775)
		(width 0.15)
		(layer "F.Cu")
		(net 285)
	)
	(segment
		(start 170.775 158.727512)
		(end 172.575 160.527512)
		(width 0.15)
		(layer "F.Cu")
		(net 285)
	)
	(segment
		(start 143.063491 98.71044)
		(end 143.063491 100.19456)
		(width 0.15)
		(layer "F.Cu")
		(net 285)
	)
	(segment
		(start 170.775 122.327512)
		(end 170.775 158.727512)
		(width 0.15)
		(layer "F.Cu")
		(net 285)
	)
	(segment
		(start 145.063491 98.710445)
		(end 145.063491 99.0525)
		(width 0.15)
		(layer "F.Cu")
		(net 285)
	)
	(segment
		(start 144.288491 98.135445)
		(end 144.488491 98.135445)
		(width 0.15)
		(layer "F.Cu")
		(net 285)
	)
	(segment
		(start 142.288491 98.13544)
		(end 142.488491 98.13544)
		(width 0.15)
		(layer "F.Cu")
		(net 285)
	)
	(segment
		(start 176.6 167.55)
		(end 176.45 167.4)
		(width 0.15)
		(layer "F.Cu")
		(net 285)
	)
	(segment
		(start 135.4075 99.2775)
		(end 141.488491 99.2775)
		(width 0.15)
		(layer "F.Cu")
		(net 285)
	)
	(segment
		(start 176.6 167.885)
		(end 176.6 167.55)
		(width 0.15)
		(layer "F.Cu")
		(net 285)
	)
	(segment
		(start 176.525 168.685)
		(end 176.525 167.96)
		(width 0.15)
		(layer "F.Cu")
		(net 285)
	)
	(segment
		(start 172.575 160.527512)
		(end 172.575 161.05)
		(width 0.15)
		(layer "F.Cu")
		(net 285)
	)
	(segment
		(start 172.575 161.05)
		(end 172.725 161.2)
		(width 0.15)
		(layer "F.Cu")
		(net 285)
	)
	(segment
		(start 147.724988 99.2775)
		(end 170.775 122.327512)
		(width 0.15)
		(layer "F.Cu")
		(net 285)
	)
	(segment
		(start 135.16 99.03)
		(end 135.4075 99.2775)
		(width 0.15)
		(layer "F.Cu")
		(net 285)
	)
	(segment
		(start 143.288491 100.41956)
		(end 143.488491 100.41956)
		(width 0.15)
		(layer "F.Cu")
		(net 285)
	)
	(via
		(at 172.725 161.2)
		(size 0.45)
		(drill 0.1)
		(layers "F.Cu" "B.Cu")
		(teardrops
			(best_length_ratio 0.4)
			(max_length 1)
			(best_width_ratio 0.9)
			(max_width 2)
			(curved_edges yes)
			(filter_ratio 0.9)
			(enabled yes)
			(allow_two_segments yes)
			(prefer_zone_connections yes)
		)
		(net 285)
	)
	(via
		(at 176.45 167.4)
		(size 0.45)
		(drill 0.1)
		(layers "F.Cu" "B.Cu")
		(teardrops
			(best_length_ratio 0.4)
			(max_length 1)
			(best_width_ratio 0.9)
			(max_width 2)
			(curved_edges yes)
			(filter_ratio 0.9)
			(enabled yes)
			(allow_two_segments yes)
			(prefer_zone_connections yes)
		)
		(net 285)
	)
	(arc
		(start 141.488491 99.2775)
		(mid 141.64759 99.211599)
		(end 141.713491 99.0525)
		(width 0.15)
		(layer "F.Cu")
		(net 285)
	)
	(arc
		(start 144.488491 98.135445)
		(mid 144.895077 98.303859)
		(end 145.063491 98.710445)
		(width 0.15)
		(layer "F.Cu")
		(net 285)
	)
	(arc
		(start 145.063491 99.0525)
		(mid 145.129392 99.211599)
		(end 145.288491 99.2775)
		(width 0.15)
		(layer "F.Cu")
		(net 285)
	)
	(arc
		(start 142.488491 98.13544)
		(mid 142.895077 98.303854)
		(end 143.063491 98.71044)
		(width 0.15)
		(layer "F.Cu")
		(net 285)
	)
	(arc
		(start 141.713491 98.71044)
		(mid 141.881905 98.303854)
		(end 142.288491 98.13544)
		(width 0.15)
		(layer "F.Cu")
		(net 285)
	)
	(arc
		(start 143.713491 98.710445)
		(mid 143.881905 98.303859)
		(end 144.288491 98.135445)
		(width 0.15)
		(layer "F.Cu")
		(net 285)
	)
	(arc
		(start 143.063491 100.19456)
		(mid 143.129392 100.353659)
		(end 143.288491 100.41956)
		(width 0.15)
		(layer "F.Cu")
		(net 285)
	)
	(arc
		(start 143.488491 100.41956)
		(mid 143.64759 100.353659)
		(end 143.713491 100.19456)
		(width 0.15)
		(layer "F.Cu")
		(net 285)
	)
	(segment
		(start 176.6 167.752512)
		(end 176.6 167.55)
		(width 0.15)
		(layer "B.Cu")
		(net 285)
	)
	(segment
		(start 176.327512 168.025)
		(end 176.6 167.752512)
		(width 0.15)
		(layer "B.Cu")
		(net 285)
	)
	(segment
		(start 172.175 166.072488)
		(end 171.575 166.672488)
		(width 0.15)
		(layer "B.Cu")
		(net 285)
	)
	(segment
		(start 171.575 167.327512)
		(end 172.272488 168.025)
		(width 0.15)
		(layer "B.Cu")
		(net 285)
	)
	(segment
		(start 174.102582 167.845)
		(end 174.102582 167.775485)
		(width 0.15)
		(layer "B.Cu")
		(net 285)
	)
	(segment
		(start 176.6 167.55)
		(end 176.45 167.4)
		(width 0.15)
		(layer "B.Cu")
		(net 285)
	)
	(segment
		(start 174.552582 167.775485)
		(end 174.552582 167.845)
		(width 0.15)
		(layer "B.Cu")
		(net 285)
	)
	(segment
		(start 172.272488 168.025)
		(end 173.922582 168.025)
		(width 0.15)
		(layer "B.Cu")
		(net 285)
	)
	(segment
		(start 172.575 161.35)
		(end 172.575 163.972488)
		(width 0.15)
		(layer "B.Cu")
		(net 285)
	)
	(segment
		(start 171.575 166.672488)
		(end 171.575 167.327512)
		(width 0.15)
		(layer "B.Cu")
		(net 285)
	)
	(segment
		(start 174.282582 167.595485)
		(end 174.372582 167.595485)
		(width 0.15)
		(layer "B.Cu")
		(net 285)
	)
	(segment
		(start 174.732582 168.025)
		(end 176.327512 168.025)
		(width 0.15)
		(layer "B.Cu")
		(net 285)
	)
	(segment
		(start 172.175 164.372488)
		(end 172.175 166.072488)
		(width 0.15)
		(layer "B.Cu")
		(net 285)
	)
	(segment
		(start 172.725 161.2)
		(end 172.575 161.35)
		(width 0.15)
		(layer "B.Cu")
		(net 285)
	)
	(segment
		(start 172.575 163.972488)
		(end 172.175 164.372488)
		(width 0.15)
		(layer "B.Cu")
		(net 285)
	)
	(arc
		(start 173.922582 168.025)
		(mid 174.049861 167.972279)
		(end 174.102582 167.845)
		(width 0.15)
		(layer "B.Cu")
		(net 285)
	)
	(arc
		(start 174.372582 167.595485)
		(mid 174.499861 167.648206)
		(end 174.552582 167.775485)
		(width 0.15)
		(layer "B.Cu")
		(net 285)
	)
	(arc
		(start 174.102582 167.775485)
		(mid 174.155303 167.648206)
		(end 174.282582 167.595485)
		(width 0.15)
		(layer "B.Cu")
		(net 285)
	)
	(arc
		(start 174.552582 167.845)
		(mid 174.605303 167.972279)
		(end 174.732582 168.025)
		(width 0.15)
		(layer "B.Cu")
		(net 285)
	)
	(segment
		(start 172.225 160.672488)
		(end 172.225 161.05)
		(width 0.15)
		(layer "F.Cu")
		(net 286)
	)
	(segment
		(start 147.580012 99.6275)
		(end 170.425 122.472488)
		(width 0.15)
		(layer "F.Cu")
		(net 286)
	)
	(segment
		(start 142.063491 99.0525)
		(end 142.063491 98.71044)
		(width 0.15)
		(layer "F.Cu")
		(net 286)
	)
	(segment
		(start 177.025 167.96)
		(end 176.95 167.885)
		(width 0.15)
		(layer "F.Cu")
		(net 286)
	)
	(segment
		(start 142.713491 98.71044)
		(end 142.713491 100.19456)
		(width 0.15)
		(layer "F.Cu")
		(net 286)
	)
	(segment
		(start 135.165 99.815)
		(end 135.3525 99.6275)
		(width 0.15)
		(layer "F.Cu")
		(net 286)
	)
	(segment
		(start 143.288491 100.76956)
		(end 143.488491 100.76956)
		(width 0.15)
		(layer "F.Cu")
		(net 286)
	)
	(segment
		(start 172.225 161.05)
		(end 172.075 161.2)
		(width 0.15)
		(layer "F.Cu")
		(net 286)
	)
	(segment
		(start 177.025 168.685)
		(end 177.025 167.96)
		(width 0.15)
		(layer "F.Cu")
		(net 286)
	)
	(segment
		(start 135.3525 99.6275)
		(end 141.488491 99.6275)
		(width 0.15)
		(layer "F.Cu")
		(net 286)
	)
	(segment
		(start 170.425 158.872488)
		(end 172.225 160.672488)
		(width 0.15)
		(layer "F.Cu")
		(net 286)
	)
	(segment
		(start 144.063491 100.19456)
		(end 144.063491 98.710445)
		(width 0.15)
		(layer "F.Cu")
		(net 286)
	)
	(segment
		(start 142.288491 98.48544)
		(end 142.488491 98.48544)
		(width 0.15)
		(layer "F.Cu")
		(net 286)
	)
	(segment
		(start 176.95 167.55)
		(end 177.1 167.4)
		(width 0.15)
		(layer "F.Cu")
		(net 286)
	)
	(segment
		(start 144.288491 98.485445)
		(end 144.488491 98.485445)
		(width 0.15)
		(layer "F.Cu")
		(net 286)
	)
	(segment
		(start 145.288491 99.6275)
		(end 147.580012 99.6275)
		(width 0.15)
		(layer "F.Cu")
		(net 286)
	)
	(segment
		(start 170.425 122.472488)
		(end 170.425 158.872488)
		(width 0.15)
		(layer "F.Cu")
		(net 286)
	)
	(segment
		(start 144.713491 98.710445)
		(end 144.713491 99.0525)
		(width 0.15)
		(layer "F.Cu")
		(net 286)
	)
	(segment
		(start 176.95 167.885)
		(end 176.95 167.55)
		(width 0.15)
		(layer "F.Cu")
		(net 286)
	)
	(via
		(at 172.075 161.2)
		(size 0.45)
		(drill 0.1)
		(layers "F.Cu" "B.Cu")
		(teardrops
			(best_length_ratio 0.4)
			(max_length 1)
			(best_width_ratio 0.9)
			(max_width 2)
			(curved_edges yes)
			(filter_ratio 0.9)
			(enabled yes)
			(allow_two_segments yes)
			(prefer_zone_connections yes)
		)
		(net 286)
	)
	(via
		(at 177.1 167.4)
		(size 0.45)
		(drill 0.1)
		(layers "F.Cu" "B.Cu")
		(teardrops
			(best_length_ratio 0.4)
			(max_length 1)
			(best_width_ratio 0.9)
			(max_width 2)
			(curved_edges yes)
			(filter_ratio 0.9)
			(enabled yes)
			(allow_two_segments yes)
			(prefer_zone_connections yes)
		)
		(net 286)
	)
	(arc
		(start 144.713491 99.0525)
		(mid 144.881905 99.459086)
		(end 145.288491 99.6275)
		(width 0.15)
		(layer "F.Cu")
		(net 286)
	)
	(arc
		(start 142.063491 98.71044)
		(mid 142.129392 98.551341)
		(end 142.288491 98.48544)
		(width 0.15)
		(layer "F.Cu")
		(net 286)
	)
	(arc
		(start 142.488491 98.48544)
		(mid 142.64759 98.551341)
		(end 142.713491 98.71044)
		(width 0.15)
		(layer "F.Cu")
		(net 286)
	)
	(arc
		(start 143.488491 100.76956)
		(mid 143.895077 100.601146)
		(end 144.063491 100.19456)
		(width 0.15)
		(layer "F.Cu")
		(net 286)
	)
	(arc
		(start 144.063491 98.710445)
		(mid 144.129392 98.551346)
		(end 144.288491 98.485445)
		(width 0.15)
		(layer "F.Cu")
		(net 286)
	)
	(arc
		(start 142.713491 100.19456)
		(mid 142.881905 100.601146)
		(end 143.288491 100.76956)
		(width 0.15)
		(layer "F.Cu")
		(net 286)
	)
	(arc
		(start 144.488491 98.485445)
		(mid 144.64759 98.551346)
		(end 144.713491 98.710445)
		(width 0.15)
		(layer "F.Cu")
		(net 286)
	)
	(arc
		(start 141.488491 99.6275)
		(mid 141.895077 99.459086)
		(end 142.063491 99.0525)
		(width 0.15)
		(layer "F.Cu")
		(net 286)
	)
	(segment
		(start 171.225 166.527512)
		(end 171.225 167.472488)
		(width 0.15)
		(layer "B.Cu")
		(net 286)
	)
	(segment
		(start 172.225 161.35)
		(end 172.225 163.827512)
		(width 0.15)
		(layer "B.Cu")
		(net 286)
	)
	(segment
		(start 171.825 164.227512)
		(end 171.825 165.927512)
		(width 0.15)
		(layer "B.Cu")
		(net 286)
	)
	(segment
		(start 171.825 165.927512)
		(end 171.225 166.527512)
		(width 0.15)
		(layer "B.Cu")
		(net 286)
	)
	(segment
		(start 171.225 167.472488)
		(end 172.127512 168.375)
		(width 0.15)
		(layer "B.Cu")
		(net 286)
	)
	(segment
		(start 172.075 161.2)
		(end 172.225 161.35)
		(width 0.15)
		(layer "B.Cu")
		(net 286)
	)
	(segment
		(start 176.95 167.897488)
		(end 176.95 167.55)
		(width 0.15)
		(layer "B.Cu")
		(net 286)
	)
	(segment
		(start 172.127512 168.375)
		(end 176.472488 168.375)
		(width 0.15)
		(layer "B.Cu")
		(net 286)
	)
	(segment
		(start 176.472488 168.375)
		(end 176.95 167.897488)
		(width 0.15)
		(layer "B.Cu")
		(net 286)
	)
	(segment
		(start 172.225 163.827512)
		(end 171.825 164.227512)
		(width 0.15)
		(layer "B.Cu")
		(net 286)
	)
	(segment
		(start 176.95 167.55)
		(end 177.1 167.4)
		(width 0.15)
		(layer "B.Cu")
		(net 286)
	)
	(segment
		(start 145.2 150.7)
		(end 146 149.9)
		(width 0.125)
		(layer "F.Cu")
		(net 288)
	)
	(segment
		(start 178.025 169.975)
		(end 178 170)
		(width 0.125)
		(layer "F.Cu")
		(net 288)
	)
	(segment
		(start 125.11 111.2)
		(end 124.5 111.81)
		(width 0.125)
		(layer "F.Cu")
		(net 288)
	)
	(segment
		(start 146 149.6)
		(end 146 149.9)
		(width 0.125)
		(layer "F.Cu")
		(net 288)
	)
	(segment
		(start 178.025 168.685)
		(end 178.025 169.975)
		(width 0.125)
		(layer "F.Cu")
		(net 288)
	)
	(segment
		(start 145.2 150.7)
		(end 145.2 152.3)
		(width 0.125)
		(layer "F.Cu")
		(net 288)
	)
	(segment
		(start 126.5 111.2)
		(end 125.11 111.2)
		(width 0.125)
		(layer "F.Cu")
		(net 288)
	)
	(via
		(at 178 170)
		(size 0.45)
		(drill 0.1)
		(layers "F.Cu" "B.Cu")
		(teardrops
			(best_length_ratio 0.4)
			(max_length 1)
			(best_width_ratio 0.9)
			(max_width 2)
			(curved_edges yes)
			(filter_ratio 0.9)
			(enabled yes)
			(allow_two_segments yes)
			(prefer_zone_connections yes)
		)
		(net 288)
	)
	(via
		(at 145.2 152.3)
		(size 0.45)
		(drill 0.1)
		(layers "F.Cu" "B.Cu")
		(teardrops
			(best_length_ratio 0.4)
			(max_length 1)
			(best_width_ratio 0.9)
			(max_width 2)
			(curved_edges yes)
			(filter_ratio 0.9)
			(enabled yes)
			(allow_two_segments yes)
			(prefer_zone_connections yes)
		)
		(net 288)
	)
	(via
		(at 124.5 111.81)
		(size 0.45)
		(drill 0.1)
		(layers "F.Cu" "B.Cu")
		(remove_unused_layers yes)
		(keep_end_layers yes)
		(zone_layer_connections)
		(teardrops
			(best_length_ratio 0.4)
			(max_length 1)
			(best_width_ratio 0.9)
			(max_width 2)
			(curved_edges yes)
			(filter_ratio 0.9)
			(enabled yes)
			(allow_two_segments yes)
			(prefer_zone_connections yes)
		)
		(net 288)
	)
	(via
		(at 146 149.6)
		(size 0.45)
		(drill 0.1)
		(layers "F.Cu" "B.Cu")
		(teardrops
			(best_length_ratio 0.4)
			(max_length 1)
			(best_width_ratio 0.9)
			(max_width 2)
			(curved_edges yes)
			(filter_ratio 0.9)
			(enabled yes)
			(allow_two_segments yes)
			(prefer_zone_connections yes)
		)
		(net 288)
	)
	(via
		(at 126.5 111.2)
		(size 0.45)
		(drill 0.1)
		(layers "F.Cu" "B.Cu")
		(remove_unused_layers yes)
		(keep_end_layers yes)
		(zone_layer_connections "In2.Cu")
		(teardrops
			(best_length_ratio 0.4)
			(max_length 1)
			(best_width_ratio 0.9)
			(max_width 2)
			(curved_edges yes)
			(filter_ratio 0.9)
			(enabled yes)
			(allow_two_segments yes)
			(prefer_zone_connections yes)
		)
		(net 288)
	)
	(segment
		(start 124.265 109.81)
		(end 123.88 109.81)
		(width 0.125)
		(layer "B.Cu")
		(net 288)
	)
	(segment
		(start 125.655 111.2)
		(end 124.265 109.81)
		(width 0.125)
		(layer "B.Cu")
		(net 288)
	)
	(segment
		(start 123.88 111.81)
		(end 124.5 111.81)
		(width 0.125)
		(layer "B.Cu")
		(net 288)
	)
	(segment
		(start 126.5 111.2)
		(end 125.655 111.2)
		(width 0.125)
		(layer "B.Cu")
		(net 288)
	)
	(segment
		(start 126.5 130.1)
		(end 126.8 130.4)
		(width 0.125)
		(layer "In2.Cu")
		(net 288)
	)
	(segment
		(start 154.6 152.3)
		(end 155.3 151.6)
		(width 0.125)
		(layer "In2.Cu")
		(net 288)
	)
	(segment
		(start 177.3 169.3)
		(end 178 170)
		(width 0.125)
		(layer "In2.Cu")
		(net 288)
	)
	(segment
		(start 155.3 151.6)
		(end 158.9 151.6)
		(width 0.125)
		(layer "In2.Cu")
		(net 288)
	)
	(segment
		(start 163.9 163.7)
		(end 169.5 169.3)
		(width 0.125)
		(layer "In2.Cu")
		(net 288)
	)
	(segment
		(start 126.5 111.2)
		(end 127.4 111.2)
		(width 0.125)
		(layer "In2.Cu")
		(net 288)
	)
	(segment
		(start 160.02 152.72)
		(end 160.02 157.82)
		(width 0.125)
		(layer "In2.Cu")
		(net 288)
	)
	(segment
		(start 126.5 115.6)
		(end 126.5 130.1)
		(width 0.125)
		(layer "In2.Cu")
		(net 288)
	)
	(segment
		(start 126.8 140.4)
		(end 127.8 141.4)
		(width 0.125)
		(layer "In2.Cu")
		(net 288)
	)
	(segment
		(start 163.9 161.7)
		(end 163.9 163.7)
		(width 0.125)
		(layer "In2.Cu")
		(net 288)
	)
	(segment
		(start 127.8 141.4)
		(end 138.49 141.4)
		(width 0.125)
		(layer "In2.Cu")
		(net 288)
	)
	(segment
		(start 127.4 111.2)
		(end 127.7 111.5)
		(width 0.125)
		(layer "In2.Cu")
		(net 288)
	)
	(segment
		(start 127.7 114.4)
		(end 126.5 115.6)
		(width 0.125)
		(layer "In2.Cu")
		(net 288)
	)
	(segment
		(start 169.5 169.3)
		(end 177.3 169.3)
		(width 0.125)
		(layer "In2.Cu")
		(net 288)
	)
	(segment
		(start 127.7 111.5)
		(end 127.7 114.4)
		(width 0.125)
		(layer "In2.Cu")
		(net 288)
	)
	(segment
		(start 146 148.91)
		(end 146 149.6)
		(width 0.125)
		(layer "In2.Cu")
		(net 288)
	)
	(segment
		(start 158.9 151.6)
		(end 160.02 152.72)
		(width 0.125)
		(layer "In2.Cu")
		(net 288)
	)
	(segment
		(start 138.49 141.4)
		(end 146 148.91)
		(width 0.125)
		(layer "In2.Cu")
		(net 288)
	)
	(segment
		(start 160.02 157.82)
		(end 163.9 161.7)
		(width 0.125)
		(layer "In2.Cu")
		(net 288)
	)
	(segment
		(start 126.8 130.4)
		(end 126.8 140.4)
		(width 0.125)
		(layer "In2.Cu")
		(net 288)
	)
	(segment
		(start 145.2 152.3)
		(end 154.6 152.3)
		(width 0.125)
		(layer "In2.Cu")
		(net 288)
	)
	(segment
		(start 178.6 167.55)
		(end 178.45 167.4)
		(width 0.15)
		(layer "F.Cu")
		(net 289)
	)
	(segment
		(start 166.575 149.65)
		(end 166.725 149.8)
		(width 0.15)
		(layer "F.Cu")
		(net 289)
	)
	(segment
		(start 146.163692 108.108138)
		(end 146.359692 108.108138)
		(width 0.15)
		(layer "F.Cu")
		(net 289)
	)
	(segment
		(start 143.223692 106.046862)
		(end 143.419692 106.046862)
		(width 0.15)
		(layer "F.Cu")
		(net 289)
	)
	(segment
		(start 149.724988 107.0775)
		(end 166.575 123.927512)
		(width 0.15)
		(layer "F.Cu")
		(net 289)
	)
	(segment
		(start 178.525 167.96)
		(end 178.6 167.885)
		(width 0.15)
		(layer "F.Cu")
		(net 289)
	)
	(segment
		(start 144.616692 107.891138)
		(end 144.616692 106.613862)
		(width 0.15)
		(layer "F.Cu")
		(net 289)
	)
	(segment
		(start 142.656692 106.8605)
		(end 142.656692 106.613862)
		(width 0.15)
		(layer "F.Cu")
		(net 289)
	)
	(segment
		(start 147.143692 106.046862)
		(end 147.339692 106.046862)
		(width 0.15)
		(layer "F.Cu")
		(net 289)
	)
	(segment
		(start 145.946692 106.613862)
		(end 145.946692 107.891138)
		(width 0.15)
		(layer "F.Cu")
		(net 289)
	)
	(segment
		(start 135.3275 107.0775)
		(end 142.439692 107.0775)
		(width 0.15)
		(layer "F.Cu")
		(net 289)
	)
	(segment
		(start 148.123692 107.0775)
		(end 149.724988 107.0775)
		(width 0.15)
		(layer "F.Cu")
		(net 289)
	)
	(segment
		(start 178.525 168.685)
		(end 178.525 167.96)
		(width 0.15)
		(layer "F.Cu")
		(net 289)
	)
	(segment
		(start 178.6 167.885)
		(end 178.6 167.55)
		(width 0.15)
		(layer "F.Cu")
		(net 289)
	)
	(segment
		(start 145.183692 106.046862)
		(end 145.379692 106.046862)
		(width 0.15)
		(layer "F.Cu")
		(net 289)
	)
	(segment
		(start 144.203692 108.108138)
		(end 144.399692 108.108138)
		(width 0.15)
		(layer "F.Cu")
		(net 289)
	)
	(segment
		(start 146.576692 107.891138)
		(end 146.576692 106.613862)
		(width 0.15)
		(layer "F.Cu")
		(net 289)
	)
	(segment
		(start 166.575 123.927512)
		(end 166.575 149.65)
		(width 0.15)
		(layer "F.Cu")
		(net 289)
	)
	(segment
		(start 143.986692 106.613862)
		(end 143.986692 107.891138)
		(width 0.15)
		(layer "F.Cu")
		(net 289)
	)
	(segment
		(start 135.09 106.84)
		(end 135.3275 107.0775)
		(width 0.15)
		(layer "F.Cu")
		(net 289)
	)
	(segment
		(start 147.906692 106.613862)
		(end 147.906692 106.8605)
		(width 0.15)
		(layer "F.Cu")
		(net 289)
	)
	(via
		(at 166.725 149.8)
		(size 0.45)
		(drill 0.1)
		(layers "F.Cu" "B.Cu")
		(teardrops
			(best_length_ratio 0.4)
			(max_length 1)
			(best_width_ratio 0.9)
			(max_width 2)
			(curved_edges yes)
			(filter_ratio 0.9)
			(enabled yes)
			(allow_two_segments yes)
			(prefer_zone_connections yes)
		)
		(net 289)
	)
	(via
		(at 178.45 167.4)
		(size 0.45)
		(drill 0.1)
		(layers "F.Cu" "B.Cu")
		(teardrops
			(best_length_ratio 0.4)
			(max_length 1)
			(best_width_ratio 0.9)
			(max_width 2)
			(curved_edges yes)
			(filter_ratio 0.9)
			(enabled yes)
			(allow_two_segments yes)
			(prefer_zone_connections yes)
		)
		(net 289)
	)
	(arc
		(start 145.946692 107.891138)
		(mid 146.01025 108.04458)
		(end 146.163692 108.108138)
		(width 0.15)
		(layer "F.Cu")
		(net 289)
	)
	(arc
		(start 146.576692 106.613862)
		(mid 146.742762 106.212932)
		(end 147.143692 106.046862)
		(width 0.15)
		(layer "F.Cu")
		(net 289)
	)
	(arc
		(start 145.379692 106.046862)
		(mid 145.780622 106.212932)
		(end 145.946692 106.613862)
		(width 0.15)
		(layer "F.Cu")
		(net 289)
	)
	(arc
		(start 147.339692 106.046862)
		(mid 147.740622 106.212932)
		(end 147.906692 106.613862)
		(width 0.15)
		(layer "F.Cu")
		(net 289)
	)
	(arc
		(start 142.656692 106.613862)
		(mid 142.822762 106.212932)
		(end 143.223692 106.046862)
		(width 0.15)
		(layer "F.Cu")
		(net 289)
	)
	(arc
		(start 147.906692 106.8605)
		(mid 147.97025 107.013942)
		(end 148.123692 107.0775)
		(width 0.15)
		(layer "F.Cu")
		(net 289)
	)
	(arc
		(start 144.399692 108.108138)
		(mid 144.553134 108.04458)
		(end 144.616692 107.891138)
		(width 0.15)
		(layer "F.Cu")
		(net 289)
	)
	(arc
		(start 143.986692 107.891138)
		(mid 144.05025 108.04458)
		(end 144.203692 108.108138)
		(width 0.15)
		(layer "F.Cu")
		(net 289)
	)
	(arc
		(start 143.419692 106.046862)
		(mid 143.820622 106.212932)
		(end 143.986692 106.613862)
		(width 0.15)
		(layer "F.Cu")
		(net 289)
	)
	(arc
		(start 146.359692 108.108138)
		(mid 146.513134 108.04458)
		(end 146.576692 107.891138)
		(width 0.15)
		(layer "F.Cu")
		(net 289)
	)
	(arc
		(start 144.616692 106.613862)
		(mid 144.782762 106.212932)
		(end 145.183692 106.046862)
		(width 0.15)
		(layer "F.Cu")
		(net 289)
	)
	(arc
		(start 142.439692 107.0775)
		(mid 142.593134 107.013942)
		(end 142.656692 106.8605)
		(width 0.15)
		(layer "F.Cu")
		(net 289)
	)
	(segment
		(start 173.258307 169.000751)
		(end 173.258307 169.049)
		(width 0.15)
		(layer "B.Cu")
		(net 289)
	)
	(segment
		(start 169.375 166.927512)
		(end 171.672488 169.225)
		(width 0.15)
		(layer "B.Cu")
		(net 289)
	)
	(segment
		(start 169.375 153.127512)
		(end 169.375 166.927512)
		(width 0.15)
		(layer "B.Cu")
		(net 289)
	)
	(segment
		(start 172.994307 168.824751)
		(end 173.082307 168.824751)
		(width 0.15)
		(layer "B.Cu")
		(net 289)
	)
	(segment
		(start 178.6 168.752512)
		(end 178.6 167.55)
		(width 0.15)
		(layer "B.Cu")
		(net 289)
	)
	(segment
		(start 178.6 167.55)
		(end 178.45 167.4)
		(width 0.15)
		(layer "B.Cu")
		(net 289)
	)
	(segment
		(start 166.725 149.8)
		(end 166.575 149.95)
		(width 0.15)
		(layer "B.Cu")
		(net 289)
	)
	(segment
		(start 173.434307 169.225)
		(end 178.127512 169.225)
		(width 0.15)
		(layer "B.Cu")
		(net 289)
	)
	(segment
		(start 171.672488 169.225)
		(end 172.642307 169.225)
		(width 0.15)
		(layer "B.Cu")
		(net 289)
	)
	(segment
		(start 172.818307 169.049)
		(end 172.818307 169.000751)
		(width 0.15)
		(layer "B.Cu")
		(net 289)
	)
	(segment
		(start 178.127512 169.225)
		(end 178.6 168.752512)
		(width 0.15)
		(layer "B.Cu")
		(net 289)
	)
	(segment
		(start 166.575 149.95)
		(end 166.575 150.327512)
		(width 0.15)
		(layer "B.Cu")
		(net 289)
	)
	(segment
		(start 166.575 150.327512)
		(end 169.375 153.127512)
		(width 0.15)
		(layer "B.Cu")
		(net 289)
	)
	(arc
		(start 173.258307 169.049)
		(mid 173.309856 169.173451)
		(end 173.434307 169.225)
		(width 0.15)
		(layer "B.Cu")
		(net 289)
	)
	(arc
		(start 173.082307 168.824751)
		(mid 173.206758 168.8763)
		(end 173.258307 169.000751)
		(width 0.15)
		(layer "B.Cu")
		(net 289)
	)
	(arc
		(start 172.818307 169.000751)
		(mid 172.869856 168.8763)
		(end 172.994307 168.824751)
		(width 0.15)
		(layer "B.Cu")
		(net 289)
	)
	(arc
		(start 172.642307 169.225)
		(mid 172.766758 169.173451)
		(end 172.818307 169.049)
		(width 0.15)
		(layer "B.Cu")
		(net 289)
	)
	(segment
		(start 135.155 107.625)
		(end 135.3525 107.4275)
		(width 0.15)
		(layer "F.Cu")
		(net 290)
	)
	(segment
		(start 144.203692 108.458138)
		(end 144.399692 108.458138)
		(width 0.15)
		(layer "F.Cu")
		(net 290)
	)
	(segment
		(start 146.163692 108.458138)
		(end 146.359692 108.458138)
		(width 0.15)
		(layer "F.Cu")
		(net 290)
	)
	(segment
		(start 166.225 124.072488)
		(end 166.225 149.65)
		(width 0.15)
		(layer "F.Cu")
		(net 290)
	)
	(segment
		(start 143.006692 106.8605)
		(end 143.006692 106.613862)
		(width 0.15)
		(layer "F.Cu")
		(net 290)
	)
	(segment
		(start 179.025 168.685)
		(end 179.025 167.96)
		(width 0.15)
		(layer "F.Cu")
		(net 290)
	)
	(segment
		(start 143.636692 106.613862)
		(end 143.636692 107.891138)
		(width 0.15)
		(layer "F.Cu")
		(net 290)
	)
	(segment
		(start 178.95 167.885)
		(end 178.95 167.55)
		(width 0.15)
		(layer "F.Cu")
		(net 290)
	)
	(segment
		(start 178.95 167.55)
		(end 179.1 167.4)
		(width 0.15)
		(layer "F.Cu")
		(net 290)
	)
	(segment
		(start 148.123692 107.4275)
		(end 149.580012 107.4275)
		(width 0.15)
		(layer "F.Cu")
		(net 290)
	)
	(segment
		(start 179.025 167.96)
		(end 178.95 167.885)
		(width 0.15)
		(layer "F.Cu")
		(net 290)
	)
	(segment
		(start 147.143692 106.396862)
		(end 147.339692 106.396862)
		(width 0.15)
		(layer "F.Cu")
		(net 290)
	)
	(segment
		(start 166.225 149.65)
		(end 166.075 149.8)
		(width 0.15)
		(layer "F.Cu")
		(net 290)
	)
	(segment
		(start 143.223692 106.396862)
		(end 143.419692 106.396862)
		(width 0.15)
		(layer "F.Cu")
		(net 290)
	)
	(segment
		(start 145.596692 106.613862)
		(end 145.596692 107.891138)
		(width 0.15)
		(layer "F.Cu")
		(net 290)
	)
	(segment
		(start 144.966692 107.891138)
		(end 144.966692 106.613862)
		(width 0.15)
		(layer "F.Cu")
		(net 290)
	)
	(segment
		(start 149.580012 107.4275)
		(end 166.225 124.072488)
		(width 0.15)
		(layer "F.Cu")
		(net 290)
	)
	(segment
		(start 146.926692 107.891138)
		(end 146.926692 106.613862)
		(width 0.15)
		(layer "F.Cu")
		(net 290)
	)
	(segment
		(start 135.3525 107.4275)
		(end 142.439692 107.4275)
		(width 0.15)
		(layer "F.Cu")
		(net 290)
	)
	(segment
		(start 145.183692 106.396862)
		(end 145.379692 106.396862)
		(width 0.15)
		(layer "F.Cu")
		(net 290)
	)
	(segment
		(start 147.556692 106.613862)
		(end 147.556692 106.8605)
		(width 0.15)
		(layer "F.Cu")
		(net 290)
	)
	(via
		(at 179.1 167.4)
		(size 0.45)
		(drill 0.1)
		(layers "F.Cu" "B.Cu")
		(teardrops
			(best_length_ratio 0.4)
			(max_length 1)
			(best_width_ratio 0.9)
			(max_width 2)
			(curved_edges yes)
			(filter_ratio 0.9)
			(enabled yes)
			(allow_two_segments yes)
			(prefer_zone_connections yes)
		)
		(net 290)
	)
	(via
		(at 166.075 149.8)
		(size 0.45)
		(drill 0.1)
		(layers "F.Cu" "B.Cu")
		(teardrops
			(best_length_ratio 0.4)
			(max_length 1)
			(best_width_ratio 0.9)
			(max_width 2)
			(curved_edges yes)
			(filter_ratio 0.9)
			(enabled yes)
			(allow_two_segments yes)
			(prefer_zone_connections yes)
		)
		(net 290)
	)
	(arc
		(start 144.966692 106.613862)
		(mid 145.03025 106.46042)
		(end 145.183692 106.396862)
		(width 0.15)
		(layer "F.Cu")
		(net 290)
	)
	(arc
		(start 147.556692 106.8605)
		(mid 147.722762 107.26143)
		(end 148.123692 107.4275)
		(width 0.15)
		(layer "F.Cu")
		(net 290)
	)
	(arc
		(start 143.006692 106.613862)
		(mid 143.07025 106.46042)
		(end 143.223692 106.396862)
		(width 0.15)
		(layer "F.Cu")
		(net 290)
	)
	(arc
		(start 143.419692 106.396862)
		(mid 143.573134 106.46042)
		(end 143.636692 106.613862)
		(width 0.15)
		(layer "F.Cu")
		(net 290)
	)
	(arc
		(start 146.926692 106.613862)
		(mid 146.99025 106.46042)
		(end 147.143692 106.396862)
		(width 0.15)
		(layer "F.Cu")
		(net 290)
	)
	(arc
		(start 142.439692 107.4275)
		(mid 142.840622 107.26143)
		(end 143.006692 106.8605)
		(width 0.15)
		(layer "F.Cu")
		(net 290)
	)
	(arc
		(start 146.359692 108.458138)
		(mid 146.760622 108.292068)
		(end 146.926692 107.891138)
		(width 0.15)
		(layer "F.Cu")
		(net 290)
	)
	(arc
		(start 145.379692 106.396862)
		(mid 145.533134 106.46042)
		(end 145.596692 106.613862)
		(width 0.15)
		(layer "F.Cu")
		(net 290)
	)
	(arc
		(start 147.339692 106.396862)
		(mid 147.493134 106.46042)
		(end 147.556692 106.613862)
		(width 0.15)
		(layer "F.Cu")
		(net 290)
	)
	(arc
		(start 144.399692 108.458138)
		(mid 144.800622 108.292068)
		(end 144.966692 107.891138)
		(width 0.15)
		(layer "F.Cu")
		(net 290)
	)
	(arc
		(start 145.596692 107.891138)
		(mid 145.762762 108.292068)
		(end 146.163692 108.458138)
		(width 0.15)
		(layer "F.Cu")
		(net 290)
	)
	(arc
		(start 143.636692 107.891138)
		(mid 143.802762 108.292068)
		(end 144.203692 108.458138)
		(width 0.15)
		(layer "F.Cu")
		(net 290)
	)
	(segment
		(start 178.95 168.897488)
		(end 178.95 167.55)
		(width 0.15)
		(layer "B.Cu")
		(net 290)
	)
	(segment
		(start 166.075 149.8)
		(end 166.225 149.95)
		(width 0.15)
		(layer "B.Cu")
		(net 290)
	)
	(segment
		(start 166.225 150.472488)
		(end 169.025 153.272488)
		(width 0.15)
		(layer "B.Cu")
		(net 290)
	)
	(segment
		(start 171.527512 169.575)
		(end 178.272488 169.575)
		(width 0.15)
		(layer "B.Cu")
		(net 290)
	)
	(segment
		(start 166.225 149.95)
		(end 166.225 150.472488)
		(width 0.15)
		(layer "B.Cu")
		(net 290)
	)
	(segment
		(start 178.95 167.55)
		(end 179.1 167.4)
		(width 0.15)
		(layer "B.Cu")
		(net 290)
	)
	(segment
		(start 178.272488 169.575)
		(end 178.95 168.897488)
		(width 0.15)
		(layer "B.Cu")
		(net 290)
	)
	(segment
		(start 169.025 153.272488)
		(end 169.025 167.072488)
		(width 0.15)
		(layer "B.Cu")
		(net 290)
	)
	(segment
		(start 169.025 167.072488)
		(end 171.527512 169.575)
		(width 0.15)
		(layer "B.Cu")
		(net 290)
	)
	(segment
		(start 179.525 169.975)
		(end 179.5 170)
		(width 0.125)
		(layer "F.Cu")
		(net 291)
	)
	(segment
		(start 144.6 152.5)
		(end 144.6 150.1)
		(width 0.125)
		(layer "F.Cu")
		(net 291)
	)
	(segment
		(start 179.525 168.685)
		(end 179.525 169.975)
		(width 0.125)
		(layer "F.Cu")
		(net 291)
	)
	(segment
		(start 144.6 150.1)
		(end 145.2 149.5)
		(width 0.125)
		(layer "F.Cu")
		(net 291)
	)
	(via
		(at 179.5 170)
		(size 0.45)
		(drill 0.1)
		(layers "F.Cu" "B.Cu")
		(teardrops
			(best_length_ratio 0.4)
			(max_length 1)
			(best_width_ratio 0.9)
			(max_width 2)
			(curved_edges yes)
			(filter_ratio 0.9)
			(enabled yes)
			(allow_two_segments yes)
			(prefer_zone_connections yes)
		)
		(net 291)
	)
	(via
		(at 144.6 152.5)
		(size 0.45)
		(drill 0.1)
		(layers "F.Cu" "B.Cu")
		(teardrops
			(best_length_ratio 0.4)
			(max_length 1)
			(best_width_ratio 0.9)
			(max_width 2)
			(curved_edges yes)
			(filter_ratio 0.9)
			(enabled yes)
			(allow_two_segments yes)
			(prefer_zone_connections yes)
		)
		(net 291)
	)
	(via
		(at 127.1 111.7)
		(size 0.45)
		(drill 0.1)
		(layers "F.Cu" "B.Cu")
		(teardrops
			(best_length_ratio 0.4)
			(max_length 1)
			(best_width_ratio 0.9)
			(max_width 2)
			(curved_edges yes)
			(filter_ratio 0.9)
			(enabled yes)
			(allow_two_segments yes)
			(prefer_zone_connections yes)
		)
		(net 291)
	)
	(via
		(at 145.2 149.5)
		(size 0.45)
		(drill 0.1)
		(layers "F.Cu" "B.Cu")
		(teardrops
			(best_length_ratio 0.4)
			(max_length 1)
			(best_width_ratio 0.9)
			(max_width 2)
			(curved_edges yes)
			(filter_ratio 0.9)
			(enabled yes)
			(allow_two_segments yes)
			(prefer_zone_connections yes)
		)
		(net 291)
	)
	(segment
		(start 125.05 112.31)
		(end 125.69 112.31)
		(width 0.125)
		(layer "B.Cu")
		(net 291)
	)
	(segment
		(start 124.35 110.81)
		(end 123.88 110.81)
		(width 0.125)
		(layer "B.Cu")
		(net 291)
	)
	(segment
		(start 125.05 111.51)
		(end 124.35 110.81)
		(width 0.125)
		(layer "B.Cu")
		(net 291)
	)
	(segment
		(start 125.05 112.31)
		(end 125.05 111.51)
		(width 0.125)
		(layer "B.Cu")
		(net 291)
	)
	(segment
		(start 126.3 111.7)
		(end 127.1 111.7)
		(width 0.125)
		(layer "B.Cu")
		(net 291)
	)
	(segment
		(start 124.55 112.81)
		(end 123.88 112.81)
		(width 0.125)
		(layer "B.Cu")
		(net 291)
	)
	(segment
		(start 125.69 112.31)
		(end 126.3 111.7)
		(width 0.125)
		(layer "B.Cu")
		(net 291)
	)
	(segment
		(start 125.05 112.31)
		(end 124.55 112.81)
		(width 0.125)
		(layer "B.Cu")
		(net 291)
	)
	(segment
		(start 125.9 140.4)
		(end 129.8 144.3)
		(width 0.125)
		(layer "In2.Cu")
		(net 291)
	)
	(segment
		(start 145.3 153.5)
		(end 144.6 152.8)
		(width 0.125)
		(layer "In2.Cu")
		(net 291)
	)
	(segment
		(start 129.8 144.3)
		(end 140 144.3)
		(width 0.125)
		(layer "In2.Cu")
		(net 291)
	)
	(segment
		(start 170.7 171)
		(end 163.6 163.9)
		(width 0.125)
		(layer "In2.Cu")
		(net 291)
	)
	(segment
		(start 125.9 115.4)
		(end 127.1 114.2)
		(width 0.125)
		(layer "In2.Cu")
		(net 291)
	)
	(segment
		(start 178.5 171)
		(end 170.7 171)
		(width 0.125)
		(layer "In2.Cu")
		(net 291)
	)
	(segment
		(start 144.6 152.8)
		(end 144.6 152.5)
		(width 0.125)
		(layer "In2.Cu")
		(net 291)
	)
	(segment
		(start 159 152.2)
		(end 158.8 152)
		(width 0.125)
		(layer "In2.Cu")
		(net 291)
	)
	(segment
		(start 155.7 152)
		(end 154.2 153.5)
		(width 0.125)
		(layer "In2.Cu")
		(net 291)
	)
	(segment
		(start 159 157.5)
		(end 159 152.2)
		(width 0.125)
		(layer "In2.Cu")
		(net 291)
	)
	(segment
		(start 158.8 152)
		(end 155.7 152)
		(width 0.125)
		(layer "In2.Cu")
		(net 291)
	)
	(segment
		(start 154.2 153.5)
		(end 145.3 153.5)
		(width 0.125)
		(layer "In2.Cu")
		(net 291)
	)
	(segment
		(start 145.2 149.5)
		(end 140 144.3)
		(width 0.125)
		(layer "In2.Cu")
		(net 291)
	)
	(segment
		(start 125.9 140.4)
		(end 125.9 115.4)
		(width 0.125)
		(layer "In2.Cu")
		(net 291)
	)
	(segment
		(start 163.6 163.9)
		(end 163.6 162.1)
		(width 0.125)
		(layer "In2.Cu")
		(net 291)
	)
	(segment
		(start 163.6 162.1)
		(end 159 157.5)
		(width 0.125)
		(layer "In2.Cu")
		(net 291)
	)
	(segment
		(start 127.1 114.2)
		(end 127.1 111.7)
		(width 0.125)
		(layer "In2.Cu")
		(net 291)
	)
	(segment
		(start 179.5 170)
		(end 178.5 171)
		(width 0.125)
		(layer "In2.Cu")
		(net 291)
	)
	(segment
		(start 170.925 164)
		(end 170.775 163.85)
		(width 0.15)
		(layer "F.Cu")
		(net 292)
	)
	(segment
		(start 170.775 163.85)
		(end 170.775 161.527512)
		(width 0.15)
		(layer "F.Cu")
		(net 292)
	)
	(segment
		(start 148.814988 103.1675)
		(end 135.4075 103.1675)
		(width 0.15)
		(layer "F.Cu")
		(net 292)
	)
	(segment
		(start 180.025 167.96)
		(end 180.1 167.885)
		(width 0.15)
		(layer "F.Cu")
		(net 292)
	)
	(segment
		(start 170.775 161.527512)
		(end 168.775 159.527512)
		(width 0.15)
		(layer "F.Cu")
		(net 292)
	)
	(segment
		(start 180.1 167.55)
		(end 179.95 167.4)
		(width 0.15)
		(layer "F.Cu")
		(net 292)
	)
	(segment
		(start 168.775 159.527512)
		(end 168.775 123.127512)
		(width 0.15)
		(layer "F.Cu")
		(net 292)
	)
	(segment
		(start 180.025 168.685)
		(end 180.025 167.96)
		(width 0.15)
		(layer "F.Cu")
		(net 292)
	)
	(segment
		(start 168.775 123.127512)
		(end 148.814988 103.1675)
		(width 0.15)
		(layer "F.Cu")
		(net 292)
	)
	(segment
		(start 135.4075 103.1675)
		(end 135.16 102.92)
		(width 0.15)
		(layer "F.Cu")
		(net 292)
	)
	(segment
		(start 180.1 167.885)
		(end 180.1 167.55)
		(width 0.15)
		(layer "F.Cu")
		(net 292)
	)
	(via
		(at 179.95 167.4)
		(size 0.45)
		(drill 0.1)
		(layers "F.Cu" "B.Cu")
		(teardrops
			(best_length_ratio 0.4)
			(max_length 1)
			(best_width_ratio 0.9)
			(max_width 2)
			(curved_edges yes)
			(filter_ratio 0.9)
			(enabled yes)
			(allow_two_segments yes)
			(prefer_zone_connections yes)
		)
		(net 292)
	)
	(via
		(at 170.925 164)
		(size 0.45)
		(drill 0.1)
		(layers "F.Cu" "B.Cu")
		(teardrops
			(best_length_ratio 0.4)
			(max_length 1)
			(best_width_ratio 0.9)
			(max_width 2)
			(curved_edges yes)
			(filter_ratio 0.9)
			(enabled yes)
			(allow_two_segments yes)
			(prefer_zone_connections yes)
		)
		(net 292)
	)
	(segment
		(start 173.127512 159.575)
		(end 171.272488 159.575)
		(width 0.15)
		(layer "B.Cu")
		(net 292)
	)
	(segment
		(start 171.019462 162.390357)
		(end 170.955 162.390357)
		(width 0.15)
		(layer "B.Cu")
		(net 292)
	)
	(segment
		(start 170.775 162.570357)
		(end 170.775 163.85)
		(width 0.15)
		(layer "B.Cu")
		(net 292)
	)
	(segment
		(start 180.1 167.25)
		(end 180.1 163.347488)
		(width 0.15)
		(layer "B.Cu")
		(net 292)
	)
	(segment
		(start 170.955 161.940357)
		(end 171.019462 161.940357)
		(width 0.15)
		(layer "B.Cu")
		(net 292)
	)
	(segment
		(start 171.199462 162.120357)
		(end 171.199462 162.210357)
		(width 0.15)
		(layer "B.Cu")
		(net 292)
	)
	(segment
		(start 174.727512 161.175)
		(end 173.127512 159.575)
		(width 0.15)
		(layer "B.Cu")
		(net 292)
	)
	(segment
		(start 177.927512 161.175)
		(end 174.727512 161.175)
		(width 0.15)
		(layer "B.Cu")
		(net 292)
	)
	(segment
		(start 170.775 163.85)
		(end 170.925 164)
		(width 0.15)
		(layer "B.Cu")
		(net 292)
	)
	(segment
		(start 171.272488 159.575)
		(end 170.775 160.072488)
		(width 0.15)
		(layer "B.Cu")
		(net 292)
	)
	(segment
		(start 179.95 167.4)
		(end 180.1 167.25)
		(width 0.15)
		(layer "B.Cu")
		(net 292)
	)
	(segment
		(start 180.1 163.347488)
		(end 177.927512 161.175)
		(width 0.15)
		(layer "B.Cu")
		(net 292)
	)
	(segment
		(start 170.775 160.072488)
		(end 170.775 161.760357)
		(width 0.15)
		(layer "B.Cu")
		(net 292)
	)
	(arc
		(start 170.955 162.390357)
		(mid 170.827721 162.443078)
		(end 170.775 162.570357)
		(width 0.15)
		(layer "B.Cu")
		(net 292)
	)
	(arc
		(start 171.199462 162.210357)
		(mid 171.146741 162.337636)
		(end 171.019462 162.390357)
		(width 0.15)
		(layer "B.Cu")
		(net 292)
	)
	(arc
		(start 170.775 161.760357)
		(mid 170.827721 161.887636)
		(end 170.955 161.940357)
		(width 0.15)
		(layer "B.Cu")
		(net 292)
	)
	(arc
		(start 171.019462 161.940357)
		(mid 171.146741 161.993078)
		(end 171.199462 162.120357)
		(width 0.15)
		(layer "B.Cu")
		(net 292)
	)
	(segment
		(start 168.425 123.272488)
		(end 148.670012 103.5175)
		(width 0.15)
		(layer "F.Cu")
		(net 293)
	)
	(segment
		(start 148.670012 103.5175)
		(end 135.3625 103.5175)
		(width 0.15)
		(layer "F.Cu")
		(net 293)
	)
	(segment
		(start 135.3625 103.5175)
		(end 135.175 103.705)
		(width 0.15)
		(layer "F.Cu")
		(net 293)
	)
	(segment
		(start 180.45 167.55)
		(end 180.6 167.4)
		(width 0.15)
		(layer "F.Cu")
		(net 293)
	)
	(segment
		(start 180.525 167.96)
		(end 180.45 167.885)
		(width 0.15)
		(layer "F.Cu")
		(net 293)
	)
	(segment
		(start 180.525 168.685)
		(end 180.525 167.96)
		(width 0.15)
		(layer "F.Cu")
		(net 293)
	)
	(segment
		(start 170.275 164)
		(end 170.425 163.85)
		(width 0.15)
		(layer "F.Cu")
		(net 293)
	)
	(segment
		(start 170.425 163.85)
		(end 170.425 161.672488)
		(width 0.15)
		(layer "F.Cu")
		(net 293)
	)
	(segment
		(start 170.425 161.672488)
		(end 168.425 159.672488)
		(width 0.15)
		(layer "F.Cu")
		(net 293)
	)
	(segment
		(start 168.425 159.672488)
		(end 168.425 123.272488)
		(width 0.15)
		(layer "F.Cu")
		(net 293)
	)
	(segment
		(start 180.45 167.885)
		(end 180.45 167.55)
		(width 0.15)
		(layer "F.Cu")
		(net 293)
	)
	(via
		(at 180.6 167.4)
		(size 0.45)
		(drill 0.1)
		(layers "F.Cu" "B.Cu")
		(teardrops
			(best_length_ratio 0.4)
			(max_length 1)
			(best_width_ratio 0.9)
			(max_width 2)
			(curved_edges yes)
			(filter_ratio 0.9)
			(enabled yes)
			(allow_two_segments yes)
			(prefer_zone_connections yes)
		)
		(net 293)
	)
	(via
		(at 170.275 164)
		(size 0.45)
		(drill 0.1)
		(layers "F.Cu" "B.Cu")
		(teardrops
			(best_length_ratio 0.4)
			(max_length 1)
			(best_width_ratio 0.9)
			(max_width 2)
			(curved_edges yes)
			(filter_ratio 0.9)
			(enabled yes)
			(allow_two_segments yes)
			(prefer_zone_connections yes)
		)
		(net 293)
	)
	(segment
		(start 173.272488 159.225)
		(end 174.872488 160.825)
		(width 0.15)
		(layer "B.Cu")
		(net 293)
	)
	(segment
		(start 171.127512 159.225)
		(end 173.272488 159.225)
		(width 0.15)
		(layer "B.Cu")
		(net 293)
	)
	(segment
		(start 178.072488 160.825)
		(end 180.45 163.202512)
		(width 0.15)
		(layer "B.Cu")
		(net 293)
	)
	(segment
		(start 180.45 167.25)
		(end 180.6 167.4)
		(width 0.15)
		(layer "B.Cu")
		(net 293)
	)
	(segment
		(start 174.872488 160.825)
		(end 178.072488 160.825)
		(width 0.15)
		(layer "B.Cu")
		(net 293)
	)
	(segment
		(start 170.425 163.85)
		(end 170.425 159.927512)
		(width 0.15)
		(layer "B.Cu")
		(net 293)
	)
	(segment
		(start 180.45 163.202512)
		(end 180.45 167.25)
		(width 0.15)
		(layer "B.Cu")
		(net 293)
	)
	(segment
		(start 170.275 164)
		(end 170.425 163.85)
		(width 0.15)
		(layer "B.Cu")
		(net 293)
	)
	(segment
		(start 170.425 159.927512)
		(end 171.127512 159.225)
		(width 0.15)
		(layer "B.Cu")
		(net 293)
	)
	(segment
		(start 181.525 167.96)
		(end 181.6 167.885)
		(width 0.15)
		(layer "F.Cu")
		(net 294)
	)
	(segment
		(start 181.6 167.55)
		(end 181.45 167.4)
		(width 0.15)
		(layer "F.Cu")
		(net 294)
	)
	(segment
		(start 138.884194 109.886814)
		(end 139.084194 109.886814)
		(width 0.15)
		(layer "F.Cu")
		(net 294)
	)
	(segment
		(start 141.884194 110.9775)
		(end 150.824988 110.9775)
		(width 0.15)
		(layer "F.Cu")
		(net 294)
	)
	(segment
		(start 138.309194 110.7525)
		(end 138.309194 110.461814)
		(width 0.15)
		(layer "F.Cu")
		(net 294)
	)
	(segment
		(start 164.375 149.65)
		(end 164.525 149.8)
		(width 0.15)
		(layer "F.Cu")
		(net 294)
	)
	(segment
		(start 140.884194 109.886814)
		(end 141.084194 109.886814)
		(width 0.15)
		(layer "F.Cu")
		(net 294)
	)
	(segment
		(start 135.43 110.9775)
		(end 135.1825 110.73)
		(width 0.15)
		(layer "F.Cu")
		(net 294)
	)
	(segment
		(start 181.525 168.685)
		(end 181.525 167.96)
		(width 0.15)
		(layer "F.Cu")
		(net 294)
	)
	(segment
		(start 139.884194 112.068166)
		(end 140.084194 112.068166)
		(width 0.15)
		(layer "F.Cu")
		(net 294)
	)
	(segment
		(start 150.824988 110.9775)
		(end 164.375 124.527512)
		(width 0.15)
		(layer "F.Cu")
		(net 294)
	)
	(segment
		(start 135.1825 110.73)
		(end 134.835 110.73)
		(width 0.15)
		(layer "F.Cu")
		(net 294)
	)
	(segment
		(start 140.309194 111.843166)
		(end 140.309194 110.461814)
		(width 0.15)
		(layer "F.Cu")
		(net 294)
	)
	(segment
		(start 164.375 124.527512)
		(end 164.375 149.65)
		(width 0.15)
		(layer "F.Cu")
		(net 294)
	)
	(segment
		(start 139.659194 110.461814)
		(end 139.659194 111.843166)
		(width 0.15)
		(layer "F.Cu")
		(net 294)
	)
	(segment
		(start 135.43 110.9775)
		(end 138.084194 110.9775)
		(width 0.15)
		(layer "F.Cu")
		(net 294)
	)
	(segment
		(start 141.659194 110.461814)
		(end 141.659194 110.7525)
		(width 0.15)
		(layer "F.Cu")
		(net 294)
	)
	(segment
		(start 181.6 167.885)
		(end 181.6 167.55)
		(width 0.15)
		(layer "F.Cu")
		(net 294)
	)
	(via
		(at 181.45 167.4)
		(size 0.45)
		(drill 0.1)
		(layers "F.Cu" "B.Cu")
		(teardrops
			(best_length_ratio 0.4)
			(max_length 1)
			(best_width_ratio 0.9)
			(max_width 2)
			(curved_edges yes)
			(filter_ratio 0.9)
			(enabled yes)
			(allow_two_segments yes)
			(prefer_zone_connections yes)
		)
		(net 294)
	)
	(via
		(at 164.525 149.8)
		(size 0.45)
		(drill 0.1)
		(layers "F.Cu" "B.Cu")
		(teardrops
			(best_length_ratio 0.4)
			(max_length 1)
			(best_width_ratio 0.9)
			(max_width 2)
			(curved_edges yes)
			(filter_ratio 0.9)
			(enabled yes)
			(allow_two_segments yes)
			(prefer_zone_connections yes)
		)
		(net 294)
	)
	(arc
		(start 141.084194 109.886814)
		(mid 141.49078 110.055228)
		(end 141.659194 110.461814)
		(width 0.15)
		(layer "F.Cu")
		(net 294)
	)
	(arc
		(start 141.659194 110.7525)
		(mid 141.725095 110.911599)
		(end 141.884194 110.9775)
		(width 0.15)
		(layer "F.Cu")
		(net 294)
	)
	(arc
		(start 140.309194 110.461814)
		(mid 140.477608 110.055228)
		(end 140.884194 109.886814)
		(width 0.15)
		(layer "F.Cu")
		(net 294)
	)
	(arc
		(start 139.084194 109.886814)
		(mid 139.49078 110.055228)
		(end 139.659194 110.461814)
		(width 0.15)
		(layer "F.Cu")
		(net 294)
	)
	(arc
		(start 138.309194 110.461814)
		(mid 138.477608 110.055228)
		(end 138.884194 109.886814)
		(width 0.15)
		(layer "F.Cu")
		(net 294)
	)
	(arc
		(start 139.659194 111.843166)
		(mid 139.725095 112.002265)
		(end 139.884194 112.068166)
		(width 0.15)
		(layer "F.Cu")
		(net 294)
	)
	(arc
		(start 140.084194 112.068166)
		(mid 140.243293 112.002265)
		(end 140.309194 111.843166)
		(width 0.15)
		(layer "F.Cu")
		(net 294)
	)
	(arc
		(start 138.084194 110.9775)
		(mid 138.243293 110.911599)
		(end 138.309194 110.7525)
		(width 0.15)
		(layer "F.Cu")
		(net 294)
	)
	(segment
		(start 170.872488 170.625)
		(end 173.031047 170.625)
		(width 0.15)
		(layer "B.Cu")
		(net 294)
	)
	(segment
		(start 164.375 149.95)
		(end 164.375 150.927512)
		(width 0.15)
		(layer "B.Cu")
		(net 294)
	)
	(segment
		(start 173.731047 170.404368)
		(end 173.731047 170.425)
		(width 0.15)
		(layer "B.Cu")
		(net 294)
	)
	(segment
		(start 164.375 150.927512)
		(end 167.975 154.527512)
		(width 0.15)
		(layer "B.Cu")
		(net 294)
	)
	(segment
		(start 174.031047 170.625)
		(end 175.217905 170.625)
		(width 0.15)
		(layer "B.Cu")
		(net 294)
	)
	(segment
		(start 181.6 167.55)
		(end 181.45 167.4)
		(width 0.15)
		(layer "B.Cu")
		(net 294)
	)
	(segment
		(start 167.975 167.727512)
		(end 170.872488 170.625)
		(width 0.15)
		(layer "B.Cu")
		(net 294)
	)
	(segment
		(start 181.6 169.952512)
		(end 181.6 167.55)
		(width 0.15)
		(layer "B.Cu")
		(net 294)
	)
	(segment
		(start 180.927512 170.625)
		(end 181.6 169.952512)
		(width 0.15)
		(layer "B.Cu")
		(net 294)
	)
	(segment
		(start 173.431047 170.204368)
		(end 173.531047 170.204368)
		(width 0.15)
		(layer "B.Cu")
		(net 294)
	)
	(segment
		(start 173.931047 170.625)
		(end 174.031047 170.625)
		(width 0.15)
		(layer "B.Cu")
		(net 294)
	)
	(segment
		(start 164.525 149.8)
		(end 164.375 149.95)
		(width 0.15)
		(layer "B.Cu")
		(net 294)
	)
	(segment
		(start 173.231047 170.425)
		(end 173.231047 170.404368)
		(width 0.15)
		(layer "B.Cu")
		(net 294)
	)
	(segment
		(start 167.975 154.527512)
		(end 167.975 167.727512)
		(width 0.15)
		(layer "B.Cu")
		(net 294)
	)
	(segment
		(start 175.217905 170.625)
		(end 180.927512 170.625)
		(width 0.15)
		(layer "B.Cu")
		(net 294)
	)
	(arc
		(start 173.531047 170.204368)
		(mid 173.672468 170.262947)
		(end 173.731047 170.404368)
		(width 0.15)
		(layer "B.Cu")
		(net 294)
	)
	(arc
		(start 173.731047 170.425)
		(mid 173.789626 170.566421)
		(end 173.931047 170.625)
		(width 0.15)
		(layer "B.Cu")
		(net 294)
	)
	(arc
		(start 173.031047 170.625)
		(mid 173.172468 170.566421)
		(end 173.231047 170.425)
		(width 0.15)
		(layer "B.Cu")
		(net 294)
	)
	(arc
		(start 173.231047 170.404368)
		(mid 173.289626 170.262947)
		(end 173.431047 170.204368)
		(width 0.15)
		(layer "B.Cu")
		(net 294)
	)
	(segment
		(start 140.659194 111.843166)
		(end 140.659194 110.461814)
		(width 0.15)
		(layer "F.Cu")
		(net 295)
	)
	(segment
		(start 138.884194 110.236814)
		(end 139.084194 110.236814)
		(width 0.15)
		(layer "F.Cu")
		(net 295)
	)
	(segment
		(start 181.95 167.55)
		(end 182.1 167.4)
		(width 0.15)
		(layer "F.Cu")
		(net 295)
	)
	(segment
		(start 164.025 124.672488)
		(end 164.025 149.65)
		(width 0.15)
		(layer "F.Cu")
		(net 295)
	)
	(segment
		(start 134.895 111.515)
		(end 135.185 111.515)
		(width 0.15)
		(layer "F.Cu")
		(net 295)
	)
	(segment
		(start 135.3725 111.3275)
		(end 138.084194 111.3275)
		(width 0.15)
		(layer "F.Cu")
		(net 295)
	)
	(segment
		(start 138.659194 110.7525)
		(end 138.659194 110.461814)
		(width 0.15)
		(layer "F.Cu")
		(net 295)
	)
	(segment
		(start 150.680012 111.3275)
		(end 164.025 124.672488)
		(width 0.15)
		(layer "F.Cu")
		(net 295)
	)
	(segment
		(start 141.884194 111.3275)
		(end 150.680012 111.3275)
		(width 0.15)
		(layer "F.Cu")
		(net 295)
	)
	(segment
		(start 140.884194 110.236814)
		(end 141.084194 110.236814)
		(width 0.15)
		(layer "F.Cu")
		(net 295)
	)
	(segment
		(start 181.95 167.885)
		(end 181.95 167.55)
		(width 0.15)
		(layer "F.Cu")
		(net 295)
	)
	(segment
		(start 135.185 111.515)
		(end 135.3725 111.3275)
		(width 0.15)
		(layer "F.Cu")
		(net 295)
	)
	(segment
		(start 139.309194 110.461814)
		(end 139.309194 111.843166)
		(width 0.15)
		(layer "F.Cu")
		(net 295)
	)
	(segment
		(start 141.309194 110.461814)
		(end 141.309194 110.7525)
		(width 0.15)
		(layer "F.Cu")
		(net 295)
	)
	(segment
		(start 139.884194 112.418166)
		(end 140.084194 112.418166)
		(width 0.15)
		(layer "F.Cu")
		(net 295)
	)
	(segment
		(start 182.025 167.96)
		(end 181.95 167.885)
		(width 0.15)
		(layer "F.Cu")
		(net 295)
	)
	(segment
		(start 164.025 149.65)
		(end 163.875 149.8)
		(width 0.15)
		(layer "F.Cu")
		(net 295)
	)
	(segment
		(start 182.025 168.685)
		(end 182.025 167.96)
		(width 0.15)
		(layer "F.Cu")
		(net 295)
	)
	(via
		(at 182.1 167.4)
		(size 0.45)
		(drill 0.1)
		(layers "F.Cu" "B.Cu")
		(teardrops
			(best_length_ratio 0.4)
			(max_length 1)
			(best_width_ratio 0.9)
			(max_width 2)
			(curved_edges yes)
			(filter_ratio 0.9)
			(enabled yes)
			(allow_two_segments yes)
			(prefer_zone_connections yes)
		)
		(net 295)
	)
	(via
		(at 163.875 149.8)
		(size 0.45)
		(drill 0.1)
		(layers "F.Cu" "B.Cu")
		(teardrops
			(best_length_ratio 0.4)
			(max_length 1)
			(best_width_ratio 0.9)
			(max_width 2)
			(curved_edges yes)
			(filter_ratio 0.9)
			(enabled yes)
			(allow_two_segments yes)
			(prefer_zone_connections yes)
		)
		(net 295)
	)
	(arc
		(start 139.084194 110.236814)
		(mid 139.243293 110.302715)
		(end 139.309194 110.461814)
		(width 0.15)
		(layer "F.Cu")
		(net 295)
	)
	(arc
		(start 140.659194 110.461814)
		(mid 140.725095 110.302715)
		(end 140.884194 110.236814)
		(width 0.15)
		(layer "F.Cu")
		(net 295)
	)
	(arc
		(start 138.084194 111.3275)
		(mid 138.49078 111.159086)
		(end 138.659194 110.7525)
		(width 0.15)
		(layer "F.Cu")
		(net 295)
	)
	(arc
		(start 141.084194 110.236814)
		(mid 141.243293 110.302715)
		(end 141.309194 110.461814)
		(width 0.15)
		(layer "F.Cu")
		(net 295)
	)
	(arc
		(start 138.659194 110.461814)
		(mid 138.725095 110.302715)
		(end 138.884194 110.236814)
		(width 0.15)
		(layer "F.Cu")
		(net 295)
	)
	(arc
		(start 139.309194 111.843166)
		(mid 139.477608 112.249752)
		(end 139.884194 112.418166)
		(width 0.15)
		(layer "F.Cu")
		(net 295)
	)
	(arc
		(start 140.084194 112.418166)
		(mid 140.49078 112.249752)
		(end 140.659194 111.843166)
		(width 0.15)
		(layer "F.Cu")
		(net 295)
	)
	(arc
		(start 141.309194 110.7525)
		(mid 141.477608 111.159086)
		(end 141.884194 111.3275)
		(width 0.15)
		(layer "F.Cu")
		(net 295)
	)
	(segment
		(start 164.025 149.95)
		(end 164.025 151.072488)
		(width 0.15)
		(layer "B.Cu")
		(net 295)
	)
	(segment
		(start 181.95 170.097488)
		(end 181.95 167.55)
		(width 0.15)
		(layer "B.Cu")
		(net 295)
	)
	(segment
		(start 167.625 154.672488)
		(end 167.625 167.872488)
		(width 0.15)
		(layer "B.Cu")
		(net 295)
	)
	(segment
		(start 163.875 149.8)
		(end 164.025 149.95)
		(width 0.15)
		(layer "B.Cu")
		(net 295)
	)
	(segment
		(start 181.072488 170.975)
		(end 181.95 170.097488)
		(width 0.15)
		(layer "B.Cu")
		(net 295)
	)
	(segment
		(start 170.727512 170.975)
		(end 181.072488 170.975)
		(width 0.15)
		(layer "B.Cu")
		(net 295)
	)
	(segment
		(start 164.025 151.072488)
		(end 167.625 154.672488)
		(width 0.15)
		(layer "B.Cu")
		(net 295)
	)
	(segment
		(start 167.625 167.872488)
		(end 170.727512 170.975)
		(width 0.15)
		(layer "B.Cu")
		(net 295)
	)
	(segment
		(start 181.95 167.55)
		(end 182.1 167.4)
		(width 0.15)
		(layer "B.Cu")
		(net 295)
	)
	(segment
		(start 135.5 121.1)
		(end 137.2 122.8)
		(width 0.2)
		(layer "F.Cu")
		(net 296)
	)
	(segment
		(start 135.5 121.1)
		(end 135.5 119.4)
		(width 0.2)
		(layer "F.Cu")
		(net 296)
	)
	(segment
		(start 182.525 169.875)
		(end 182.5 169.9)
		(width 0.125)
		(layer "F.Cu")
		(net 296)
	)
	(segment
		(start 148.3 122.8)
		(end 137.2 122.8)
		(width 0.2)
		(layer "F.Cu")
		(net 296)
	)
	(segment
		(start 182.525 168.685)
		(end 182.525 169.875)
		(width 0.125)
		(layer "F.Cu")
		(net 296)
	)
	(via
		(at 148.3 122.8)
		(size 0.45)
		(drill 0.1)
		(layers "F.Cu" "B.Cu")
		(teardrops
			(best_length_ratio 0.4)
			(max_length 1)
			(best_width_ratio 0.9)
			(max_width 2)
			(curved_edges yes)
			(filter_ratio 0.9)
			(enabled yes)
			(allow_two_segments yes)
			(prefer_zone_connections yes)
		)
		(net 296)
	)
	(via
		(at 131.73 97.91)
		(size 0.45)
		(drill 0.1)
		(layers "F.Cu" "B.Cu")
		(remove_unused_layers yes)
		(keep_end_layers yes)
		(zone_layer_connections "In2.Cu")
		(teardrops
			(best_length_ratio 0.4)
			(max_length 1)
			(best_width_ratio 0.9)
			(max_width 2)
			(curved_edges yes)
			(filter_ratio 0.9)
			(enabled yes)
			(allow_two_segments yes)
			(prefer_zone_connections yes)
		)
		(net 296)
	)
	(via
		(at 182.5 169.9)
		(size 0.45)
		(drill 0.1)
		(layers "F.Cu" "B.Cu")
		(teardrops
			(best_length_ratio 0.4)
			(max_length 1)
			(best_width_ratio 0.9)
			(max_width 2)
			(curved_edges yes)
			(filter_ratio 0.9)
			(enabled yes)
			(allow_two_segments yes)
			(prefer_zone_connections yes)
		)
		(net 296)
	)
	(via
		(at 135.5 119.4)
		(size 0.45)
		(drill 0.1)
		(layers "F.Cu" "B.Cu")
		(teardrops
			(best_length_ratio 0.4)
			(max_length 1)
			(best_width_ratio 0.9)
			(max_width 2)
			(curved_edges yes)
			(filter_ratio 0.9)
			(enabled yes)
			(allow_two_segments yes)
			(prefer_zone_connections yes)
		)
		(net 296)
	)
	(segment
		(start 135.5 119.4)
		(end 135.5 114.3)
		(width 0.2)
		(layer "In2.Cu")
		(net 296)
	)
	(segment
		(start 135.5 114.3)
		(end 131.73 110.53)
		(width 0.2)
		(layer "In2.Cu")
		(net 296)
	)
	(segment
		(start 131.73 110.53)
		(end 131.73 97.91)
		(width 0.2)
		(layer "In2.Cu")
		(net 296)
	)
	(segment
		(start 175.5 164.8)
		(end 174.6 163.9)
		(width 0.2)
		(layer "In5.Cu")
		(net 296)
	)
	(segment
		(start 182.5 169.9)
		(end 181.3 168.7)
		(width 0.2)
		(layer "In5.Cu")
		(net 296)
	)
	(segment
		(start 169.2125 152.515914)
		(end 168.77 152.073414)
		(width 0.2)
		(layer "In5.Cu")
		(net 296)
	)
	(segment
		(start 168.77 152.073414)
		(end 168.77 138.17)
		(width 0.2)
		(layer "In5.Cu")
		(net 296)
	)
	(segment
		(start 181.3 168.7)
		(end 176.6 168.7)
		(width 0.2)
		(layer "In5.Cu")
		(net 296)
	)
	(segment
		(start 175.5 167.6)
		(end 175.5 164.8)
		(width 0.2)
		(layer "In5.Cu")
		(net 296)
	)
	(segment
		(start 153.7 128.2)
		(end 148.3 122.8)
		(width 0.2)
		(layer "In5.Cu")
		(net 296)
	)
	(segment
		(start 174.6 161.5)
		(end 169.2125 156.1125)
		(width 0.2)
		(layer "In5.Cu")
		(net 296)
	)
	(segment
		(start 176.6 168.7)
		(end 175.5 167.6)
		(width 0.2)
		(layer "In5.Cu")
		(net 296)
	)
	(segment
		(start 169.2125 156.1125)
		(end 169.2125 152.515914)
		(width 0.2)
		(layer "In5.Cu")
		(net 296)
	)
	(segment
		(start 168.77 138.17)
		(end 158.8 128.2)
		(width 0.2)
		(layer "In5.Cu")
		(net 296)
	)
	(segment
		(start 174.6 163.9)
		(end 174.6 161.5)
		(width 0.2)
		(layer "In5.Cu")
		(net 296)
	)
	(segment
		(start 158.8 128.2)
		(end 153.7 128.2)
		(width 0.2)
		(layer "In5.Cu")
		(net 296)
	)
	(segment
		(start 183.025 170.275)
		(end 182.5 170.8)
		(width 0.125)
		(layer "F.Cu")
		(net 297)
	)
	(segment
		(start 183.025 168.685)
		(end 183.025 170.275)
		(width 0.125)
		(layer "F.Cu")
		(net 297)
	)
	(via
		(at 182.5 170.8)
		(size 0.45)
		(drill 0.1)
		(layers "F.Cu" "B.Cu")
		(teardrops
			(best_length_ratio 0.4)
			(max_length 1)
			(best_width_ratio 0.9)
			(max_width 2)
			(curved_edges yes)
			(filter_ratio 0.9)
			(enabled yes)
			(allow_two_segments yes)
			(prefer_zone_connections yes)
		)
		(net 297)
	)
	(segment
		(start 184.525 168.685)
		(end 184.525 169.775)
		(width 0.125)
		(layer "F.Cu")
		(net 300)
	)
	(segment
		(start 184.525 169.775)
		(end 183.5 170.8)
		(width 0.125)
		(layer "F.Cu")
		(net 300)
	)
	(via
		(at 183.5 170.8)
		(size 0.45)
		(drill 0.1)
		(layers "F.Cu" "B.Cu")
		(teardrops
			(best_length_ratio 0.4)
			(max_length 1)
			(best_width_ratio 0.9)
			(max_width 2)
			(curved_edges yes)
			(filter_ratio 0.9)
			(enabled yes)
			(allow_two_segments yes)
			(prefer_zone_connections yes)
		)
		(net 300)
	)
	(segment
		(start 221.4 142.5)
		(end 221.8 142.1)
		(width 0.125)
		(layer "F.Cu")
		(net 303)
	)
	(segment
		(start 186.8 170.8)
		(end 185.1 170.8)
		(width 0.125)
		(layer "F.Cu")
		(net 303)
	)
	(segment
		(start 186.8 170.8)
		(end 187.525 170.075)
		(width 0.125)
		(layer "F.Cu")
		(net 303)
	)
	(segment
		(start 221.4 143.9)
		(end 221.4 142.5)
		(width 0.125)
		(layer "F.Cu")
		(net 303)
	)
	(segment
		(start 221.4 143.9)
		(end 222 144.5)
		(width 0.125)
		(layer "F.Cu")
		(net 303)
	)
	(segment
		(start 222 145.9)
		(end 222 144.5)
		(width 0.125)
		(layer "F.Cu")
		(net 303)
	)
	(segment
		(start 187.525 168.685)
		(end 187.525 170.075)
		(width 0.125)
		(layer "F.Cu")
		(net 303)
	)
	(via
		(at 222 145.9)
		(size 0.45)
		(drill 0.1)
		(layers "F.Cu" "B.Cu")
		(teardrops
			(best_length_ratio 0.4)
			(max_length 1)
			(best_width_ratio 0.9)
			(max_width 2)
			(curved_edges yes)
			(filter_ratio 0.9)
			(enabled yes)
			(allow_two_segments yes)
			(prefer_zone_connections yes)
		)
		(net 303)
	)
	(via
		(at 185.1 170.8)
		(size 0.45)
		(drill 0.1)
		(layers "F.Cu" "B.Cu")
		(teardrops
			(best_length_ratio 0.4)
			(max_length 1)
			(best_width_ratio 0.9)
			(max_width 2)
			(curved_edges yes)
			(filter_ratio 0.9)
			(enabled yes)
			(allow_two_segments yes)
			(prefer_zone_connections yes)
		)
		(net 303)
	)
	(via
		(at 221.8 142.1)
		(size 0.45)
		(drill 0.1)
		(layers "F.Cu" "B.Cu")
		(teardrops
			(best_length_ratio 0.4)
			(max_length 1)
			(best_width_ratio 0.9)
			(max_width 2)
			(curved_edges yes)
			(filter_ratio 0.9)
			(enabled yes)
			(allow_two_segments yes)
			(prefer_zone_connections yes)
		)
		(net 303)
	)
	(via
		(at 167.25 141.875)
		(size 0.45)
		(drill 0.1)
		(layers "F.Cu" "B.Cu")
		(teardrops
			(best_length_ratio 0.4)
			(max_length 1)
			(best_width_ratio 0.9)
			(max_width 2)
			(curved_edges yes)
			(filter_ratio 0.9)
			(enabled yes)
			(allow_two_segments yes)
			(prefer_zone_connections yes)
		)
		(net 303)
	)
	(via
		(at 158.55 154.4)
		(size 0.45)
		(drill 0.1)
		(layers "F.Cu" "B.Cu")
		(teardrops
			(best_length_ratio 0.4)
			(max_length 1)
			(best_width_ratio 0.9)
			(max_width 2)
			(curved_edges yes)
			(filter_ratio 0.9)
			(enabled yes)
			(allow_two_segments yes)
			(prefer_zone_connections yes)
		)
		(net 303)
	)
	(via
		(at 245.8 132.833999)
		(size 0.45)
		(drill 0.1)
		(layers "F.Cu" "B.Cu")
		(remove_unused_layers yes)
		(keep_end_layers yes)
		(zone_layer_connections "In2.Cu")
		(teardrops
			(best_length_ratio 0.4)
			(max_length 1)
			(best_width_ratio 0.9)
			(max_width 2)
			(curved_edges yes)
			(filter_ratio 0.9)
			(enabled yes)
			(allow_two_segments yes)
			(prefer_zone_connections yes)
		)
		(net 303)
	)
	(segment
		(start 222.395 141.505)
		(end 221.8 142.1)
		(width 0.125)
		(layer "In2.Cu")
		(net 303)
	)
	(segment
		(start 222 147.5)
		(end 222 145.9)
		(width 0.125)
		(layer "In2.Cu")
		(net 303)
	)
	(segment
		(start 166.4 167.2)
		(end 163.3 164.1)
		(width 0.125)
		(layer "In2.Cu")
		(net 303)
	)
	(segment
		(start 158.1 157.4)
		(end 163.3 162.6)
		(width 0.125)
		(layer "In2.Cu")
		(net 303)
	)
	(segment
		(start 196.725 147.425)
		(end 221.925 147.425)
		(width 0.125)
		(layer "In2.Cu")
		(net 303)
	)
	(segment
		(start 245.19 131.73)
		(end 245.8 132.34)
		(width 0.125)
		(layer "In2.Cu")
		(net 303)
	)
	(segment
		(start 221.07 134.58)
		(end 221.07 132.91)
		(width 0.125)
		(layer "In2.Cu")
		(net 303)
	)
	(segment
		(start 168.2 140.925)
		(end 188.65 140.925)
		(width 0.125)
		(layer "In2.Cu")
		(net 303)
	)
	(segment
		(start 182.4 169.3)
		(end 180.3525 171.3475)
		(width 0.125)
		(layer "In2.Cu")
		(net 303)
	)
	(segment
		(start 245.8 132.34)
		(end 245.8 132.833999)
		(width 0.125)
		(layer "In2.Cu")
		(net 303)
	)
	(segment
		(start 158.55 154.4)
		(end 158.1 154.85)
		(width 0.125)
		(layer "In2.Cu")
		(net 303)
	)
	(segment
		(start 183.6 169.3)
		(end 182.4 169.3)
		(width 0.125)
		(layer "In2.Cu")
		(net 303)
	)
	(segment
		(start 222.395 135.905)
		(end 222.395 141.505)
		(width 0.125)
		(layer "In2.Cu")
		(net 303)
	)
	(segment
		(start 185.1 170.8)
		(end 183.6 169.3)
		(width 0.125)
		(layer "In2.Cu")
		(net 303)
	)
	(segment
		(start 167.25 141.875)
		(end 168.2 140.925)
		(width 0.125)
		(layer "In2.Cu")
		(net 303)
	)
	(segment
		(start 158.1 154.85)
		(end 158.1 157.4)
		(width 0.125)
		(layer "In2.Cu")
		(net 303)
	)
	(segment
		(start 222.25 131.73)
		(end 245.19 131.73)
		(width 0.125)
		(layer "In2.Cu")
		(net 303)
	)
	(segment
		(start 221.07 132.91)
		(end 222.25 131.73)
		(width 0.125)
		(layer "In2.Cu")
		(net 303)
	)
	(segment
		(start 188.65 140.925)
		(end 189.525 141.8)
		(width 0.125)
		(layer "In2.Cu")
		(net 303)
	)
	(segment
		(start 222.395 135.905)
		(end 221.07 134.58)
		(width 0.125)
		(layer "In2.Cu")
		(net 303)
	)
	(segment
		(start 180.3525 171.3475)
		(end 168.7475 171.3475)
		(width 0.125)
		(layer "In2.Cu")
		(net 303)
	)
	(segment
		(start 163.3 164.1)
		(end 163.3 162.6)
		(width 0.125)
		(layer "In2.Cu")
		(net 303)
	)
	(segment
		(start 168.7475 171.3475)
		(end 166.4 169)
		(width 0.125)
		(layer "In2.Cu")
		(net 303)
	)
	(segment
		(start 191.1 141.8)
		(end 196.725 147.425)
		(width 0.125)
		(layer "In2.Cu")
		(net 303)
	)
	(segment
		(start 221.925 147.425)
		(end 222 147.5)
		(width 0.125)
		(layer "In2.Cu")
		(net 303)
	)
	(segment
		(start 166.4 169)
		(end 166.4 167.2)
		(width 0.125)
		(layer "In2.Cu")
		(net 303)
	)
	(segment
		(start 189.525 141.8)
		(end 191.1 141.8)
		(width 0.125)
		(layer "In2.Cu")
		(net 303)
	)
	(segment
		(start 167.25 141.875)
		(end 163.625 141.875)
		(width 0.125)
		(layer "In5.Cu")
		(net 303)
	)
	(segment
		(start 158.425 147.075)
		(end 158.425 149.225)
		(width 0.125)
		(layer "In5.Cu")
		(net 303)
	)
	(segment
		(start 159 149.8)
		(end 159 153.95)
		(width 0.125)
		(layer "In5.Cu")
		(net 303)
	)
	(segment
		(start 163.625 141.875)
		(end 158.425 147.075)
		(width 0.125)
		(layer "In5.Cu")
		(net 303)
	)
	(segment
		(start 159 153.95)
		(end 158.55 154.4)
		(width 0.125)
		(layer "In5.Cu")
		(net 303)
	)
	(segment
		(start 158.425 149.225)
		(end 159 149.8)
		(width 0.125)
		(layer "In5.Cu")
		(net 303)
	)
	(segment
		(start 189.025 169.925)
		(end 189 169.95)
		(width 0.125)
		(layer "F.Cu")
		(net 304)
	)
	(segment
		(start 189.025 168.685)
		(end 189.025 169.925)
		(width 0.125)
		(layer "F.Cu")
		(net 304)
	)
	(via
		(at 189 169.95)
		(size 0.45)
		(drill 0.1)
		(layers "F.Cu" "B.Cu")
		(teardrops
			(best_length_ratio 0.4)
			(max_length 1)
			(best_width_ratio 0.9)
			(max_width 2)
			(curved_edges yes)
			(filter_ratio 0.9)
			(enabled yes)
			(allow_two_segments yes)
			(prefer_zone_connections yes)
		)
		(net 304)
	)
	(segment
		(start 188.6 168.7)
		(end 189 169.1)
		(width 0.125)
		(layer "B.Cu")
		(net 304)
	)
	(segment
		(start 189 169.1)
		(end 189 169.95)
		(width 0.125)
		(layer "B.Cu")
		(net 304)
	)
	(segment
		(start 186.7 168.7)
		(end 188.6 168.7)
		(width 0.125)
		(layer "B.Cu")
		(net 304)
	)
	(segment
		(start 212.45 78.11)
		(end 216.65 82.31)
		(width 0.2)
		(layer "F.Cu")
		(net 310)
	)
	(segment
		(start 225.1 146.4)
		(end 219.5 146.4)
		(width 0.125)
		(layer "F.Cu")
		(net 310)
	)
	(segment
		(start 217.8 144.7)
		(end 219.5 146.4)
		(width 0.125)
		(layer "F.Cu")
		(net 310)
	)
	(segment
		(start 209.419 78.11)
		(end 212.45 78.11)
		(width 0.2)
		(layer "F.Cu")
		(net 310)
	)
	(segment
		(start 217.8 144.7)
		(end 217.8 142.85)
		(width 0.125)
		(layer "F.Cu")
		(net 310)
	)
	(segment
		(start 192.05 167.05)
		(end 192.525 167.525)
		(width 0.125)
		(layer "F.Cu")
		(net 310)
	)
	(segment
		(start 192.525 168.685)
		(end 192.525 167.525)
		(width 0.125)
		(layer "F.Cu")
		(net 310)
	)
	(segment
		(start 192.05 167.05)
		(end 191.5 167.05)
		(width 0.125)
		(layer "F.Cu")
		(net 310)
	)
	(via
		(at 216.65 82.31)
		(size 0.45)
		(drill 0.1)
		(layers "F.Cu" "B.Cu")
		(remove_unused_layers yes)
		(keep_end_layers yes)
		(zone_layer_connections "In2.Cu")
		(teardrops
			(best_length_ratio 0.4)
			(max_length 1)
			(best_width_ratio 0.9)
			(max_width 2)
			(curved_edges yes)
			(filter_ratio 0.9)
			(enabled yes)
			(allow_two_segments yes)
			(prefer_zone_connections yes)
		)
		(net 310)
	)
	(via
		(at 188.95 158.45)
		(size 0.45)
		(drill 0.1)
		(layers "F.Cu" "B.Cu")
		(teardrops
			(best_length_ratio 0.4)
			(max_length 1)
			(best_width_ratio 0.9)
			(max_width 2)
			(curved_edges yes)
			(filter_ratio 0.9)
			(enabled yes)
			(allow_two_segments yes)
			(prefer_zone_connections yes)
		)
		(net 310)
	)
	(via
		(at 225.1 146.4)
		(size 0.45)
		(drill 0.1)
		(layers "F.Cu" "B.Cu")
		(teardrops
			(best_length_ratio 0.4)
			(max_length 1)
			(best_width_ratio 0.9)
			(max_width 2)
			(curved_edges yes)
			(filter_ratio 0.9)
			(enabled yes)
			(allow_two_segments yes)
			(prefer_zone_connections yes)
		)
		(net 310)
	)
	(via
		(at 217.8 142.85)
		(size 0.45)
		(drill 0.1)
		(layers "F.Cu" "B.Cu")
		(teardrops
			(best_length_ratio 0.4)
			(max_length 1)
			(best_width_ratio 0.9)
			(max_width 2)
			(curved_edges yes)
			(filter_ratio 0.9)
			(enabled yes)
			(allow_two_segments yes)
			(prefer_zone_connections yes)
		)
		(net 310)
	)
	(via
		(at 191.5 167.05)
		(size 0.45)
		(drill 0.1)
		(layers "F.Cu" "B.Cu")
		(teardrops
			(best_length_ratio 0.4)
			(max_length 1)
			(best_width_ratio 0.9)
			(max_width 2)
			(curved_edges yes)
			(filter_ratio 0.9)
			(enabled yes)
			(allow_two_segments yes)
			(prefer_zone_connections yes)
		)
		(net 310)
	)
	(segment
		(start 191.15 168.45)
		(end 191.5 168.1)
		(width 0.125)
		(layer "B.Cu")
		(net 310)
	)
	(segment
		(start 188.05 164.95)
		(end 189.5 166.4)
		(width 0.125)
		(layer "B.Cu")
		(net 310)
	)
	(segment
		(start 191.5 168.1)
		(end 191.5 167.05)
		(width 0.125)
		(layer "B.Cu")
		(net 310)
	)
	(segment
		(start 188.05 163.8)
		(end 188.05 164.95)
		(width 0.125)
		(layer "B.Cu")
		(net 310)
	)
	(segment
		(start 190.55 168.45)
		(end 191.15 168.45)
		(width 0.125)
		(layer "B.Cu")
		(net 310)
	)
	(segment
		(start 189.5 167.4)
		(end 190.55 168.45)
		(width 0.125)
		(layer "B.Cu")
		(net 310)
	)
	(segment
		(start 189.5 166.4)
		(end 189.5 167.4)
		(width 0.125)
		(layer "B.Cu")
		(net 310)
	)
	(segment
		(start 188.95 158.45)
		(end 189.8 159.3)
		(width 0.125)
		(layer "B.Cu")
		(net 310)
	)
	(segment
		(start 189.8 162.05)
		(end 188.05 163.8)
		(width 0.125)
		(layer "B.Cu")
		(net 310)
	)
	(segment
		(start 189.8 159.3)
		(end 189.8 162.05)
		(width 0.125)
		(layer "B.Cu")
		(net 310)
	)
	(segment
		(start 212.245 121.745)
		(end 214.705 124.205)
		(width 0.125)
		(layer "In2.Cu")
		(net 310)
	)
	(segment
		(start 215.4 156.45)
		(end 220.15 151.7)
		(width 0.125)
		(layer "In2.Cu")
		(net 310)
	)
	(segment
		(start 219.2 141.45)
		(end 219.2 135.71)
		(width 0.125)
		(layer "In2.Cu")
		(net 310)
	)
	(segment
		(start 215.395 124.205)
		(end 216.5 125.31)
		(width 0.125)
		(layer "In2.Cu")
		(net 310)
	)
	(segment
		(start 191.35 156.45)
		(end 215.4 156.45)
		(width 0.125)
		(layer "In2.Cu")
		(net 310)
	)
	(segment
		(start 206.55 115.36)
		(end 212.245 121.055)
		(width 0.125)
		(layer "In2.Cu")
		(net 310)
	)
	(segment
		(start 189.35 158.45)
		(end 191.35 156.45)
		(width 0.125)
		(layer "In2.Cu")
		(net 310)
	)
	(segment
		(start 212.245 121.055)
		(end 212.245 121.745)
		(width 0.125)
		(layer "In2.Cu")
		(net 310)
	)
	(segment
		(start 220.15 151.7)
		(end 221.2 151.7)
		(width 0.125)
		(layer "In2.Cu")
		(net 310)
	)
	(segment
		(start 206.55 91.435)
		(end 206.55 115.36)
		(width 0.125)
		(layer "In2.Cu")
		(net 310)
	)
	(segment
		(start 216.5 125.31)
		(end 216.5 133.01)
		(width 0.125)
		(layer "In2.Cu")
		(net 310)
	)
	(segment
		(start 215.675 82.31)
		(end 206.55 91.435)
		(width 0.125)
		(layer "In2.Cu")
		(net 310)
	)
	(segment
		(start 216.65 82.31)
		(end 215.675 82.31)
		(width 0.125)
		(layer "In2.Cu")
		(net 310)
	)
	(segment
		(start 217.8 142.85)
		(end 219.2 141.45)
		(width 0.125)
		(layer "In2.Cu")
		(net 310)
	)
	(segment
		(start 216.5 133.01)
		(end 219.2 135.71)
		(width 0.125)
		(layer "In2.Cu")
		(net 310)
	)
	(segment
		(start 214.705 124.205)
		(end 215.395 124.205)
		(width 0.125)
		(layer "In2.Cu")
		(net 310)
	)
	(segment
		(start 225.1 147.8)
		(end 225.1 146.4)
		(width 0.125)
		(layer "In2.Cu")
		(net 310)
	)
	(segment
		(start 188.95 158.45)
		(end 189.35 158.45)
		(width 0.125)
		(layer "In2.Cu")
		(net 310)
	)
	(segment
		(start 221.2 151.7)
		(end 225.1 147.8)
		(width 0.125)
		(layer "In2.Cu")
		(net 310)
	)
	(segment
		(start 193.025 170.125)
		(end 193 170.15)
		(width 0.125)
		(layer "F.Cu")
		(net 311)
	)
	(segment
		(start 193.025 168.685)
		(end 193.025 170.125)
		(width 0.125)
		(layer "F.Cu")
		(net 311)
	)
	(via
		(at 193 170.15)
		(size 0.45)
		(drill 0.1)
		(layers "F.Cu" "B.Cu")
		(teardrops
			(best_length_ratio 0.4)
			(max_length 1)
			(best_width_ratio 0.9)
			(max_width 2)
			(curved_edges yes)
			(filter_ratio 0.9)
			(enabled yes)
			(allow_two_segments yes)
			(prefer_zone_connections yes)
		)
		(net 311)
	)
	(segment
		(start 187.65 169.9)
		(end 188.35 170.6)
		(width 0.125)
		(layer "B.Cu")
		(net 311)
	)
	(segment
		(start 188.35 170.6)
		(end 192.55 170.6)
		(width 0.125)
		(layer "B.Cu")
		(net 311)
	)
	(segment
		(start 192.55 170.6)
		(end 193 170.15)
		(width 0.125)
		(layer "B.Cu")
		(net 311)
	)
	(segment
		(start 186.7 169.9)
		(end 187.65 169.9)
		(width 0.125)
		(layer "B.Cu")
		(net 311)
	)
	(segment
		(start 196.525 167.96)
		(end 196.585 167.9)
		(width 0.185)
		(layer "F.Cu")
		(net 312)
	)
	(segment
		(start 196.525 168.685)
		(end 196.525 167.96)
		(width 0.185)
		(layer "F.Cu")
		(net 312)
	)
	(segment
		(start 134.590659 116.278042)
		(end 134.778042 116.278042)
		(width 0.185)
		(layer "F.Cu")
		(net 312)
	)
	(segment
		(start 153.023316 124.177)
		(end 153.527 123.673316)
		(width 0.185)
		(layer "F.Cu")
		(net 312)
	)
	(segment
		(start 151.958298 124.177)
		(end 153.023316 124.177)
		(width 0.185)
		(layer "F.Cu")
		(net 312)
	)
	(segment
		(start 196.585 167.9)
		(end 196.585 167.1325)
		(width 0.185)
		(layer "F.Cu")
		(net 312)
	)
	(segment
		(start 153.527 123.15)
		(end 153.677 123)
		(width 0.185)
		(layer "F.Cu")
		(net 312)
	)
	(segment
		(start 196.585 167.1325)
		(end 196.4525 167)
		(width 0.185)
		(layer "F.Cu")
		(net 312)
	)
	(segment
		(start 130.6 118.85)
		(end 130.9095 118.5405)
		(width 0.185)
		(layer "F.Cu")
		(net 312)
	)
	(segment
		(start 130.9095 118.5405)
		(end 132.328201 118.5405)
		(width 0.185)
		(layer "F.Cu")
		(net 312)
	)
	(segment
		(start 147.459341 115.678042)
		(end 149.46 117.678701)
		(width 0.185)
		(layer "F.Cu")
		(net 312)
	)
	(segment
		(start 149.46 117.678701)
		(end 149.46 121.678702)
		(width 0.185)
		(layer "F.Cu")
		(net 312)
	)
	(segment
		(start 149.46 121.678702)
		(end 151.958298 124.177)
		(width 0.185)
		(layer "F.Cu")
		(net 312)
	)
	(segment
		(start 147.271958 115.678042)
		(end 147.459341 115.678042)
		(width 0.185)
		(layer "F.Cu")
		(net 312)
	)
	(segment
		(start 153.527 123.673316)
		(end 153.527 123.15)
		(width 0.185)
		(layer "F.Cu")
		(net 312)
	)
	(segment
		(start 132.328201 118.5405)
		(end 134.590659 116.278042)
		(width 0.185)
		(layer "F.Cu")
		(net 312)
	)
	(via
		(at 134.778042 116.278042)
		(size 0.45)
		(drill 0.1)
		(layers "F.Cu" "B.Cu")
		(teardrops
			(best_length_ratio 0.4)
			(max_length 1)
			(best_width_ratio 0.9)
			(max_width 2)
			(curved_edges yes)
			(filter_ratio 0.9)
			(enabled yes)
			(allow_two_segments yes)
			(prefer_zone_connections yes)
		)
		(net 312)
	)
	(via
		(at 196.4525 167)
		(size 0.45)
		(drill 0.1)
		(layers "F.Cu" "B.Cu")
		(teardrops
			(best_length_ratio 0.4)
			(max_length 1)
			(best_width_ratio 0.9)
			(max_width 2)
			(curved_edges yes)
			(filter_ratio 0.9)
			(enabled yes)
			(allow_two_segments yes)
			(prefer_zone_connections yes)
		)
		(net 312)
	)
	(via
		(at 147.271958 115.678042)
		(size 0.45)
		(drill 0.1)
		(layers "F.Cu" "B.Cu")
		(teardrops
			(best_length_ratio 0.4)
			(max_length 1)
			(best_width_ratio 0.9)
			(max_width 2)
			(curved_edges yes)
			(filter_ratio 0.9)
			(enabled yes)
			(allow_two_segments yes)
			(prefer_zone_connections yes)
		)
		(net 312)
	)
	(via
		(at 153.677 123)
		(size 0.45)
		(drill 0.1)
		(layers "F.Cu" "B.Cu")
		(teardrops
			(best_length_ratio 0.4)
			(max_length 1)
			(best_width_ratio 0.9)
			(max_width 2)
			(curved_edges yes)
			(filter_ratio 0.9)
			(enabled yes)
			(allow_two_segments yes)
			(prefer_zone_connections yes)
		)
		(net 312)
	)
	(segment
		(start 147.071299 115.29)
		(end 147.271958 115.490659)
		(width 0.185)
		(layer "B.Cu")
		(net 312)
	)
	(segment
		(start 147.271958 115.490659)
		(end 147.271958 115.678042)
		(width 0.185)
		(layer "B.Cu")
		(net 312)
	)
	(segment
		(start 135.578701 115.29)
		(end 147.071299 115.29)
		(width 0.185)
		(layer "B.Cu")
		(net 312)
	)
	(segment
		(start 134.778042 116.090659)
		(end 135.578701 115.29)
		(width 0.185)
		(layer "B.Cu")
		(net 312)
	)
	(segment
		(start 134.778042 116.278042)
		(end 134.778042 116.090659)
		(width 0.185)
		(layer "B.Cu")
		(net 312)
	)
	(segment
		(start 170.0815 136.32482)
		(end 170.0815 154.88482)
		(width 0.159)
		(layer "In5.Cu")
		(net 312)
	)
	(segment
		(start 183.3815 165.77482)
		(end 183.3815 167.37482)
		(width 0.159)
		(layer "In5.Cu")
		(net 312)
	)
	(segment
		(start 153.677 123)
		(end 153.5315 123.1455)
		(width 0.159)
		(layer "In5.Cu")
		(net 312)
	)
	(segment
		(start 186.47518 170.4685)
		(end 191.42482 170.4685)
		(width 0.159)
		(layer "In5.Cu")
		(net 312)
	)
	(segment
		(start 155.753112 126.2685)
		(end 160.02518 126.2685)
		(width 0.159)
		(layer "In5.Cu")
		(net 312)
	)
	(segment
		(start 181.47518 165.1185)
		(end 182.72518 165.1185)
		(width 0.159)
		(layer "In5.Cu")
		(net 312)
	)
	(segment
		(start 160.02518 126.2685)
		(end 170.0815 136.32482)
		(width 0.159)
		(layer "In5.Cu")
		(net 312)
	)
	(segment
		(start 182.72518 165.1185)
		(end 183.3815 165.77482)
		(width 0.159)
		(layer "In5.Cu")
		(net 312)
	)
	(segment
		(start 153.5315 124.47482)
		(end 153.841443 124.784763)
		(width 0.159)
		(layer "In5.Cu")
		(net 312)
	)
	(segment
		(start 183.3815 167.37482)
		(end 186.47518 170.4685)
		(width 0.159)
		(layer "In5.Cu")
		(net 312)
	)
	(segment
		(start 154.435122 124.700201)
		(end 154.498761 124.76384)
		(width 0.159)
		(layer "In5.Cu")
		(net 312)
	)
	(segment
		(start 196.5935 167.141)
		(end 196.4525 167)
		(width 0.159)
		(layer "In5.Cu")
		(net 312)
	)
	(segment
		(start 154.49876 125.018398)
		(end 154.414198 125.102961)
		(width 0.159)
		(layer "In5.Cu")
		(net 312)
	)
	(segment
		(start 193.12482 168.7685)
		(end 195.556434 168.7685)
		(width 0.159)
		(layer "In5.Cu")
		(net 312)
	)
	(segment
		(start 176.17518 159.8185)
		(end 181.47518 165.1185)
		(width 0.159)
		(layer "In5.Cu")
		(net 312)
	)
	(segment
		(start 191.42482 170.4685)
		(end 193.12482 168.7685)
		(width 0.159)
		(layer "In5.Cu")
		(net 312)
	)
	(segment
		(start 153.5315 123.1455)
		(end 153.5315 124.47482)
		(width 0.159)
		(layer "In5.Cu")
		(net 312)
	)
	(segment
		(start 154.096001 124.784763)
		(end 154.180564 124.700201)
		(width 0.159)
		(layer "In5.Cu")
		(net 312)
	)
	(segment
		(start 175.01518 159.8185)
		(end 176.17518 159.8185)
		(width 0.159)
		(layer "In5.Cu")
		(net 312)
	)
	(segment
		(start 170.0815 154.88482)
		(end 175.01518 159.8185)
		(width 0.159)
		(layer "In5.Cu")
		(net 312)
	)
	(segment
		(start 195.556434 168.7685)
		(end 196.5935 167.731434)
		(width 0.159)
		(layer "In5.Cu")
		(net 312)
	)
	(segment
		(start 154.414198 125.357519)
		(end 154.477839 125.421159)
		(width 0.159)
		(layer "In5.Cu")
		(net 312)
	)
	(segment
		(start 154.477839 125.421159)
		(end 155.32518 126.2685)
		(width 0.159)
		(layer "In5.Cu")
		(net 312)
	)
	(segment
		(start 196.5935 167.731434)
		(end 196.5935 167.141)
		(width 0.159)
		(layer "In5.Cu")
		(net 312)
	)
	(segment
		(start 155.32518 126.2685)
		(end 155.753112 126.2685)
		(width 0.159)
		(layer "In5.Cu")
		(net 312)
	)
	(arc
		(start 154.180564 124.700201)
		(mid 154.307843 124.64748)
		(end 154.435122 124.700201)
		(width 0.159)
		(layer "In5.Cu")
		(net 312)
	)
	(arc
		(start 154.414198 125.102961)
		(mid 154.361477 125.23024)
		(end 154.414198 125.357519)
		(width 0.159)
		(layer "In5.Cu")
		(net 312)
	)
	(arc
		(start 153.841443 124.784763)
		(mid 153.968722 124.837484)
		(end 154.096001 124.784763)
		(width 0.159)
		(layer "In5.Cu")
		(net 312)
	)
	(arc
		(start 154.498761 124.76384)
		(mid 154.551481 124.89112)
		(end 154.49876 125.018398)
		(width 0.159)
		(layer "In5.Cu")
		(net 312)
	)
	(segment
		(start 132.170799 118.1605)
		(end 134.321958 116.009341)
		(width 0.185)
		(layer "F.Cu")
		(net 313)
	)
	(segment
		(start 130.9095 118.1605)
		(end 132.170799 118.1605)
		(width 0.185)
		(layer "F.Cu")
		(net 313)
	)
	(segment
		(start 134.321958 116.009341)
		(end 134.321958 115.821958)
		(width 0.185)
		(layer "F.Cu")
		(net 313)
	)
	(segment
		(start 153.173 123.526684)
		(end 152.876684 123.823)
		(width 0.185)
		(layer "F.Cu")
		(net 313)
	)
	(segment
		(start 197.025 168.685)
		(end 197.025 167.96)
		(width 0.185)
		(layer "F.Cu")
		(net 313)
	)
	(segment
		(start 152.876684 123.823)
		(end 152.15 123.823)
		(width 0.185)
		(layer "F.Cu")
		(net 313)
	)
	(segment
		(start 147.728042 115.409341)
		(end 147.728042 115.221958)
		(width 0.185)
		(layer "F.Cu")
		(net 313)
	)
	(segment
		(start 196.965 167.1325)
		(end 197.0975 167)
		(width 0.185)
		(layer "F.Cu")
		(net 313)
	)
	(segment
		(start 196.965 167.9)
		(end 196.965 167.1325)
		(width 0.185)
		(layer "F.Cu")
		(net 313)
	)
	(segment
		(start 152.141702 123.823)
		(end 149.84 121.521298)
		(width 0.185)
		(layer "F.Cu")
		(net 313)
	)
	(segment
		(start 130.599 117.85)
		(end 130.9095 118.1605)
		(width 0.185)
		(layer "F.Cu")
		(net 313)
	)
	(segment
		(start 152.15 123.823)
		(end 152.141702 123.823)
		(width 0.185)
		(layer "F.Cu")
		(net 313)
	)
	(segment
		(start 153.023 123)
		(end 153.173 123.15)
		(width 0.185)
		(layer "F.Cu")
		(net 313)
	)
	(segment
		(start 149.84 121.521298)
		(end 149.84 117.521299)
		(width 0.185)
		(layer "F.Cu")
		(net 313)
	)
	(segment
		(start 153.173 123.15)
		(end 153.173 123.526684)
		(width 0.185)
		(layer "F.Cu")
		(net 313)
	)
	(segment
		(start 149.84 117.521299)
		(end 147.728042 115.409341)
		(width 0.185)
		(layer "F.Cu")
		(net 313)
	)
	(segment
		(start 197.025 167.96)
		(end 196.965 167.9)
		(width 0.185)
		(layer "F.Cu")
		(net 313)
	)
	(via
		(at 134.321958 115.821958)
		(size 0.45)
		(drill 0.1)
		(layers "F.Cu" "B.Cu")
		(teardrops
			(best_length_ratio 0.4)
			(max_length 1)
			(best_width_ratio 0.9)
			(max_width 2)
			(curved_edges yes)
			(filter_ratio 0.9)
			(enabled yes)
			(allow_two_segments yes)
			(prefer_zone_connections yes)
		)
		(net 313)
	)
	(via
		(at 153.023 123)
		(size 0.45)
		(drill 0.1)
		(layers "F.Cu" "B.Cu")
		(teardrops
			(best_length_ratio 0.4)
			(max_length 1)
			(best_width_ratio 0.9)
			(max_width 2)
			(curved_edges yes)
			(filter_ratio 0.9)
			(enabled yes)
			(allow_two_segments yes)
			(prefer_zone_connections yes)
		)
		(net 313)
	)
	(via
		(at 197.0975 167)
		(size 0.45)
		(drill 0.1)
		(layers "F.Cu" "B.Cu")
		(teardrops
			(best_length_ratio 0.4)
			(max_length 1)
			(best_width_ratio 0.9)
			(max_width 2)
			(curved_edges yes)
			(filter_ratio 0.9)
			(enabled yes)
			(allow_two_segments yes)
			(prefer_zone_connections yes)
		)
		(net 313)
	)
	(via
		(at 147.728042 115.221958)
		(size 0.45)
		(drill 0.1)
		(layers "F.Cu" "B.Cu")
		(teardrops
			(best_length_ratio 0.4)
			(max_length 1)
			(best_width_ratio 0.9)
			(max_width 2)
			(curved_edges yes)
			(filter_ratio 0.9)
			(enabled yes)
			(allow_two_segments yes)
			(prefer_zone_connections yes)
		)
		(net 313)
	)
	(segment
		(start 147.540659 115.221958)
		(end 147.728042 115.221958)
		(width 0.185)
		(layer "B.Cu")
		(net 313)
	)
	(segment
		(start 147.228701 114.91)
		(end 147.540659 115.221958)
		(width 0.185)
		(layer "B.Cu")
		(net 313)
	)
	(segment
		(start 135.421299 114.91)
		(end 147.228701 114.91)
		(width 0.185)
		(layer "B.Cu")
		(net 313)
	)
	(segment
		(start 134.509341 115.821958)
		(end 135.421299 114.91)
		(width 0.185)
		(layer "B.Cu")
		(net 313)
	)
	(segment
		(start 134.321958 115.821958)
		(end 134.509341 115.821958)
		(width 0.185)
		(layer "B.Cu")
		(net 313)
	)
	(segment
		(start 153.1685 124.62518)
		(end 155.17482 126.6315)
		(width 0.159)
		(layer "In5.Cu")
		(net 313)
	)
	(segment
		(start 155.17482 126.6315)
		(end 159.87482 126.6315)
		(width 0.159)
		(layer "In5.Cu")
		(net 313)
	)
	(segment
		(start 169.7185 136.47518)
		(end 169.7185 155.03518)
		(width 0.159)
		(layer "In5.Cu")
		(net 313)
	)
	(segment
		(start 169.7185 155.03518)
		(end 174.86482 160.1815)
		(width 0.159)
		(layer "In5.Cu")
		(net 313)
	)
	(segment
		(start 195.743566 169.1315)
		(end 196.9565 167.918566)
		(width 0.159)
		(layer "In5.Cu")
		(net 313)
	)
	(segment
		(start 193.27518 169.1315)
		(end 195.743566 169.1315)
		(width 0.159)
		(layer "In5.Cu")
		(net 313)
	)
	(segment
		(start 196.9565 167.141)
		(end 197.0975 167)
		(width 0.159)
		(layer "In5.Cu")
		(net 313)
	)
	(segment
		(start 183.0185 165.92518)
		(end 183.0185 167.52518)
		(width 0.159)
		(layer "In5.Cu")
		(net 313)
	)
	(segment
		(start 183.0185 167.52518)
		(end 186.32482 170.8315)
		(width 0.159)
		(layer "In5.Cu")
		(net 313)
	)
	(segment
		(start 191.57518 170.8315)
		(end 193.27518 169.1315)
		(width 0.159)
		(layer "In5.Cu")
		(net 313)
	)
	(segment
		(start 153.023 123)
		(end 153.1685 123.1455)
		(width 0.159)
		(layer "In5.Cu")
		(net 313)
	)
	(segment
		(start 153.1685 123.1455)
		(end 153.1685 124.62518)
		(width 0.159)
		(layer "In5.Cu")
		(net 313)
	)
	(segment
		(start 186.32482 170.8315)
		(end 191.57518 170.8315)
		(width 0.159)
		(layer "In5.Cu")
		(net 313)
	)
	(segment
		(start 182.57482 165.4815)
		(end 183.0185 165.92518)
		(width 0.159)
		(layer "In5.Cu")
		(net 313)
	)
	(segment
		(start 176.02482 160.1815)
		(end 181.32482 165.4815)
		(width 0.159)
		(layer "In5.Cu")
		(net 313)
	)
	(segment
		(start 196.9565 167.918566)
		(end 196.9565 167.141)
		(width 0.159)
		(layer "In5.Cu")
		(net 313)
	)
	(segment
		(start 159.87482 126.6315)
		(end 169.7185 136.47518)
		(width 0.159)
		(layer "In5.Cu")
		(net 313)
	)
	(segment
		(start 181.32482 165.4815)
		(end 182.57482 165.4815)
		(width 0.159)
		(layer "In5.Cu")
		(net 313)
	)
	(segment
		(start 174.86482 160.1815)
		(end 176.02482 160.1815)
		(width 0.159)
		(layer "In5.Cu")
		(net 313)
	)
	(segment
		(start 157.8 125)
		(end 137.4 125)
		(width 0.125)
		(layer "F.Cu")
		(net 314)
	)
	(segment
		(start 160.6 127.8)
		(end 157.8 125)
		(width 0.125)
		(layer "F.Cu")
		(net 314)
	)
	(segment
		(start 126.6 93)
		(end 122.57 93)
		(width 0.125)
		(layer "F.Cu")
		(net 314)
	)
	(segment
		(start 197.525 168.685)
		(end 197.525 167.475)
		(width 0.2)
		(layer "F.Cu")
		(net 314)
	)
	(segment
		(start 163.4 152)
		(end 160.6 149.2)
		(width 0.125)
		(layer "F.Cu")
		(net 314)
	)
	(segment
		(start 122.57 93)
		(end 122.53 92.96)
		(width 0.125)
		(layer "F.Cu")
		(net 314)
	)
	(segment
		(start 137.4 125)
		(end 135.4 123)
		(width 0.125)
		(layer "F.Cu")
		(net 314)
	)
	(segment
		(start 167.6 154)
		(end 165.6 152)
		(width 0.125)
		(layer "F.Cu")
		(net 314)
	)
	(segment
		(start 167.6 157.25)
		(end 167.6 154)
		(width 0.125)
		(layer "F.Cu")
		(net 314)
	)
	(segment
		(start 160.6 149.2)
		(end 160.6 127.8)
		(width 0.125)
		(layer "F.Cu")
		(net 314)
	)
	(segment
		(start 165.6 152)
		(end 163.4 152)
		(width 0.125)
		(layer "F.Cu")
		(net 314)
	)
	(segment
		(start 166 158.85)
		(end 167.6 157.25)
		(width 0.125)
		(layer "F.Cu")
		(net 314)
	)
	(segment
		(start 197.525 167.475)
		(end 197.6 167.4)
		(width 0.2)
		(layer "F.Cu")
		(net 314)
	)
	(via
		(at 166 158.85)
		(size 0.45)
		(drill 0.1)
		(layers "F.Cu" "B.Cu")
		(teardrops
			(best_length_ratio 0.4)
			(max_length 1)
			(best_width_ratio 0.9)
			(max_width 2)
			(curved_edges yes)
			(filter_ratio 0.9)
			(enabled yes)
			(allow_two_segments yes)
			(prefer_zone_connections yes)
		)
		(net 314)
	)
	(via
		(at 126.6 93)
		(size 0.45)
		(drill 0.1)
		(layers "F.Cu" "B.Cu")
		(teardrops
			(best_length_ratio 0.4)
			(max_length 1)
			(best_width_ratio 0.9)
			(max_width 2)
			(curved_edges yes)
			(filter_ratio 0.9)
			(enabled yes)
			(allow_two_segments yes)
			(prefer_zone_connections yes)
		)
		(net 314)
	)
	(via
		(at 122.53 92.96)
		(size 0.45)
		(drill 0.1)
		(layers "F.Cu" "B.Cu")
		(remove_unused_layers yes)
		(keep_end_layers yes)
		(zone_layer_connections)
		(teardrops
			(best_length_ratio 0.4)
			(max_length 1)
			(best_width_ratio 0.9)
			(max_width 2)
			(curved_edges yes)
			(filter_ratio 0.9)
			(enabled yes)
			(allow_two_segments yes)
			(prefer_zone_connections yes)
		)
		(net 314)
	)
	(via
		(at 122.53 88.06)
		(size 0.45)
		(drill 0.1)
		(layers "F.Cu" "B.Cu")
		(remove_unused_layers yes)
		(keep_end_layers yes)
		(zone_layer_connections)
		(teardrops
			(best_length_ratio 0.4)
			(max_length 1)
			(best_width_ratio 0.9)
			(max_width 2)
			(curved_edges yes)
			(filter_ratio 0.9)
			(enabled yes)
			(allow_two_segments yes)
			(prefer_zone_connections yes)
		)
		(net 314)
	)
	(via
		(at 197.6 167.4)
		(size 0.45)
		(drill 0.1)
		(layers "F.Cu" "B.Cu")
		(teardrops
			(best_length_ratio 0.4)
			(max_length 1)
			(best_width_ratio 0.9)
			(max_width 2)
			(curved_edges yes)
			(filter_ratio 0.9)
			(enabled yes)
			(allow_two_segments yes)
			(prefer_zone_connections yes)
		)
		(net 314)
	)
	(via
		(at 135.4 123)
		(size 0.45)
		(drill 0.1)
		(layers "F.Cu" "B.Cu")
		(teardrops
			(best_length_ratio 0.4)
			(max_length 1)
			(best_width_ratio 0.9)
			(max_width 2)
			(curved_edges yes)
			(filter_ratio 0.9)
			(enabled yes)
			(allow_two_segments yes)
			(prefer_zone_connections yes)
		)
		(net 314)
	)
	(segment
		(start 122 88.59)
		(end 122 92.43)
		(width 0.125)
		(layer "B.Cu")
		(net 314)
	)
	(segment
		(start 122 92.43)
		(end 122.53 92.96)
		(width 0.125)
		(layer "B.Cu")
		(net 314)
	)
	(segment
		(start 122.53 88.06)
		(end 122 88.59)
		(width 0.125)
		(layer "B.Cu")
		(net 314)
	)
	(segment
		(start 198.4 165.2)
		(end 198.4 166.6)
		(width 0.125)
		(layer "In2.Cu")
		(net 314)
	)
	(segment
		(start 187.1 163.75)
		(end 196.95 163.75)
		(width 0.125)
		(layer "In2.Cu")
		(net 314)
	)
	(segment
		(start 167.3 162.1)
		(end 167.6 162.4)
		(width 0.125)
		(layer "In2.Cu")
		(net 314)
	)
	(segment
		(start 135.4 122.4)
		(end 131.2 118.2)
		(width 0.125)
		(layer "In2.Cu")
		(net 314)
	)
	(segment
		(start 131.2 118.2)
		(end 131.2 97.6)
		(width 0.125)
		(layer "In2.Cu")
		(net 314)
	)
	(segment
		(start 165.2 160.8)
		(end 166.5 162.1)
		(width 0.125)
		(layer "In2.Cu")
		(net 314)
	)
	(segment
		(start 198.4 166.6)
		(end 197.6 167.4)
		(width 0.125)
		(layer "In2.Cu")
		(net 314)
	)
	(segment
		(start 166 158.85)
		(end 165.75 159.1)
		(width 0.125)
		(layer "In2.Cu")
		(net 314)
	)
	(segment
		(start 131.2 97.6)
		(end 126.6 93)
		(width 0.125)
		(layer "In2.Cu")
		(net 314)
	)
	(segment
		(start 167.6 162.4)
		(end 185.75 162.4)
		(width 0.125)
		(layer "In2.Cu")
		(net 314)
	)
	(segment
		(start 166.5 162.1)
		(end 167.3 162.1)
		(width 0.125)
		(layer "In2.Cu")
		(net 314)
	)
	(segment
		(start 165.2 160.1)
		(end 165.2 160.8)
		(width 0.125)
		(layer "In2.Cu")
		(net 314)
	)
	(segment
		(start 196.95 163.75)
		(end 198.4 165.2)
		(width 0.125)
		(layer "In2.Cu")
		(net 314)
	)
	(segment
		(start 165.75 159.1)
		(end 165.75 159.55)
		(width 0.125)
		(layer "In2.Cu")
		(net 314)
	)
	(segment
		(start 135.4 123)
		(end 135.4 122.4)
		(width 0.125)
		(layer "In2.Cu")
		(net 314)
	)
	(segment
		(start 185.75 162.4)
		(end 187.1 163.75)
		(width 0.125)
		(layer "In2.Cu")
		(net 314)
	)
	(segment
		(start 165.75 159.55)
		(end 165.2 160.1)
		(width 0.125)
		(layer "In2.Cu")
		(net 314)
	)
	(segment
		(start 199.025 168.685)
		(end 199.025 167.425)
		(width 0.125)
		(layer "F.Cu")
		(net 315)
	)
	(segment
		(start 199.025 167.425)
		(end 199.6 166.85)
		(width 0.125)
		(layer "F.Cu")
		(net 315)
	)
	(segment
		(start 167.15 158.9)
		(end 167.85 158.2)
		(width 0.125)
		(layer "F.Cu")
		(net 315)
	)
	(segment
		(start 167.85 158.2)
		(end 167.85 149.95)
		(width 0.125)
		(layer "F.Cu")
		(net 315)
	)
	(segment
		(start 218.959 82.851)
		(end 218.959 70.61)
		(width 0.5)
		(layer "F.Cu")
		(net 315)
	)
	(via
		(at 199.6 166.85)
		(size 0.45)
		(drill 0.1)
		(layers "F.Cu" "B.Cu")
		(teardrops
			(best_length_ratio 0.4)
			(max_length 1)
			(best_width_ratio 0.9)
			(max_width 2)
			(curved_edges yes)
			(filter_ratio 0.9)
			(enabled yes)
			(allow_two_segments yes)
			(prefer_zone_connections yes)
		)
		(net 315)
	)
	(via
		(at 218.7 146.4)
		(size 0.45)
		(drill 0.1)
		(layers "F.Cu" "B.Cu")
		(teardrops
			(best_length_ratio 0.4)
			(max_length 1)
			(best_width_ratio 0.9)
			(max_width 2)
			(curved_edges yes)
			(filter_ratio 0.9)
			(enabled yes)
			(allow_two_segments yes)
			(prefer_zone_connections yes)
		)
		(net 315)
	)
	(via
		(at 167.15 158.9)
		(size 0.45)
		(drill 0.1)
		(layers "F.Cu" "B.Cu")
		(teardrops
			(best_length_ratio 0.4)
			(max_length 1)
			(best_width_ratio 0.9)
			(max_width 2)
			(curved_edges yes)
			(filter_ratio 0.9)
			(enabled yes)
			(allow_two_segments yes)
			(prefer_zone_connections yes)
		)
		(net 315)
	)
	(via
		(at 218.959 82.851)
		(size 0.45)
		(drill 0.1)
		(layers "F.Cu" "B.Cu")
		(remove_unused_layers yes)
		(keep_end_layers yes)
		(zone_layer_connections "In2.Cu")
		(teardrops
			(best_length_ratio 0.4)
			(max_length 1)
			(best_width_ratio 0.9)
			(max_width 2)
			(curved_edges yes)
			(filter_ratio 0.9)
			(enabled yes)
			(allow_two_segments yes)
			(prefer_zone_connections yes)
		)
		(net 315)
	)
	(via
		(at 219.8 142.9)
		(size 0.45)
		(drill 0.1)
		(layers "F.Cu" "B.Cu")
		(teardrops
			(best_length_ratio 0.4)
			(max_length 1)
			(best_width_ratio 0.9)
			(max_width 2)
			(curved_edges yes)
			(filter_ratio 0.9)
			(enabled yes)
			(allow_two_segments yes)
			(prefer_zone_connections yes)
		)
		(net 315)
	)
	(via
		(at 167.85 149.95)
		(size 0.45)
		(drill 0.1)
		(layers "F.Cu" "B.Cu")
		(teardrops
			(best_length_ratio 0.4)
			(max_length 1)
			(best_width_ratio 0.9)
			(max_width 2)
			(curved_edges yes)
			(filter_ratio 0.9)
			(enabled yes)
			(allow_two_segments yes)
			(prefer_zone_connections yes)
		)
		(net 315)
	)
	(segment
		(start 218.7 146.4)
		(end 219.8 145.3)
		(width 0.125)
		(layer "B.Cu")
		(net 315)
	)
	(segment
		(start 219.8 145.3)
		(end 219.8 142.9)
		(width 0.125)
		(layer "B.Cu")
		(net 315)
	)
	(segment
		(start 166.2 159.4)
		(end 166.2 159.5)
		(width 0.125)
		(layer "In2.Cu")
		(net 315)
	)
	(segment
		(start 218.65 146.4)
		(end 218.1 146.95)
		(width 0.125)
		(layer "In2.Cu")
		(net 315)
	)
	(segment
		(start 218.15 131.41)
		(end 218.15 123.96)
		(width 0.125)
		(layer "In2.Cu")
		(net 315)
	)
	(segment
		(start 207.25 113.06)
		(end 207.25 91.835)
		(width 0.125)
		(layer "In2.Cu")
		(net 315)
	)
	(segment
		(start 218.7 146.4)
		(end 218.65 146.4)
		(width 0.125)
		(layer "In2.Cu")
		(net 315)
	)
	(segment
		(start 162.5 145.55)
		(end 162.5 150)
		(width 0.125)
		(layer "In2.Cu")
		(net 315)
	)
	(segment
		(start 218.3 83.51)
		(end 218.959 82.851)
		(width 0.125)
		(layer "In2.Cu")
		(net 315)
	)
	(segment
		(start 165.6 160.846446)
		(end 166.603554 161.85)
		(width 0.125)
		(layer "In2.Cu")
		(net 315)
	)
	(segment
		(start 197.206777 163.42)
		(end 199.6 165.813223)
		(width 0.125)
		(layer "In2.Cu")
		(net 315)
	)
	(segment
		(start 189.425 140.325)
		(end 167.725 140.325)
		(width 0.125)
		(layer "In2.Cu")
		(net 315)
	)
	(segment
		(start 166.603554 161.85)
		(end 167.45 161.85)
		(width 0.125)
		(layer "In2.Cu")
		(net 315)
	)
	(segment
		(start 165.6 160.1)
		(end 165.6 160.846446)
		(width 0.125)
		(layer "In2.Cu")
		(net 315)
	)
	(segment
		(start 167.85 150.4)
		(end 167.85 149.95)
		(width 0.125)
		(layer "In2.Cu")
		(net 315)
	)
	(segment
		(start 167.55 150.7)
		(end 167.85 150.4)
		(width 0.125)
		(layer "In2.Cu")
		(net 315)
	)
	(segment
		(start 190.45 141.35)
		(end 189.425 140.325)
		(width 0.125)
		(layer "In2.Cu")
		(net 315)
	)
	(segment
		(start 199.6 165.813223)
		(end 199.6 166.85)
		(width 0.125)
		(layer "In2.Cu")
		(net 315)
	)
	(segment
		(start 191.45 141.35)
		(end 190.45 141.35)
		(width 0.125)
		(layer "In2.Cu")
		(net 315)
	)
	(segment
		(start 166.7 158.9)
		(end 166.2 159.4)
		(width 0.125)
		(layer "In2.Cu")
		(net 315)
	)
	(segment
		(start 167.725 140.325)
		(end 162.5 145.55)
		(width 0.125)
		(layer "In2.Cu")
		(net 315)
	)
	(segment
		(start 167.75 162.15)
		(end 186.02 162.15)
		(width 0.125)
		(layer "In2.Cu")
		(net 315)
	)
	(segment
		(start 166.2 159.5)
		(end 165.6 160.1)
		(width 0.125)
		(layer "In2.Cu")
		(net 315)
	)
	(segment
		(start 167.45 161.85)
		(end 167.75 162.15)
		(width 0.125)
		(layer "In2.Cu")
		(net 315)
	)
	(segment
		(start 186.02 162.15)
		(end 187.29 163.42)
		(width 0.125)
		(layer "In2.Cu")
		(net 315)
	)
	(segment
		(start 167.15 158.9)
		(end 166.7 158.9)
		(width 0.125)
		(layer "In2.Cu")
		(net 315)
	)
	(segment
		(start 218.15 123.96)
		(end 207.25 113.06)
		(width 0.125)
		(layer "In2.Cu")
		(net 315)
	)
	(segment
		(start 162.5 150)
		(end 163.2 150.7)
		(width 0.125)
		(layer "In2.Cu")
		(net 315)
	)
	(segment
		(start 215.575 83.51)
		(end 218.3 83.51)
		(width 0.125)
		(layer "In2.Cu")
		(net 315)
	)
	(segment
		(start 207.25 91.835)
		(end 215.575 83.51)
		(width 0.125)
		(layer "In2.Cu")
		(net 315)
	)
	(segment
		(start 219.8 133.06)
		(end 218.15 131.41)
		(width 0.125)
		(layer "In2.Cu")
		(net 315)
	)
	(segment
		(start 218.1 146.95)
		(end 197.05 146.95)
		(width 0.125)
		(layer "In2.Cu")
		(net 315)
	)
	(segment
		(start 197.05 146.95)
		(end 191.45 141.35)
		(width 0.125)
		(layer "In2.Cu")
		(net 315)
	)
	(segment
		(start 187.29 163.42)
		(end 197.206777 163.42)
		(width 0.125)
		(layer "In2.Cu")
		(net 315)
	)
	(segment
		(start 163.2 150.7)
		(end 167.55 150.7)
		(width 0.125)
		(layer "In2.Cu")
		(net 315)
	)
	(segment
		(start 219.8 142.9)
		(end 219.8 133.06)
		(width 0.125)
		(layer "In2.Cu")
		(net 315)
	)
	(segment
		(start 200.525 168.685)
		(end 200.525 169.625)
		(width 0.125)
		(layer "F.Cu")
		(net 318)
	)
	(segment
		(start 199.9 170.25)
		(end 200.525 169.625)
		(width 0.125)
		(layer "F.Cu")
		(net 318)
	)
	(segment
		(start 199.9 170.25)
		(end 199.9 170.35)
		(width 0.125)
		(layer "F.Cu")
		(net 318)
	)
	(via
		(at 199.9 170.35)
		(size 0.45)
		(drill 0.1)
		(layers "F.Cu" "B.Cu")
		(teardrops
			(best_length_ratio 0.4)
			(max_length 1)
			(best_width_ratio 0.9)
			(max_width 2)
			(curved_edges yes)
			(filter_ratio 0.9)
			(enabled yes)
			(allow_two_segments yes)
			(prefer_zone_connections yes)
		)
		(net 318)
	)
	(segment
		(start 195.95 168.625)
		(end 195.475 168.15)
		(width 0.125)
		(layer "B.Cu")
		(net 318)
	)
	(segment
		(start 198.925 168.625)
		(end 195.95 168.625)
		(width 0.125)
		(layer "B.Cu")
		(net 318)
	)
	(segment
		(start 199.9 169.6)
		(end 198.925 168.625)
		(width 0.125)
		(layer "B.Cu")
		(net 318)
	)
	(segment
		(start 195.475 164.45)
		(end 196.6 163.325)
		(width 0.125)
		(layer "B.Cu")
		(net 318)
	)
	(segment
		(start 199.9 170.35)
		(end 199.9 169.6)
		(width 0.125)
		(layer "B.Cu")
		(net 318)
	)
	(segment
		(start 195.475 168.15)
		(end 195.475 164.45)
		(width 0.125)
		(layer "B.Cu")
		(net 318)
	)
	(segment
		(start 113.53 132.9)
		(end 113.68 133.05)
		(width 0.182)
		(layer "F.Cu")
		(net 321)
	)
	(segment
		(start 109.505 132.41)
		(end 110.74 132.41)
		(width 0.182)
		(layer "F.Cu")
		(net 321)
	)
	(segment
		(start 111.23 132.9)
		(end 113.53 132.9)
		(width 0.182)
		(layer "F.Cu")
		(net 321)
	)
	(segment
		(start 202.525 168.685)
		(end 202.525 167.525)
		(width 0.182)
		(layer "F.Cu")
		(net 321)
	)
	(segment
		(start 110.74 132.41)
		(end 111.23 132.9)
		(width 0.182)
		(layer "F.Cu")
		(net 321)
	)
	(segment
		(start 202.525 167.525)
		(end 202.5 167.5)
		(width 0.182)
		(layer "F.Cu")
		(net 321)
	)
	(via
		(at 113.68 133.05)
		(size 0.45)
		(drill 0.1)
		(layers "F.Cu" "B.Cu")
		(remove_unused_layers yes)
		(keep_end_layers yes)
		(zone_layer_connections "In5.Cu")
		(teardrops
			(best_length_ratio 0.4)
			(max_length 1)
			(best_width_ratio 0.9)
			(max_width 2)
			(curved_edges yes)
			(filter_ratio 0.9)
			(enabled yes)
			(allow_two_segments yes)
			(prefer_zone_connections yes)
		)
		(net 321)
	)
	(via
		(at 202.5 167.5)
		(size 0.45)
		(drill 0.1)
		(layers "F.Cu" "B.Cu")
		(teardrops
			(best_length_ratio 0.4)
			(max_length 1)
			(best_width_ratio 0.9)
			(max_width 2)
			(curved_edges yes)
			(filter_ratio 0.9)
			(enabled yes)
			(allow_two_segments yes)
			(prefer_zone_connections yes)
		)
		(net 321)
	)
	(via
		(at 166.4 159.9)
		(size 0.45)
		(drill 0.1)
		(layers "F.Cu" "B.Cu")
		(teardrops
			(best_length_ratio 0.4)
			(max_length 1)
			(best_width_ratio 0.9)
			(max_width 2)
			(curved_edges yes)
			(filter_ratio 0.9)
			(enabled yes)
			(allow_two_segments yes)
			(prefer_zone_connections yes)
		)
		(net 321)
	)
	(segment
		(start 166.4 159.9)
		(end 177.5 159.9)
		(width 0.155)
		(layer "In2.Cu")
		(net 321)
	)
	(segment
		(start 178.1 160.5)
		(end 186.85 160.5)
		(width 0.155)
		(layer "In2.Cu")
		(net 321)
	)
	(segment
		(start 188.8 162.45)
		(end 199.1 162.45)
		(width 0.155)
		(layer "In2.Cu")
		(net 321)
	)
	(segment
		(start 202.05 167.5)
		(end 202.5 167.5)
		(width 0.155)
		(layer "In2.Cu")
		(net 321)
	)
	(segment
		(start 186.85 160.5)
		(end 188.8 162.45)
		(width 0.155)
		(layer "In2.Cu")
		(net 321)
	)
	(segment
		(start 199.1 162.45)
		(end 201.45 164.8)
		(width 0.155)
		(layer "In2.Cu")
		(net 321)
	)
	(segment
		(start 201.45 164.8)
		(end 201.45 166.9)
		(width 0.155)
		(layer "In2.Cu")
		(net 321)
	)
	(segment
		(start 201.45 166.9)
		(end 202.05 167.5)
		(width 0.155)
		(layer "In2.Cu")
		(net 321)
	)
	(segment
		(start 177.5 159.9)
		(end 178.1 160.5)
		(width 0.155)
		(layer "In2.Cu")
		(net 321)
	)
	(segment
		(start 158.05 156.2)
		(end 158.05 156.7)
		(width 0.155)
		(layer "In5.Cu")
		(net 321)
	)
	(segment
		(start 121.15 136.3)
		(end 121.15 143.6)
		(width 0.155)
		(layer "In5.Cu")
		(net 321)
	)
	(segment
		(start 138.010149 144.755351)
		(end 138.100149 144.755351)
		(width 0.155)
		(layer "In5.Cu")
		(net 321)
	)
	(segment
		(start 142.5 150.7)
		(end 155.1 150.7)
		(width 0.155)
		(layer "In5.Cu")
		(net 321)
	)
	(segment
		(start 125.330149 145.25)
		(end 125.330149 144.935354)
		(width 0.155)
		(layer "In5.Cu")
		(net 321)
	)
	(segment
		(start 125.780149 145.25)
		(end 125.780149 145.864646)
		(width 0.155)
		(layer "In5.Cu")
		(net 321)
	)
	(segment
		(start 117.9 133.05)
		(end 121.15 136.3)
		(width 0.155)
		(layer "In5.Cu")
		(net 321)
	)
	(segment
		(start 132.730149 145.86465)
		(end 132.730149 145.43)
		(width 0.155)
		(layer "In5.Cu")
		(net 321)
	)
	(segment
		(start 129.030149 145.07)
		(end 129.030149 144.935351)
		(width 0.155)
		(layer "In5.Cu")
		(net 321)
	)
	(segment
		(start 126.860149 145.25)
		(end 126.950149 145.25)
		(width 0.155)
		(layer "In5.Cu")
		(net 321)
	)
	(segment
		(start 125.780149 144.935354)
		(end 125.780149 145.25)
		(width 0.155)
		(layer "In5.Cu")
		(net 321)
	)
	(segment
		(start 138.280149 144.935351)
		(end 138.280149 145.07)
		(width 0.155)
		(layer "In5.Cu")
		(net 321)
	)
	(segment
		(start 133.680149 145.43)
		(end 133.680149 145.614652)
		(width 0.155)
		(layer "In5.Cu")
		(net 321)
	)
	(segment
		(start 137.830149 145.07)
		(end 137.830149 144.935351)
		(width 0.155)
		(layer "In5.Cu")
		(net 321)
	)
	(segment
		(start 131.830149 145.25)
		(end 131.830149 144.93535)
		(width 0.155)
		(layer "In5.Cu")
		(net 321)
	)
	(segment
		(start 156.5 152.1)
		(end 156.5 154.65)
		(width 0.155)
		(layer "In5.Cu")
		(net 321)
	)
	(segment
		(start 129.480149 144.935351)
		(end 129.480149 145.07)
		(width 0.155)
		(layer "In5.Cu")
		(net 321)
	)
	(segment
		(start 131.560149 146.04465)
		(end 131.650149 146.04465)
		(width 0.155)
		(layer "In5.Cu")
		(net 321)
	)
	(segment
		(start 137.380149 144.93535)
		(end 137.380149 145.07)
		(width 0.155)
		(layer "In5.Cu")
		(net 321)
	)
	(segment
		(start 135.030149 145.86465)
		(end 135.030149 145.25)
		(width 0.155)
		(layer "In5.Cu")
		(net 321)
	)
	(segment
		(start 140.85 149.05)
		(end 142.5 150.7)
		(width 0.155)
		(layer "In5.Cu")
		(net 321)
	)
	(segment
		(start 126.230149 145.25)
		(end 126.230149 145.07)
		(width 0.155)
		(layer "In5.Cu")
		(net 321)
	)
	(segment
		(start 133.000149 145.25)
		(end 133.500149 145.25)
		(width 0.155)
		(layer "In5.Cu")
		(net 321)
	)
	(segment
		(start 132.460149 146.04465)
		(end 132.550149 146.04465)
		(width 0.155)
		(layer "In5.Cu")
		(net 321)
	)
	(segment
		(start 130.930149 145.07)
		(end 130.930149 144.935351)
		(width 0.155)
		(layer "In5.Cu")
		(net 321)
	)
	(segment
		(start 125.330149 145.864646)
		(end 125.330149 145.25)
		(width 0.155)
		(layer "In5.Cu")
		(net 321)
	)
	(segment
		(start 124.880149 145.25)
		(end 124.880149 145.864646)
		(width 0.155)
		(layer "In5.Cu")
		(net 321)
	)
	(segment
		(start 137.380149 145.25)
		(end 137.380149 145.864652)
		(width 0.155)
		(layer "In5.Cu")
		(net 321)
	)
	(segment
		(start 133.860149 145.794652)
		(end 133.950149 145.794652)
		(width 0.155)
		(layer "In5.Cu")
		(net 321)
	)
	(segment
		(start 128.580149 145.25)
		(end 128.580149 145.864649)
		(width 0.155)
		(layer "In5.Cu")
		(net 321)
	)
	(segment
		(start 131.380149 144.935351)
		(end 131.380149 145.07)
		(width 0.155)
		(layer "In5.Cu")
		(net 321)
	)
	(segment
		(start 130.250149 145.25)
		(end 130.750149 145.25)
		(width 0.155)
		(layer "In5.Cu")
		(net 321)
	)
	(segment
		(start 132.280149 145.43)
		(end 132.280149 145.86465)
		(width 0.155)
		(layer "In5.Cu")
		(net 321)
	)
	(segment
		(start 125.060149 146.044646)
		(end 125.150149 146.044646)
		(width 0.155)
		(layer "In5.Cu")
		(net 321)
	)
	(segment
		(start 137.830149 145.25)
		(end 137.830149 145.07)
		(width 0.155)
		(layer "In5.Cu")
		(net 321)
	)
	(segment
		(start 137.380149 145.07)
		(end 137.380149 145.25)
		(width 0.155)
		(layer "In5.Cu")
		(net 321)
	)
	(segment
		(start 129.750149 145.25)
		(end 130.250149 145.25)
		(width 0.155)
		(layer "In5.Cu")
		(net 321)
	)
	(segment
		(start 139.8 145.25)
		(end 139.9525 145.4025)
		(width 0.155)
		(layer "In5.Cu")
		(net 321)
	)
	(segment
		(start 126.230149 145.07)
		(end 126.230149 144.935354)
		(width 0.155)
		(layer "In5.Cu")
		(net 321)
	)
	(segment
		(start 131.110149 144.755351)
		(end 131.200149 144.755351)
		(width 0.155)
		(layer "In5.Cu")
		(net 321)
	)
	(segment
		(start 124.160149 146.044646)
		(end 124.250149 146.044646)
		(width 0.155)
		(layer "In5.Cu")
		(net 321)
	)
	(segment
		(start 136.930149 145.07)
		(end 136.930149 144.93535)
		(width 0.155)
		(layer "In5.Cu")
		(net 321)
	)
	(segment
		(start 127.450149 145.25)
		(end 127.950149 145.25)
		(width 0.155)
		(layer "In5.Cu")
		(net 321)
	)
	(segment
		(start 132.910149 145.25)
		(end 133.000149 145.25)
		(width 0.155)
		(layer "In5.Cu")
		(net 321)
	)
	(segment
		(start 123.980149 145.43)
		(end 123.980149 145.864646)
		(width 0.155)
		(layer "In5.Cu")
		(net 321)
	)
	(segment
		(start 158.05 156.7)
		(end 159.125 157.775)
		(width 0.155)
		(layer "In5.Cu")
		(net 321)
	)
	(segment
		(start 125.510149 144.755354)
		(end 125.600149 144.755354)
		(width 0.155)
		(layer "In5.Cu")
		(net 321)
	)
	(segment
		(start 135.750149 145.25)
		(end 136.250149 145.25)
		(width 0.155)
		(layer "In5.Cu")
		(net 321)
	)
	(segment
		(start 128.580149 145.07)
		(end 128.580149 145.25)
		(width 0.155)
		(layer "In5.Cu")
		(net 321)
	)
	(segment
		(start 124.430149 145.43)
		(end 124.430149 145.25)
		(width 0.155)
		(layer "In5.Cu")
		(net 321)
	)
	(segment
		(start 134.580149 144.935349)
		(end 134.580149 145.25)
		(width 0.155)
		(layer "In5.Cu")
		(net 321)
	)
	(segment
		(start 125.960149 146.044646)
		(end 126.050149 146.044646)
		(width 0.155)
		(layer "In5.Cu")
		(net 321)
	)
	(segment
		(start 126.230149 145.864646)
		(end 126.230149 145.25)
		(width 0.155)
		(layer "In5.Cu")
		(net 321)
	)
	(segment
		(start 136.250149 145.25)
		(end 136.750149 145.25)
		(width 0.155)
		(layer "In5.Cu")
		(net 321)
	)
	(segment
		(start 135.660149 145.25)
		(end 135.750149 145.25)
		(width 0.155)
		(layer "In5.Cu")
		(net 321)
	)
	(segment
		(start 129.210149 144.755351)
		(end 129.300149 144.755351)
		(width 0.155)
		(layer "In5.Cu")
		(net 321)
	)
	(segment
		(start 134.130149 145.25)
		(end 134.130149 144.935349)
		(width 0.155)
		(layer "In5.Cu")
		(net 321)
	)
	(segment
		(start 121.15 143.6)
		(end 122.8 145.25)
		(width 0.155)
		(layer "In5.Cu")
		(net 321)
	)
	(segment
		(start 140.85 146.3)
		(end 140.85 149.05)
		(width 0.155)
		(layer "In5.Cu")
		(net 321)
	)
	(segment
		(start 132.280149 144.93535)
		(end 132.280149 145.25)
		(width 0.155)
		(layer "In5.Cu")
		(net 321)
	)
	(segment
		(start 138.460149 145.25)
		(end 138.550149 145.25)
		(width 0.155)
		(layer "In5.Cu")
		(net 321)
	)
	(segment
		(start 131.380149 145.07)
		(end 131.380149 145.25)
		(width 0.155)
		(layer "In5.Cu")
		(net 321)
	)
	(segment
		(start 122.8 145.25)
		(end 123.800149 145.25)
		(width 0.155)
		(layer "In5.Cu")
		(net 321)
	)
	(segment
		(start 128.130149 145.07)
		(end 128.130149 144.935351)
		(width 0.155)
		(layer "In5.Cu")
		(net 321)
	)
	(segment
		(start 135.480149 144.935348)
		(end 135.480149 145.07)
		(width 0.155)
		(layer "In5.Cu")
		(net 321)
	)
	(segment
		(start 126.950149 145.25)
		(end 127.450149 145.25)
		(width 0.155)
		(layer "In5.Cu")
		(net 321)
	)
	(segment
		(start 135.030149 145.25)
		(end 135.030149 145.07)
		(width 0.155)
		(layer "In5.Cu")
		(net 321)
	)
	(segment
		(start 126.680149 144.935354)
		(end 126.680149 145.07)
		(width 0.155)
		(layer "In5.Cu")
		(net 321)
	)
	(segment
		(start 155.1 150.7)
		(end 156.5 152.1)
		(width 0.155)
		(layer "In5.Cu")
		(net 321)
	)
	(segment
		(start 131.380149 145.25)
		(end 131.380149 145.86465)
		(width 0.155)
		(layer "In5.Cu")
		(net 321)
	)
	(segment
		(start 113.68 133.05)
		(end 117.9 133.05)
		(width 0.155)
		(layer "In5.Cu")
		(net 321)
	)
	(segment
		(start 139.9525 145.4025)
		(end 140.85 146.3)
		(width 0.155)
		(layer "In5.Cu")
		(net 321)
	)
	(segment
		(start 134.580149 145.25)
		(end 134.580149 145.86465)
		(width 0.155)
		(layer "In5.Cu")
		(net 321)
	)
	(segment
		(start 134.760149 146.04465)
		(end 134.850149 146.04465)
		(width 0.155)
		(layer "In5.Cu")
		(net 321)
	)
	(segment
		(start 135.210149 144.755348)
		(end 135.300149 144.755348)
		(width 0.155)
		(layer "In5.Cu")
		(net 321)
	)
	(segment
		(start 137.560149 146.044652)
		(end 137.650149 146.044652)
		(width 0.155)
		(layer "In5.Cu")
		(net 321)
	)
	(segment
		(start 137.110149 144.75535)
		(end 137.200149 144.75535)
		(width 0.155)
		(layer "In5.Cu")
		(net 321)
	)
	(segment
		(start 129.660149 145.25)
		(end 129.750149 145.25)
		(width 0.155)
		(layer "In5.Cu")
		(net 321)
	)
	(segment
		(start 159.125 157.775)
		(end 160.975 157.775)
		(width 0.155)
		(layer "In5.Cu")
		(net 321)
	)
	(segment
		(start 128.310149 144.755351)
		(end 128.400149 144.755351)
		(width 0.155)
		(layer "In5.Cu")
		(net 321)
	)
	(segment
		(start 124.610149 144.755354)
		(end 124.700149 144.755354)
		(width 0.155)
		(layer "In5.Cu")
		(net 321)
	)
	(segment
		(start 137.830149 145.864652)
		(end 137.830149 145.25)
		(width 0.155)
		(layer "In5.Cu")
		(net 321)
	)
	(segment
		(start 134.310149 144.755349)
		(end 134.400149 144.755349)
		(width 0.155)
		(layer "In5.Cu")
		(net 321)
	)
	(segment
		(start 126.410149 144.755354)
		(end 126.500149 144.755354)
		(width 0.155)
		(layer "In5.Cu")
		(net 321)
	)
	(segment
		(start 128.760149 146.044649)
		(end 128.850149 146.044649)
		(width 0.155)
		(layer "In5.Cu")
		(net 321)
	)
	(segment
		(start 156.5 154.65)
		(end 158.05 156.2)
		(width 0.155)
		(layer "In5.Cu")
		(net 321)
	)
	(segment
		(start 134.130149 145.614652)
		(end 134.130149 145.43)
		(width 0.155)
		(layer "In5.Cu")
		(net 321)
	)
	(segment
		(start 129.030149 145.25)
		(end 129.030149 145.07)
		(width 0.155)
		(layer "In5.Cu")
		(net 321)
	)
	(segment
		(start 138.550149 145.25)
		(end 139.8 145.25)
		(width 0.155)
		(layer "In5.Cu")
		(net 321)
	)
	(segment
		(start 163.05 159.85)
		(end 166.35 159.85)
		(width 0.155)
		(layer "In5.Cu")
		(net 321)
	)
	(segment
		(start 124.880149 144.935354)
		(end 124.880149 145.25)
		(width 0.155)
		(layer "In5.Cu")
		(net 321)
	)
	(segment
		(start 128.580149 144.935351)
		(end 128.580149 145.07)
		(width 0.155)
		(layer "In5.Cu")
		(net 321)
	)
	(segment
		(start 132.280149 145.25)
		(end 132.280149 145.43)
		(width 0.155)
		(layer "In5.Cu")
		(net 321)
	)
	(segment
		(start 124.430149 145.25)
		(end 124.430149 144.935354)
		(width 0.155)
		(layer "In5.Cu")
		(net 321)
	)
	(segment
		(start 166.35 159.85)
		(end 166.4 159.9)
		(width 0.155)
		(layer "In5.Cu")
		(net 321)
	)
	(segment
		(start 132.010149 144.75535)
		(end 132.100149 144.75535)
		(width 0.155)
		(layer "In5.Cu")
		(net 321)
	)
	(segment
		(start 131.830149 145.86465)
		(end 131.830149 145.25)
		(width 0.155)
		(layer "In5.Cu")
		(net 321)
	)
	(segment
		(start 129.030149 145.864649)
		(end 129.030149 145.25)
		(width 0.155)
		(layer "In5.Cu")
		(net 321)
	)
	(segment
		(start 124.430149 145.864646)
		(end 124.430149 145.43)
		(width 0.155)
		(layer "In5.Cu")
		(net 321)
	)
	(segment
		(start 135.030149 145.07)
		(end 135.030149 144.935348)
		(width 0.155)
		(layer "In5.Cu")
		(net 321)
	)
	(segment
		(start 134.130149 145.43)
		(end 134.130149 145.25)
		(width 0.155)
		(layer "In5.Cu")
		(net 321)
	)
	(segment
		(start 160.975 157.775)
		(end 163.05 159.85)
		(width 0.155)
		(layer "In5.Cu")
		(net 321)
	)
	(arc
		(start 137.200149 144.75535)
		(mid 137.327428 144.808071)
		(end 137.380149 144.93535)
		(width 0.155)
		(layer "In5.Cu")
		(net 321)
	)
	(arc
		(start 128.130149 144.935351)
		(mid 128.18287 144.808072)
		(end 128.310149 144.755351)
		(width 0.155)
		(layer "In5.Cu")
		(net 321)
	)
	(arc
		(start 132.730149 145.43)
		(mid 132.78287 145.302721)
		(end 132.910149 145.25)
		(width 0.155)
		(layer "In5.Cu")
		(net 321)
	)
	(arc
		(start 135.480149 145.07)
		(mid 135.53287 145.197279)
		(end 135.660149 145.25)
		(width 0.155)
		(layer "In5.Cu")
		(net 321)
	)
	(arc
		(start 126.680149 145.07)
		(mid 126.73287 145.197279)
		(end 126.860149 145.25)
		(width 0.155)
		(layer "In5.Cu")
		(net 321)
	)
	(arc
		(start 136.750149 145.25)
		(mid 136.877428 145.197279)
		(end 136.930149 145.07)
		(width 0.155)
		(layer "In5.Cu")
		(net 321)
	)
	(arc
		(start 125.780149 145.864646)
		(mid 125.83287 145.991925)
		(end 125.960149 146.044646)
		(width 0.155)
		(layer "In5.Cu")
		(net 321)
	)
	(arc
		(start 137.650149 146.044652)
		(mid 137.777428 145.991931)
		(end 137.830149 145.864652)
		(width 0.155)
		(layer "In5.Cu")
		(net 321)
	)
	(arc
		(start 129.300149 144.755351)
		(mid 129.427428 144.808072)
		(end 129.480149 144.935351)
		(width 0.155)
		(layer "In5.Cu")
		(net 321)
	)
	(arc
		(start 131.830149 144.93535)
		(mid 131.88287 144.808071)
		(end 132.010149 144.75535)
		(width 0.155)
		(layer "In5.Cu")
		(net 321)
	)
	(arc
		(start 131.380149 145.86465)
		(mid 131.43287 145.991929)
		(end 131.560149 146.04465)
		(width 0.155)
		(layer "In5.Cu")
		(net 321)
	)
	(arc
		(start 124.880149 145.864646)
		(mid 124.93287 145.991925)
		(end 125.060149 146.044646)
		(width 0.155)
		(layer "In5.Cu")
		(net 321)
	)
	(arc
		(start 129.480149 145.07)
		(mid 129.53287 145.197279)
		(end 129.660149 145.25)
		(width 0.155)
		(layer "In5.Cu")
		(net 321)
	)
	(arc
		(start 123.980149 145.864646)
		(mid 124.03287 145.991925)
		(end 124.160149 146.044646)
		(width 0.155)
		(layer "In5.Cu")
		(net 321)
	)
	(arc
		(start 126.500149 144.755354)
		(mid 126.627428 144.808075)
		(end 126.680149 144.935354)
		(width 0.155)
		(layer "In5.Cu")
		(net 321)
	)
	(arc
		(start 137.830149 144.935351)
		(mid 137.88287 144.808072)
		(end 138.010149 144.755351)
		(width 0.155)
		(layer "In5.Cu")
		(net 321)
	)
	(arc
		(start 133.950149 145.794652)
		(mid 134.077428 145.741931)
		(end 134.130149 145.614652)
		(width 0.155)
		(layer "In5.Cu")
		(net 321)
	)
	(arc
		(start 134.850149 146.04465)
		(mid 134.977428 145.991929)
		(end 135.030149 145.86465)
		(width 0.155)
		(layer "In5.Cu")
		(net 321)
	)
	(arc
		(start 126.230149 144.935354)
		(mid 126.28287 144.808075)
		(end 126.410149 144.755354)
		(width 0.155)
		(layer "In5.Cu")
		(net 321)
	)
	(arc
		(start 138.100149 144.755351)
		(mid 138.227428 144.808072)
		(end 138.280149 144.935351)
		(width 0.155)
		(layer "In5.Cu")
		(net 321)
	)
	(arc
		(start 137.380149 145.864652)
		(mid 137.43287 145.991931)
		(end 137.560149 146.044652)
		(width 0.155)
		(layer "In5.Cu")
		(net 321)
	)
	(arc
		(start 132.100149 144.75535)
		(mid 132.227428 144.808071)
		(end 132.280149 144.93535)
		(width 0.155)
		(layer "In5.Cu")
		(net 321)
	)
	(arc
		(start 128.850149 146.044649)
		(mid 128.977428 145.991928)
		(end 129.030149 145.864649)
		(width 0.155)
		(layer "In5.Cu")
		(net 321)
	)
	(arc
		(start 130.930149 144.935351)
		(mid 130.98287 144.808072)
		(end 131.110149 144.755351)
		(width 0.155)
		(layer "In5.Cu")
		(net 321)
	)
	(arc
		(start 136.930149 144.93535)
		(mid 136.98287 144.808071)
		(end 137.110149 144.75535)
		(width 0.155)
		(layer "In5.Cu")
		(net 321)
	)
	(arc
		(start 135.300149 144.755348)
		(mid 135.427428 144.808069)
		(end 135.480149 144.935348)
		(width 0.155)
		(layer "In5.Cu")
		(net 321)
	)
	(arc
		(start 128.400149 144.755351)
		(mid 128.527428 144.808072)
		(end 128.580149 144.935351)
		(width 0.155)
		(layer "In5.Cu")
		(net 321)
	)
	(arc
		(start 134.580149 145.86465)
		(mid 134.63287 145.991929)
		(end 134.760149 146.04465)
		(width 0.155)
		(layer "In5.Cu")
		(net 321)
	)
	(arc
		(start 135.030149 144.935348)
		(mid 135.08287 144.808069)
		(end 135.210149 144.755348)
		(width 0.155)
		(layer "In5.Cu")
		(net 321)
	)
	(arc
		(start 123.800149 145.25)
		(mid 123.927428 145.302721)
		(end 123.980149 145.43)
		(width 0.155)
		(layer "In5.Cu")
		(net 321)
	)
	(arc
		(start 128.580149 145.864649)
		(mid 128.63287 145.991928)
		(end 128.760149 146.044649)
		(width 0.155)
		(layer "In5.Cu")
		(net 321)
	)
	(arc
		(start 127.950149 145.25)
		(mid 128.077428 145.197279)
		(end 128.130149 145.07)
		(width 0.155)
		(layer "In5.Cu")
		(net 321)
	)
	(arc
		(start 130.750149 145.25)
		(mid 130.877428 145.197279)
		(end 130.930149 145.07)
		(width 0.155)
		(layer "In5.Cu")
		(net 321)
	)
	(arc
		(start 132.280149 145.86465)
		(mid 132.33287 145.991929)
		(end 132.460149 146.04465)
		(width 0.155)
		(layer "In5.Cu")
		(net 321)
	)
	(arc
		(start 124.700149 144.755354)
		(mid 124.827428 144.808075)
		(end 124.880149 144.935354)
		(width 0.155)
		(layer "In5.Cu")
		(net 321)
	)
	(arc
		(start 134.400149 144.755349)
		(mid 134.527428 144.80807)
		(end 134.580149 144.935349)
		(width 0.155)
		(layer "In5.Cu")
		(net 321)
	)
	(arc
		(start 133.680149 145.614652)
		(mid 133.73287 145.741931)
		(end 133.860149 145.794652)
		(width 0.155)
		(layer "In5.Cu")
		(net 321)
	)
	(arc
		(start 125.330149 144.935354)
		(mid 125.38287 144.808075)
		(end 125.510149 144.755354)
		(width 0.155)
		(layer "In5.Cu")
		(net 321)
	)
	(arc
		(start 124.430149 144.935354)
		(mid 124.48287 144.808075)
		(end 124.610149 144.755354)
		(width 0.155)
		(layer "In5.Cu")
		(net 321)
	)
	(arc
		(start 125.600149 144.755354)
		(mid 125.727428 144.808075)
		(end 125.780149 144.935354)
		(width 0.155)
		(layer "In5.Cu")
		(net 321)
	)
	(arc
		(start 134.130149 144.935349)
		(mid 134.18287 144.80807)
		(end 134.310149 144.755349)
		(width 0.155)
		(layer "In5.Cu")
		(net 321)
	)
	(arc
		(start 126.050149 146.044646)
		(mid 126.177428 145.991925)
		(end 126.230149 145.864646)
		(width 0.155)
		(layer "In5.Cu")
		(net 321)
	)
	(arc
		(start 129.030149 144.935351)
		(mid 129.08287 144.808072)
		(end 129.210149 144.755351)
		(width 0.155)
		(layer "In5.Cu")
		(net 321)
	)
	(arc
		(start 132.550149 146.04465)
		(mid 132.677428 145.991929)
		(end 132.730149 145.86465)
		(width 0.155)
		(layer "In5.Cu")
		(net 321)
	)
	(arc
		(start 125.150149 146.044646)
		(mid 125.277428 145.991925)
		(end 125.330149 145.864646)
		(width 0.155)
		(layer "In5.Cu")
		(net 321)
	)
	(arc
		(start 131.650149 146.04465)
		(mid 131.777428 145.991929)
		(end 131.830149 145.86465)
		(width 0.155)
		(layer "In5.Cu")
		(net 321)
	)
	(arc
		(start 131.200149 144.755351)
		(mid 131.327428 144.808072)
		(end 131.380149 144.935351)
		(width 0.155)
		(layer "In5.Cu")
		(net 321)
	)
	(arc
		(start 138.280149 145.07)
		(mid 138.33287 145.197279)
		(end 138.460149 145.25)
		(width 0.155)
		(layer "In5.Cu")
		(net 321)
	)
	(arc
		(start 124.250149 146.044646)
		(mid 124.377428 145.991925)
		(end 124.430149 145.864646)
		(width 0.155)
		(layer "In5.Cu")
		(net 321)
	)
	(arc
		(start 133.500149 145.25)
		(mid 133.627428 145.302721)
		(end 133.680149 145.43)
		(width 0.155)
		(layer "In5.Cu")
		(net 321)
	)
	(segment
		(start 207 169.85)
		(end 207 168.71)
		(width 0.182)
		(layer "F.Cu")
		(net 322)
	)
	(segment
		(start 110.59 131.31)
		(end 111.18 131.9)
		(width 0.182)
		(layer "F.Cu")
		(net 322)
	)
	(segment
		(start 111.18 131.9)
		(end 113.79 131.9)
		(width 0.182)
		(layer "F.Cu")
		(net 322)
	)
	(segment
		(start 113.79 131.9)
		(end 114.05 132.16)
		(width 0.182)
		(layer "F.Cu")
		(net 322)
	)
	(segment
		(start 109.505 131.31)
		(end 110.59 131.31)
		(width 0.182)
		(layer "F.Cu")
		(net 322)
	)
	(segment
		(start 207 168.71)
		(end 207.025 168.685)
		(width 0.182)
		(layer "F.Cu")
		(net 322)
	)
	(via
		(at 114.05 132.16)
		(size 0.45)
		(drill 0.1)
		(layers "F.Cu" "B.Cu")
		(remove_unused_layers yes)
		(keep_end_layers yes)
		(zone_layer_connections "In5.Cu")
		(teardrops
			(best_length_ratio 0.4)
			(max_length 1)
			(best_width_ratio 0.9)
			(max_width 2)
			(curved_edges yes)
			(filter_ratio 0.9)
			(enabled yes)
			(allow_two_segments yes)
			(prefer_zone_connections yes)
		)
		(net 322)
	)
	(via
		(at 164.8 159.3)
		(size 0.45)
		(drill 0.1)
		(layers "F.Cu" "B.Cu")
		(teardrops
			(best_length_ratio 0.4)
			(max_length 1)
			(best_width_ratio 0.9)
			(max_width 2)
			(curved_edges yes)
			(filter_ratio 0.9)
			(enabled yes)
			(allow_two_segments yes)
			(prefer_zone_connections yes)
		)
		(net 322)
	)
	(via
		(at 207 169.85)
		(size 0.45)
		(drill 0.1)
		(layers "F.Cu" "B.Cu")
		(teardrops
			(best_length_ratio 0.4)
			(max_length 1)
			(best_width_ratio 0.9)
			(max_width 2)
			(curved_edges yes)
			(filter_ratio 0.9)
			(enabled yes)
			(allow_two_segments yes)
			(prefer_zone_connections yes)
		)
		(net 322)
	)
	(segment
		(start 168.575 167.9)
		(end 164.4 163.725)
		(width 0.155)
		(layer "In2.Cu")
		(net 322)
	)
	(segment
		(start 185.175 168.75)
		(end 170.95 168.75)
		(width 0.155)
		(layer "In2.Cu")
		(net 322)
	)
	(segment
		(start 187.375 170.95)
		(end 185.175 168.75)
		(width 0.155)
		(layer "In2.Cu")
		(net 322)
	)
	(segment
		(start 206.65 170.95)
		(end 187.375 170.95)
		(width 0.155)
		(layer "In2.Cu")
		(net 322)
	)
	(segment
		(start 207 169.85)
		(end 207 170.6)
		(width 0.155)
		(layer "In2.Cu")
		(net 322)
	)
	(segment
		(start 164.4 163.725)
		(end 164.4 159.7)
		(width 0.155)
		(layer "In2.Cu")
		(net 322)
	)
	(segment
		(start 170.95 168.75)
		(end 170.1 167.9)
		(width 0.155)
		(layer "In2.Cu")
		(net 322)
	)
	(segment
		(start 164.4 159.7)
		(end 164.8 159.3)
		(width 0.155)
		(layer "In2.Cu")
		(net 322)
	)
	(segment
		(start 207 170.6)
		(end 206.65 170.95)
		(width 0.155)
		(layer "In2.Cu")
		(net 322)
	)
	(segment
		(start 170.1 167.9)
		(end 168.575 167.9)
		(width 0.155)
		(layer "In2.Cu")
		(net 322)
	)
	(segment
		(start 142.85 149.575)
		(end 142.85 149.95)
		(width 0.155)
		(layer "In5.Cu")
		(net 322)
	)
	(segment
		(start 123.133681 141.835)
		(end 123.133681 141.925)
		(width 0.155)
		(layer "In5.Cu")
		(net 322)
	)
	(segment
		(start 122.953701 143.005)
		(end 122.48 143.005)
		(width 0.155)
		(layer "In5.Cu")
		(net 322)
	)
	(segment
		(start 123.133681 140.035)
		(end 123.133681 140.125)
		(width 0.155)
		(layer "In5.Cu")
		(net 322)
	)
	(segment
		(start 122.3 139.855)
		(end 122.48 139.855)
		(width 0.155)
		(layer "In5.Cu")
		(net 322)
	)
	(segment
		(start 142.2875 149.3)
		(end 142.575 149.3)
		(width 0.155)
		(layer "In5.Cu")
		(net 322)
	)
	(segment
		(start 158.5525 155.7525)
		(end 158.7825 155.7525)
		(width 0.155)
		(layer "In5.Cu")
		(net 322)
	)
	(segment
		(start 139.65 144.3)
		(end 141.55 146.2)
		(width 0.155)
		(layer "In5.Cu")
		(net 322)
	)
	(segment
		(start 122.953681 139.405)
		(end 122.3 139.405)
		(width 0.155)
		(layer "In5.Cu")
		(net 322)
	)
	(segment
		(start 122.18 137.5)
		(end 122.3 137.62)
		(width 0.155)
		(layer "In5.Cu")
		(net 322)
	)
	(segment
		(start 122.3 143.185)
		(end 122.3 143.275)
		(width 0.155)
		(layer "In5.Cu")
		(net 322)
	)
	(segment
		(start 157.05 154.25)
		(end 158.5525 155.7525)
		(width 0.155)
		(layer "In5.Cu")
		(net 322)
	)
	(segment
		(start 122.48 139.855)
		(end 122.953681 139.855)
		(width 0.155)
		(layer "In5.Cu")
		(net 322)
	)
	(segment
		(start 121.516317 139.585)
		(end 121.516317 139.675)
		(width 0.155)
		(layer "In5.Cu")
		(net 322)
	)
	(segment
		(start 122.48 141.655)
		(end 122.953681 141.655)
		(width 0.155)
		(layer "In5.Cu")
		(net 322)
	)
	(segment
		(start 122.48 142.555)
		(end 122.953701 142.555)
		(width 0.155)
		(layer "In5.Cu")
		(net 322)
	)
	(segment
		(start 122.3 138.955)
		(end 122.953681 138.955)
		(width 0.155)
		(layer "In5.Cu")
		(net 322)
	)
	(segment
		(start 122.953701 141.205)
		(end 122.48 141.205)
		(width 0.155)
		(layer "In5.Cu")
		(net 322)
	)
	(segment
		(start 123.133701 142.735)
		(end 123.133701 142.825)
		(width 0.155)
		(layer "In5.Cu")
		(net 322)
	)
	(segment
		(start 121.696317 139.855)
		(end 122.3 139.855)
		(width 0.155)
		(layer "In5.Cu")
		(net 322)
	)
	(segment
		(start 122.18 136.08)
		(end 122.18 137.5)
		(width 0.155)
		(layer "In5.Cu")
		(net 322)
	)
	(segment
		(start 122.3 139.405)
		(end 121.696317 139.405)
		(width 0.155)
		(layer "In5.Cu")
		(net 322)
	)
	(segment
		(start 122.3 142.285)
		(end 122.3 142.375)
		(width 0.155)
		(layer "In5.Cu")
		(net 322)
	)
	(segment
		(start 122.48 140.755)
		(end 122.953701 140.755)
		(width 0.155)
		(layer "In5.Cu")
		(net 322)
	)
	(segment
		(start 122.953681 140.305)
		(end 122.48 140.305)
		(width 0.155)
		(layer "In5.Cu")
		(net 322)
	)
	(segment
		(start 159.0025 155.9725)
		(end 159.0025 156.6475)
		(width 0.155)
		(layer "In5.Cu")
		(net 322)
	)
	(segment
		(start 122.3 137.62)
		(end 122.3 137.875)
		(width 0.155)
		(layer "In5.Cu")
		(net 322)
	)
	(segment
		(start 158.7825 155.7525)
		(end 159.0025 155.9725)
		(width 0.155)
		(layer "In5.Cu")
		(net 322)
	)
	(segment
		(start 141.55 148.5625)
		(end 142.2875 149.3)
		(width 0.155)
		(layer "In5.Cu")
		(net 322)
	)
	(segment
		(start 159.1925 156.8375)
		(end 161.0375 156.8375)
		(width 0.155)
		(layer "In5.Cu")
		(net 322)
	)
	(segment
		(start 122.3 138.505)
		(end 121.696317 138.505)
		(width 0.155)
		(layer "In5.Cu")
		(net 322)
	)
	(segment
		(start 123.133681 139.135)
		(end 123.133681 139.225)
		(width 0.155)
		(layer "In5.Cu")
		(net 322)
	)
	(segment
		(start 122.3 141.385)
		(end 122.3 141.475)
		(width 0.155)
		(layer "In5.Cu")
		(net 322)
	)
	(segment
		(start 157.05 151.15)
		(end 157.05 154.25)
		(width 0.155)
		(layer "In5.Cu")
		(net 322)
	)
	(segment
		(start 163.1 158.9)
		(end 164.4 158.9)
		(width 0.155)
		(layer "In5.Cu")
		(net 322)
	)
	(segment
		(start 122.3 140.485)
		(end 122.3 140.575)
		(width 0.155)
		(layer "In5.Cu")
		(net 322)
	)
	(segment
		(start 123.2 144.3)
		(end 139.65 144.3)
		(width 0.155)
		(layer "In5.Cu")
		(net 322)
	)
	(segment
		(start 122.3 143.275)
		(end 122.3 143.3)
		(width 0.155)
		(layer "In5.Cu")
		(net 322)
	)
	(segment
		(start 121.516317 138.685)
		(end 121.516317 138.775)
		(width 0.155)
		(layer "In5.Cu")
		(net 322)
	)
	(segment
		(start 142.575 149.3)
		(end 142.85 149.575)
		(width 0.155)
		(layer "In5.Cu")
		(net 322)
	)
	(segment
		(start 141.55 146.2)
		(end 141.55 148.5625)
		(width 0.155)
		(layer "In5.Cu")
		(net 322)
	)
	(segment
		(start 122.953681 138.505)
		(end 122.48 138.505)
		(width 0.155)
		(layer "In5.Cu")
		(net 322)
	)
	(segment
		(start 143.1 150.2)
		(end 156.1 150.2)
		(width 0.155)
		(layer "In5.Cu")
		(net 322)
	)
	(segment
		(start 142.85 149.95)
		(end 143.1 150.2)
		(width 0.155)
		(layer "In5.Cu")
		(net 322)
	)
	(segment
		(start 121.696317 138.955)
		(end 122.3 138.955)
		(width 0.155)
		(layer "In5.Cu")
		(net 322)
	)
	(segment
		(start 122.48 138.505)
		(end 122.3 138.505)
		(width 0.155)
		(layer "In5.Cu")
		(net 322)
	)
	(segment
		(start 114.05 132.16)
		(end 118.26 132.16)
		(width 0.155)
		(layer "In5.Cu")
		(net 322)
	)
	(segment
		(start 161.0375 156.8375)
		(end 163.1 158.9)
		(width 0.155)
		(layer "In5.Cu")
		(net 322)
	)
	(segment
		(start 122.3 143.3)
		(end 122.3 143.4)
		(width 0.155)
		(layer "In5.Cu")
		(net 322)
	)
	(segment
		(start 122.48 138.055)
		(end 122.953681 138.055)
		(width 0.155)
		(layer "In5.Cu")
		(net 322)
	)
	(segment
		(start 122.3 143.4)
		(end 123.2 144.3)
		(width 0.155)
		(layer "In5.Cu")
		(net 322)
	)
	(segment
		(start 164.4 158.9)
		(end 164.8 159.3)
		(width 0.155)
		(layer "In5.Cu")
		(net 322)
	)
	(segment
		(start 159.0025 156.6475)
		(end 159.1925 156.8375)
		(width 0.155)
		(layer "In5.Cu")
		(net 322)
	)
	(segment
		(start 123.133681 138.235)
		(end 123.133681 138.325)
		(width 0.155)
		(layer "In5.Cu")
		(net 322)
	)
	(segment
		(start 156.1 150.2)
		(end 157.05 151.15)
		(width 0.155)
		(layer "In5.Cu")
		(net 322)
	)
	(segment
		(start 118.26 132.16)
		(end 122.18 136.08)
		(width 0.155)
		(layer "In5.Cu")
		(net 322)
	)
	(segment
		(start 123.133701 140.935)
		(end 123.133701 141.025)
		(width 0.155)
		(layer "In5.Cu")
		(net 322)
	)
	(segment
		(start 122.953681 142.105)
		(end 122.48 142.105)
		(width 0.155)
		(layer "In5.Cu")
		(net 322)
	)
	(arc
		(start 122.48 143.005)
		(mid 122.352721 143.057721)
		(end 122.3 143.185)
		(width 0.155)
		(layer "In5.Cu")
		(net 322)
	)
	(arc
		(start 122.953681 138.955)
		(mid 123.08096 139.007721)
		(end 123.133681 139.135)
		(width 0.155)
		(layer "In5.Cu")
		(net 322)
	)
	(arc
		(start 123.133681 141.925)
		(mid 123.08096 142.052279)
		(end 122.953681 142.105)
		(width 0.155)
		(layer "In5.Cu")
		(net 322)
	)
	(arc
		(start 122.3 141.475)
		(mid 122.352721 141.602279)
		(end 122.48 141.655)
		(width 0.155)
		(layer "In5.Cu")
		(net 322)
	)
	(arc
		(start 121.516317 138.775)
		(mid 121.569038 138.902279)
		(end 121.696317 138.955)
		(width 0.155)
		(layer "In5.Cu")
		(net 322)
	)
	(arc
		(start 123.133681 139.225)
		(mid 123.08096 139.352279)
		(end 122.953681 139.405)
		(width 0.155)
		(layer "In5.Cu")
		(net 322)
	)
	(arc
		(start 122.48 142.105)
		(mid 122.352721 142.157721)
		(end 122.3 142.285)
		(width 0.155)
		(layer "In5.Cu")
		(net 322)
	)
	(arc
		(start 122.953701 142.555)
		(mid 123.08098 142.607721)
		(end 123.133701 142.735)
		(width 0.155)
		(layer "In5.Cu")
		(net 322)
	)
	(arc
		(start 122.953681 141.655)
		(mid 123.08096 141.707721)
		(end 123.133681 141.835)
		(width 0.155)
		(layer "In5.Cu")
		(net 322)
	)
	(arc
		(start 122.3 140.575)
		(mid 122.352721 140.702279)
		(end 122.48 140.755)
		(width 0.155)
		(layer "In5.Cu")
		(net 322)
	)
	(arc
		(start 121.696317 138.505)
		(mid 121.569038 138.557721)
		(end 121.516317 138.685)
		(width 0.155)
		(layer "In5.Cu")
		(net 322)
	)
	(arc
		(start 122.953681 139.855)
		(mid 123.08096 139.907721)
		(end 123.133681 140.035)
		(width 0.155)
		(layer "In5.Cu")
		(net 322)
	)
	(arc
		(start 122.3 142.375)
		(mid 122.352721 142.502279)
		(end 122.48 142.555)
		(width 0.155)
		(layer "In5.Cu")
		(net 322)
	)
	(arc
		(start 122.3 137.875)
		(mid 122.352721 138.002279)
		(end 122.48 138.055)
		(width 0.155)
		(layer "In5.Cu")
		(net 322)
	)
	(arc
		(start 122.48 140.305)
		(mid 122.352721 140.357721)
		(end 122.3 140.485)
		(width 0.155)
		(layer "In5.Cu")
		(net 322)
	)
	(arc
		(start 121.696317 139.405)
		(mid 121.569038 139.457721)
		(end 121.516317 139.585)
		(width 0.155)
		(layer "In5.Cu")
		(net 322)
	)
	(arc
		(start 123.133701 142.825)
		(mid 123.08098 142.952279)
		(end 122.953701 143.005)
		(width 0.155)
		(layer "In5.Cu")
		(net 322)
	)
	(arc
		(start 123.133681 138.325)
		(mid 123.08096 138.452279)
		(end 122.953681 138.505)
		(width 0.155)
		(layer "In5.Cu")
		(net 322)
	)
	(arc
		(start 121.516317 139.675)
		(mid 121.569038 139.802279)
		(end 121.696317 139.855)
		(width 0.155)
		(layer "In5.Cu")
		(net 322)
	)
	(arc
		(start 123.133681 140.125)
		(mid 123.08096 140.252279)
		(end 122.953681 140.305)
		(width 0.155)
		(layer "In5.Cu")
		(net 322)
	)
	(arc
		(start 122.48 141.205)
		(mid 122.352721 141.257721)
		(end 122.3 141.385)
		(width 0.155)
		(layer "In5.Cu")
		(net 322)
	)
	(arc
		(start 122.953681 138.055)
		(mid 123.08096 138.107721)
		(end 123.133681 138.235)
		(width 0.155)
		(layer "In5.Cu")
		(net 322)
	)
	(arc
		(start 122.953701 140.755)
		(mid 123.08098 140.807721)
		(end 123.133701 140.935)
		(width 0.155)
		(layer "In5.Cu")
		(net 322)
	)
	(arc
		(start 123.133701 141.025)
		(mid 123.08098 141.152279)
		(end 122.953701 141.205)
		(width 0.155)
		(layer "In5.Cu")
		(net 322)
	)
	(segment
		(start 208.7 170.825)
		(end 209.025 170.5)
		(width 0.182)
		(layer "F.Cu")
		(net 323)
	)
	(segment
		(start 110.77 139.01)
		(end 110.98 138.8)
		(width 0.182)
		(layer "F.Cu")
		(net 323)
	)
	(segment
		(start 209.025 170.5)
		(end 209.025 168.685)
		(width 0.182)
		(layer "F.Cu")
		(net 323)
	)
	(segment
		(start 109.505 139.01)
		(end 110.77 139.01)
		(width 0.182)
		(layer "F.Cu")
		(net 323)
	)
	(segment
		(start 111.225648 138.404352)
		(end 113.36 138.404352)
		(width 0.182)
		(layer "F.Cu")
		(net 323)
	)
	(segment
		(start 110.98 138.8)
		(end 110.98 138.65)
		(width 0.182)
		(layer "F.Cu")
		(net 323)
	)
	(segment
		(start 110.98 138.65)
		(end 111.225648 138.404352)
		(width 0.182)
		(layer "F.Cu")
		(net 323)
	)
	(via
		(at 208.7 170.825)
		(size 0.45)
		(drill 0.1)
		(layers "F.Cu" "B.Cu")
		(teardrops
			(best_length_ratio 0.4)
			(max_length 1)
			(best_width_ratio 0.9)
			(max_width 2)
			(curved_edges yes)
			(filter_ratio 0.9)
			(enabled yes)
			(allow_two_segments yes)
			(prefer_zone_connections yes)
		)
		(net 323)
	)
	(via
		(at 165.325 163.7)
		(size 0.45)
		(drill 0.1)
		(layers "F.Cu" "B.Cu")
		(teardrops
			(best_length_ratio 0.4)
			(max_length 1)
			(best_width_ratio 0.9)
			(max_width 2)
			(curved_edges yes)
			(filter_ratio 0.9)
			(enabled yes)
			(allow_two_segments yes)
			(prefer_zone_connections yes)
		)
		(net 323)
	)
	(via
		(at 113.36 138.404352)
		(size 0.45)
		(drill 0.1)
		(layers "F.Cu" "B.Cu")
		(remove_unused_layers yes)
		(keep_end_layers yes)
		(zone_layer_connections "In5.Cu")
		(teardrops
			(best_length_ratio 0.4)
			(max_length 1)
			(best_width_ratio 0.9)
			(max_width 2)
			(curved_edges yes)
			(filter_ratio 0.9)
			(enabled yes)
			(allow_two_segments yes)
			(prefer_zone_connections yes)
		)
		(net 323)
	)
	(segment
		(start 165.325 163.7)
		(end 167.125 165.5)
		(width 0.155)
		(layer "In2.Cu")
		(net 323)
	)
	(segment
		(start 208.7 169.875)
		(end 208.7 170.825)
		(width 0.155)
		(layer "In2.Cu")
		(net 323)
	)
	(segment
		(start 169.15 165.5)
		(end 171.6125 167.9625)
		(width 0.155)
		(layer "In2.Cu")
		(net 323)
	)
	(segment
		(start 187.025 169.4)
		(end 208.225 169.4)
		(width 0.155)
		(layer "In2.Cu")
		(net 323)
	)
	(segment
		(start 171.6125 167.9625)
		(end 185.5875 167.9625)
		(width 0.155)
		(layer "In2.Cu")
		(net 323)
	)
	(segment
		(start 185.5875 167.9625)
		(end 187.025 169.4)
		(width 0.155)
		(layer "In2.Cu")
		(net 323)
	)
	(segment
		(start 208.225 169.4)
		(end 208.7 169.875)
		(width 0.155)
		(layer "In2.Cu")
		(net 323)
	)
	(segment
		(start 167.125 165.5)
		(end 169.15 165.5)
		(width 0.155)
		(layer "In2.Cu")
		(net 323)
	)
	(segment
		(start 114.554352 138.404352)
		(end 114.712995 138.562995)
		(width 0.155)
		(layer "In5.Cu")
		(net 323)
	)
	(segment
		(start 117.514325 141.364325)
		(end 117.905 141.755)
		(width 0.155)
		(layer "In5.Cu")
		(net 323)
	)
	(segment
		(start 116.003946 138.162996)
		(end 115.28575 138.881193)
		(width 0.155)
		(layer "In5.Cu")
		(net 323)
	)
	(segment
		(start 114.878676 139.924663)
		(end 115.476669 139.326669)
		(width 0.155)
		(layer "In5.Cu")
		(net 323)
	)
	(segment
		(start 116.113064 139.963064)
		(end 117.20603 138.870095)
		(width 0.155)
		(layer "In5.Cu")
		(net 323)
	)
	(segment
		(start 115.196873 140.497419)
		(end 115.260512 140.561058)
		(width 0.155)
		(layer "In5.Cu")
		(net 323)
	)
	(segment
		(start 115.476669 139.326669)
		(end 116.569635 138.2337)
		(width 0.155)
		(layer "In5.Cu")
		(net 323)
	)
	(segment
		(start 115.158472 139.008472)
		(end 114.560478 139.606465)
		(width 0.155)
		(layer "In5.Cu")
		(net 323)
	)
	(segment
		(start 113.36 138.404352)
		(end 114.554352 138.404352)
		(width 0.155)
		(layer "In5.Cu")
		(net 323)
	)
	(segment
		(start 164.5 162.875)
		(end 165.325 163.7)
		(width 0.155)
		(layer "In5.Cu")
		(net 323)
	)
	(segment
		(start 119.605 147.2)
		(end 121.645 149.24)
		(width 0.155)
		(layer "In5.Cu")
		(net 323)
	)
	(segment
		(start 115.794867 139.644867)
		(end 115.196873 140.24286)
		(width 0.155)
		(layer "In5.Cu")
		(net 323)
	)
	(segment
		(start 116.887833 138.551899)
		(end 115.794866 139.644867)
		(width 0.155)
		(layer "In5.Cu")
		(net 323)
	)
	(segment
		(start 153.15 153.75)
		(end 153.7 154.3)
		(width 0.155)
		(layer "In5.Cu")
		(net 323)
	)
	(segment
		(start 121.645 149.24)
		(end 126.245 149.24)
		(width 0.155)
		(layer "In5.Cu")
		(net 323)
	)
	(segment
		(start 161.125 162.875)
		(end 164.5 162.875)
		(width 0.155)
		(layer "In5.Cu")
		(net 323)
	)
	(segment
		(start 153.7 154.3)
		(end 153.7 158.75)
		(width 0.155)
		(layer "In5.Cu")
		(net 323)
	)
	(segment
		(start 116.151466 141.197453)
		(end 116.749459 140.599459)
		(width 0.155)
		(layer "In5.Cu")
		(net 323)
	)
	(segment
		(start 117.258574 141.108574)
		(end 117.514325 141.364325)
		(width 0.155)
		(layer "In5.Cu")
		(net 323)
	)
	(segment
		(start 142.155 153.75)
		(end 153.15 153.75)
		(width 0.155)
		(layer "In5.Cu")
		(net 323)
	)
	(segment
		(start 117.194935 141.044935)
		(end 117.258574 141.108574)
		(width 0.155)
		(layer "In5.Cu")
		(net 323)
	)
	(segment
		(start 116.749459 140.599459)
		(end 116.876737 140.472178)
		(width 0.155)
		(layer "In5.Cu")
		(net 323)
	)
	(segment
		(start 116.824195 138.233702)
		(end 116.887834 138.297341)
		(width 0.155)
		(layer "In5.Cu")
		(net 323)
	)
	(segment
		(start 126.245 149.24)
		(end 126.5575 149.5525)
		(width 0.155)
		(layer "In5.Cu")
		(net 323)
	)
	(segment
		(start 126.5575 149.5525)
		(end 137.0775 149.5525)
		(width 0.155)
		(layer "In5.Cu")
		(net 323)
	)
	(segment
		(start 116.431262 140.281262)
		(end 115.833268 140.879255)
		(width 0.155)
		(layer "In5.Cu")
		(net 323)
	)
	(segment
		(start 119.455 147.2)
		(end 119.605 147.2)
		(width 0.155)
		(layer "In5.Cu")
		(net 323)
	)
	(segment
		(start 116.431261 140.281262)
		(end 116.431262 140.281262)
		(width 0.155)
		(layer "In5.Cu")
		(net 323)
	)
	(segment
		(start 115.158471 139.008472)
		(end 115.158472 139.008472)
		(width 0.155)
		(layer "In5.Cu")
		(net 323)
	)
	(segment
		(start 114.967553 138.562995)
		(end 115.68575 137.844799)
		(width 0.155)
		(layer "In5.Cu")
		(net 323)
	)
	(segment
		(start 115.794866 139.644867)
		(end 115.794867 139.644867)
		(width 0.155)
		(layer "In5.Cu")
		(net 323)
	)
	(segment
		(start 118.026278 139.577198)
		(end 118.089917 139.640837)
		(width 0.155)
		(layer "In5.Cu")
		(net 323)
	)
	(segment
		(start 139.625 152.1)
		(end 140.505 152.1)
		(width 0.155)
		(layer "In5.Cu")
		(net 323)
	)
	(segment
		(start 157 162.05)
		(end 160.3 162.05)
		(width 0.155)
		(layer "In5.Cu")
		(net 323)
	)
	(segment
		(start 117.905 145.65)
		(end 119.455 147.2)
		(width 0.155)
		(layer "In5.Cu")
		(net 323)
	)
	(segment
		(start 117.46059 138.870097)
		(end 117.524229 138.933736)
		(width 0.155)
		(layer "In5.Cu")
		(net 323)
	)
	(segment
		(start 160.3 162.05)
		(end 161.125 162.875)
		(width 0.155)
		(layer "In5.Cu")
		(net 323)
	)
	(segment
		(start 115.940308 137.844799)
		(end 116.003947 137.908438)
		(width 0.155)
		(layer "In5.Cu")
		(net 323)
	)
	(segment
		(start 117.905 141.755)
		(end 117.905 145.65)
		(width 0.155)
		(layer "In5.Cu")
		(net 323)
	)
	(segment
		(start 140.505 152.1)
		(end 142.155 153.75)
		(width 0.155)
		(layer "In5.Cu")
		(net 323)
	)
	(segment
		(start 115.28575 138.881193)
		(end 115.158471 139.008472)
		(width 0.155)
		(layer "In5.Cu")
		(net 323)
	)
	(segment
		(start 117.524228 139.188294)
		(end 116.431261 140.281262)
		(width 0.155)
		(layer "In5.Cu")
		(net 323)
	)
	(segment
		(start 115.515071 140.561058)
		(end 116.113064 139.963064)
		(width 0.155)
		(layer "In5.Cu")
		(net 323)
	)
	(segment
		(start 115.833268 141.133814)
		(end 115.896907 141.197453)
		(width 0.155)
		(layer "In5.Cu")
		(net 323)
	)
	(segment
		(start 114.560478 139.861024)
		(end 114.624117 139.924663)
		(width 0.155)
		(layer "In5.Cu")
		(net 323)
	)
	(segment
		(start 118.089918 139.895397)
		(end 117.194935 140.790377)
		(width 0.155)
		(layer "In5.Cu")
		(net 323)
	)
	(segment
		(start 137.0775 149.5525)
		(end 139.625 152.1)
		(width 0.155)
		(layer "In5.Cu")
		(net 323)
	)
	(segment
		(start 116.876737 140.472178)
		(end 117.771718 139.577197)
		(width 0.155)
		(layer "In5.Cu")
		(net 323)
	)
	(segment
		(start 153.7 158.75)
		(end 157 162.05)
		(width 0.155)
		(layer "In5.Cu")
		(net 323)
	)
	(arc
		(start 118.089917 139.640837)
		(mid 118.142637 139.768117)
		(end 118.089918 139.895397)
		(width 0.155)
		(layer "In5.Cu")
		(net 323)
	)
	(arc
		(start 115.833268 140.879255)
		(mid 115.780547 141.006534)
		(end 115.833268 141.133814)
		(width 0.155)
		(layer "In5.Cu")
		(net 323)
	)
	(arc
		(start 115.896907 141.197453)
		(mid 116.024187 141.250173)
		(end 116.151466 141.197453)
		(width 0.155)
		(layer "In5.Cu")
		(net 323)
	)
	(arc
		(start 117.524229 138.933736)
		(mid 117.576949 139.061016)
		(end 117.524228 139.188294)
		(width 0.155)
		(layer "In5.Cu")
		(net 323)
	)
	(arc
		(start 116.569635 138.2337)
		(mid 116.696916 138.180981)
		(end 116.824195 138.233702)
		(width 0.155)
		(layer "In5.Cu")
		(net 323)
	)
	(arc
		(start 117.20603 138.870095)
		(mid 117.333311 138.817376)
		(end 117.46059 138.870097)
		(width 0.155)
		(layer "In5.Cu")
		(net 323)
	)
	(arc
		(start 116.887834 138.297341)
		(mid 116.940554 138.424621)
		(end 116.887833 138.551899)
		(width 0.155)
		(layer "In5.Cu")
		(net 323)
	)
	(arc
		(start 115.196873 140.24286)
		(mid 115.144152 140.370139)
		(end 115.196873 140.497419)
		(width 0.155)
		(layer "In5.Cu")
		(net 323)
	)
	(arc
		(start 114.624117 139.924663)
		(mid 114.751397 139.977383)
		(end 114.878676 139.924663)
		(width 0.155)
		(layer "In5.Cu")
		(net 323)
	)
	(arc
		(start 115.68575 137.844799)
		(mid 115.813029 137.792078)
		(end 115.940308 137.844799)
		(width 0.155)
		(layer "In5.Cu")
		(net 323)
	)
	(arc
		(start 116.003947 137.908438)
		(mid 116.056667 138.035718)
		(end 116.003946 138.162996)
		(width 0.155)
		(layer "In5.Cu")
		(net 323)
	)
	(arc
		(start 115.260512 140.561058)
		(mid 115.387792 140.613778)
		(end 115.515071 140.561058)
		(width 0.155)
		(layer "In5.Cu")
		(net 323)
	)
	(arc
		(start 117.194935 140.790377)
		(mid 117.142214 140.917656)
		(end 117.194935 141.044935)
		(width 0.155)
		(layer "In5.Cu")
		(net 323)
	)
	(arc
		(start 117.771718 139.577197)
		(mid 117.898999 139.524478)
		(end 118.026278 139.577198)
		(width 0.155)
		(layer "In5.Cu")
		(net 323)
	)
	(arc
		(start 114.560478 139.606465)
		(mid 114.507757 139.733744)
		(end 114.560478 139.861024)
		(width 0.155)
		(layer "In5.Cu")
		(net 323)
	)
	(arc
		(start 114.712995 138.562995)
		(mid 114.840274 138.615716)
		(end 114.967553 138.562995)
		(width 0.155)
		(layer "In5.Cu")
		(net 323)
	)
	(segment
		(start 270.1045 76.970566)
		(end 270.1045 142.470566)
		(width 0.202)
		(layer "F.Cu")
		(net 324)
	)
	(segment
		(start 297.699 73.41)
		(end 297.7545 73.3545)
		(width 0.202)
		(layer "F.Cu")
		(net 324)
	)
	(segment
		(start 297.7545 73.3545)
		(end 297.7545 72.429566)
		(width 0.202)
		(layer "F.Cu")
		(net 324)
	)
	(segment
		(start 297.699 74.035)
		(end 297.699 73.41)
		(width 0.202)
		(layer "F.Cu")
		(net 324)
	)
	(segment
		(start 228.1055 143.930566)
		(end 228.1055 143.5285)
		(width 0.202)
		(layer "F.Cu")
		(net 324)
	)
	(segment
		(start 228.1055 143.5285)
		(end 227.977 143.4)
		(width 0.202)
		(layer "F.Cu")
		(net 324)
	)
	(segment
		(start 277.880566 69.1945)
		(end 270.1045 76.970566)
		(width 0.202)
		(layer "F.Cu")
		(net 324)
	)
	(segment
		(start 211.0805 167.316999)
		(end 211.0805 167.124)
		(width 0.202)
		(layer "F.Cu")
		(net 324)
	)
	(segment
		(start 211.025 167.372499)
		(end 211.0805 167.316999)
		(width 0.202)
		(layer "F.Cu")
		(net 324)
	)
	(segment
		(start 297.7545 72.429566)
		(end 294.519434 69.1945)
		(width 0.202)
		(layer "F.Cu")
		(net 324)
	)
	(segment
		(start 211.0805 167.124)
		(end 210.9565 167)
		(width 0.202)
		(layer "F.Cu")
		(net 324)
	)
	(segment
		(start 228.619434 144.4445)
		(end 228.1055 143.930566)
		(width 0.202)
		(layer "F.Cu")
		(net 324)
	)
	(segment
		(start 294.519434 69.1945)
		(end 277.880566 69.1945)
		(width 0.202)
		(layer "F.Cu")
		(net 324)
	)
	(segment
		(start 268.130566 144.4445)
		(end 228.619434 144.4445)
		(width 0.202)
		(layer "F.Cu")
		(net 324)
	)
	(segment
		(start 211.025 168.685)
		(end 211.025 167.372499)
		(width 0.202)
		(layer "F.Cu")
		(net 324)
	)
	(segment
		(start 270.1045 142.470566)
		(end 268.130566 144.4445)
		(width 0.202)
		(layer "F.Cu")
		(net 324)
	)
	(via
		(at 210.9565 167)
		(size 0.45)
		(drill 0.1)
		(layers "F.Cu" "B.Cu")
		(teardrops
			(best_length_ratio 0.4)
			(max_length 1)
			(best_width_ratio 0.9)
			(max_width 2)
			(curved_edges yes)
			(filter_ratio 0.9)
			(enabled yes)
			(allow_two_segments yes)
			(prefer_zone_connections yes)
		)
		(net 324)
	)
	(via
		(at 227.977 143.4)
		(size 0.45)
		(drill 0.1)
		(layers "F.Cu" "B.Cu")
		(teardrops
			(best_length_ratio 0.4)
			(max_length 1)
			(best_width_ratio 0.9)
			(max_width 2)
			(curved_edges yes)
			(filter_ratio 0.9)
			(enabled yes)
			(allow_two_segments yes)
			(prefer_zone_connections yes)
		)
		(net 324)
	)
	(segment
		(start 219.722542 161.113)
		(end 220.922542 161.113)
		(width 0.178)
		(layer "In5.Cu")
		(net 324)
	)
	(segment
		(start 220.922542 161.113)
		(end 222.613 159.422542)
		(width 0.178)
		(layer "In5.Cu")
		(net 324)
	)
	(segment
		(start 211.088 166.8685)
		(end 211.088 166.047542)
		(width 0.178)
		(layer "In5.Cu")
		(net 324)
	)
	(segment
		(start 218.622542 162.213)
		(end 219.722542 161.113)
		(width 0.178)
		(layer "In5.Cu")
		(net 324)
	)
	(segment
		(start 211.088 166.047542)
		(end 212.813 164.322542)
		(width 0.178)
		(layer "In5.Cu")
		(net 324)
	)
	(segment
		(start 222.613 159.422542)
		(end 222.613 150.622542)
		(width 0.178)
		(layer "In5.Cu")
		(net 324)
	)
	(segment
		(start 222.613 150.622542)
		(end 228.113 145.122542)
		(width 0.178)
		(layer "In5.Cu")
		(net 324)
	)
	(segment
		(start 213.772542 162.213)
		(end 218.622542 162.213)
		(width 0.178)
		(layer "In5.Cu")
		(net 324)
	)
	(segment
		(start 212.813 164.322542)
		(end 212.813 163.172542)
		(width 0.178)
		(layer "In5.Cu")
		(net 324)
	)
	(segment
		(start 228.113 143.536)
		(end 227.977 143.4)
		(width 0.178)
		(layer "In5.Cu")
		(net 324)
	)
	(segment
		(start 210.9565 167)
		(end 211.088 166.8685)
		(width 0.178)
		(layer "In5.Cu")
		(net 324)
	)
	(segment
		(start 212.813 163.172542)
		(end 213.772542 162.213)
		(width 0.178)
		(layer "In5.Cu")
		(net 324)
	)
	(segment
		(start 228.113 145.122542)
		(end 228.113 143.536)
		(width 0.178)
		(layer "In5.Cu")
		(net 324)
	)
	(segment
		(start 298.1435 73.3545)
		(end 298.1435 72.268434)
		(width 0.202)
		(layer "F.Cu")
		(net 325)
	)
	(segment
		(start 228.4945 143.769434)
		(end 228.4945 143.5285)
		(width 0.202)
		(layer "F.Cu")
		(net 325)
	)
	(segment
		(start 298.199 73.41)
		(end 298.1435 73.3545)
		(width 0.202)
		(layer "F.Cu")
		(net 325)
	)
	(segment
		(start 211.525 167.372499)
		(end 211.4695 167.316999)
		(width 0.202)
		(layer "F.Cu")
		(net 325)
	)
	(segment
		(start 294.680566 68.8055)
		(end 277.719434 68.8055)
		(width 0.202)
		(layer "F.Cu")
		(net 325)
	)
	(segment
		(start 277.719434 68.8055)
		(end 269.7155 76.809434)
		(width 0.202)
		(layer "F.Cu")
		(net 325)
	)
	(segment
		(start 211.4695 167.124)
		(end 211.5935 167)
		(width 0.202)
		(layer "F.Cu")
		(net 325)
	)
	(segment
		(start 267.969434 144.0555)
		(end 228.780566 144.0555)
		(width 0.202)
		(layer "F.Cu")
		(net 325)
	)
	(segment
		(start 211.4695 167.316999)
		(end 211.4695 167.124)
		(width 0.202)
		(layer "F.Cu")
		(net 325)
	)
	(segment
		(start 269.7155 142.309434)
		(end 267.969434 144.0555)
		(width 0.202)
		(layer "F.Cu")
		(net 325)
	)
	(segment
		(start 211.525 168.685)
		(end 211.525 167.372499)
		(width 0.202)
		(layer "F.Cu")
		(net 325)
	)
	(segment
		(start 298.1435 72.268434)
		(end 294.680566 68.8055)
		(width 0.202)
		(layer "F.Cu")
		(net 325)
	)
	(segment
		(start 298.199 74.035)
		(end 298.199 73.41)
		(width 0.202)
		(layer "F.Cu")
		(net 325)
	)
	(segment
		(start 228.780566 144.0555)
		(end 228.4945 143.769434)
		(width 0.202)
		(layer "F.Cu")
		(net 325)
	)
	(segment
		(start 269.7155 76.809434)
		(end 269.7155 142.309434)
		(width 0.202)
		(layer "F.Cu")
		(net 325)
	)
	(segment
		(start 228.4945 143.5285)
		(end 228.623 143.4)
		(width 0.202)
		(layer "F.Cu")
		(net 325)
	)
	(via
		(at 211.5935 167)
		(size 0.45)
		(drill 0.1)
		(layers "F.Cu" "B.Cu")
		(teardrops
			(best_length_ratio 0.4)
			(max_length 1)
			(best_width_ratio 0.9)
			(max_width 2)
			(curved_edges yes)
			(filter_ratio 0.9)
			(enabled yes)
			(allow_two_segments yes)
			(prefer_zone_connections yes)
		)
		(net 325)
	)
	(via
		(at 228.623 143.4)
		(size 0.45)
		(drill 0.1)
		(layers "F.Cu" "B.Cu")
		(teardrops
			(best_length_ratio 0.4)
			(max_length 1)
			(best_width_ratio 0.9)
			(max_width 2)
			(curved_edges yes)
			(filter_ratio 0.9)
			(enabled yes)
			(allow_two_segments yes)
			(prefer_zone_connections yes)
		)
		(net 325)
	)
	(segment
		(start 222.987 150.777458)
		(end 228.487 145.277458)
		(width 0.178)
		(layer "In5.Cu")
		(net 325)
	)
	(segment
		(start 228.487 143.536)
		(end 228.623 143.4)
		(width 0.178)
		(layer "In5.Cu")
		(net 325)
	)
	(segment
		(start 222.987 159.577458)
		(end 222.987 150.777458)
		(width 0.178)
		(layer "In5.Cu")
		(net 325)
	)
	(segment
		(start 213.187 164.477458)
		(end 213.187 163.327458)
		(width 0.178)
		(layer "In5.Cu")
		(net 325)
	)
	(segment
		(start 213.187 163.327458)
		(end 213.927458 162.587)
		(width 0.178)
		(layer "In5.Cu")
		(net 325)
	)
	(segment
		(start 213.927458 162.587)
		(end 218.777458 162.587)
		(width 0.178)
		(layer "In5.Cu")
		(net 325)
	)
	(segment
		(start 211.462 166.202458)
		(end 213.187 164.477458)
		(width 0.178)
		(layer "In5.Cu")
		(net 325)
	)
	(segment
		(start 211.462 166.8685)
		(end 211.462 166.202458)
		(width 0.178)
		(layer "In5.Cu")
		(net 325)
	)
	(segment
		(start 221.077458 161.487)
		(end 222.987 159.577458)
		(width 0.178)
		(layer "In5.Cu")
		(net 325)
	)
	(segment
		(start 211.5935 167)
		(end 211.462 166.8685)
		(width 0.178)
		(layer "In5.Cu")
		(net 325)
	)
	(segment
		(start 219.877458 161.487)
		(end 221.077458 161.487)
		(width 0.178)
		(layer "In5.Cu")
		(net 325)
	)
	(segment
		(start 228.487 145.277458)
		(end 228.487 143.536)
		(width 0.178)
		(layer "In5.Cu")
		(net 325)
	)
	(segment
		(start 218.777458 162.587)
		(end 219.877458 161.487)
		(width 0.178)
		(layer "In5.Cu")
		(net 325)
	)
	(segment
		(start 268.980566 146.0945)
		(end 230.019434 146.0945)
		(width 0.202)
		(layer "F.Cu")
		(net 326)
	)
	(segment
		(start 271.6045 77.570566)
		(end 271.6045 143.470566)
		(width 0.202)
		(layer "F.Cu")
		(net 326)
	)
	(segment
		(start 294.699 73.41)
		(end 294.7545 73.3545)
		(width 0.202)
		(layer "F.Cu")
		(net 326)
	)
	(segment
		(start 212.525 168.685)
		(end 212.525 167.372499)
		(width 0.202)
		(layer "F.Cu")
		(net 326)
	)
	(segment
		(start 212.525 167.372499)
		(end 212.5805 167.316999)
		(width 0.202)
		(layer "F.Cu")
		(net 326)
	)
	(segment
		(start 229.4555 145.530566)
		(end 229.4555 145.124)
		(width 0.202)
		(layer "F.Cu")
		(net 326)
	)
	(segment
		(start 229.4555 145.124)
		(end 229.3315 145)
		(width 0.202)
		(layer "F.Cu")
		(net 326)
	)
	(segment
		(start 292.919434 70.2945)
		(end 278.880566 70.2945)
		(width 0.202)
		(layer "F.Cu")
		(net 326)
	)
	(segment
		(start 212.5805 167.316999)
		(end 212.5805 167.124)
		(width 0.202)
		(layer "F.Cu")
		(net 326)
	)
	(segment
		(start 271.6045 143.470566)
		(end 268.980566 146.0945)
		(width 0.202)
		(layer "F.Cu")
		(net 326)
	)
	(segment
		(start 212.5805 167.124)
		(end 212.4565 167)
		(width 0.202)
		(layer "F.Cu")
		(net 326)
	)
	(segment
		(start 294.7545 72.129566)
		(end 292.919434 70.2945)
		(width 0.202)
		(layer "F.Cu")
		(net 326)
	)
	(segment
		(start 230.019434 146.0945)
		(end 229.4555 145.530566)
		(width 0.202)
		(layer "F.Cu")
		(net 326)
	)
	(segment
		(start 294.7545 73.3545)
		(end 294.7545 72.129566)
		(width 0.202)
		(layer "F.Cu")
		(net 326)
	)
	(segment
		(start 294.699 74.035)
		(end 294.699 73.41)
		(width 0.202)
		(layer "F.Cu")
		(net 326)
	)
	(segment
		(start 278.880566 70.2945)
		(end 271.6045 77.570566)
		(width 0.202)
		(layer "F.Cu")
		(net 326)
	)
	(via
		(at 229.3315 145)
		(size 0.45)
		(drill 0.1)
		(layers "F.Cu" "B.Cu")
		(teardrops
			(best_length_ratio 0.4)
			(max_length 1)
			(best_width_ratio 0.9)
			(max_width 2)
			(curved_edges yes)
			(filter_ratio 0.9)
			(enabled yes)
			(allow_two_segments yes)
			(prefer_zone_connections yes)
		)
		(net 326)
	)
	(via
		(at 212.4565 167)
		(size 0.45)
		(drill 0.1)
		(layers "F.Cu" "B.Cu")
		(teardrops
			(best_length_ratio 0.4)
			(max_length 1)
			(best_width_ratio 0.9)
			(max_width 2)
			(curved_edges yes)
			(filter_ratio 0.9)
			(enabled yes)
			(allow_two_segments yes)
			(prefer_zone_connections yes)
		)
		(net 326)
	)
	(segment
		(start 224.313 159.922542)
		(end 220.972542 163.263)
		(width 0.178)
		(layer "In5.Cu")
		(net 326)
	)
	(segment
		(start 224.313 153.322542)
		(end 224.313 159.922542)
		(width 0.178)
		(layer "In5.Cu")
		(net 326)
	)
	(segment
		(start 229.463 145.1315)
		(end 229.463 145.722542)
		(width 0.178)
		(layer "In5.Cu")
		(net 326)
	)
	(segment
		(start 212.588 166.8685)
		(end 212.4565 167)
		(width 0.178)
		(layer "In5.Cu")
		(net 326)
	)
	(segment
		(start 229.463 145.722542)
		(end 225.813 149.372542)
		(width 0.178)
		(layer "In5.Cu")
		(net 326)
	)
	(segment
		(start 220.972542 163.263)
		(end 214.972542 163.263)
		(width 0.178)
		(layer "In5.Cu")
		(net 326)
	)
	(segment
		(start 214.972542 163.263)
		(end 214.513 163.722542)
		(width 0.178)
		(layer "In5.Cu")
		(net 326)
	)
	(segment
		(start 225.813 149.372542)
		(end 225.813 151.822542)
		(width 0.178)
		(layer "In5.Cu")
		(net 326)
	)
	(segment
		(start 229.3315 145)
		(end 229.463 145.1315)
		(width 0.178)
		(layer "In5.Cu")
		(net 326)
	)
	(segment
		(start 214.513 164.222542)
		(end 212.588 166.147542)
		(width 0.178)
		(layer "In5.Cu")
		(net 326)
	)
	(segment
		(start 212.588 166.147542)
		(end 212.588 166.8685)
		(width 0.178)
		(layer "In5.Cu")
		(net 326)
	)
	(segment
		(start 214.513 163.722542)
		(end 214.513 164.222542)
		(width 0.178)
		(layer "In5.Cu")
		(net 326)
	)
	(segment
		(start 225.813 151.822542)
		(end 224.313 153.322542)
		(width 0.178)
		(layer "In5.Cu")
		(net 326)
	)
	(segment
		(start 295.1435 73.3545)
		(end 295.1435 71.968434)
		(width 0.202)
		(layer "F.Cu")
		(net 327)
	)
	(segment
		(start 278.719434 69.9055)
		(end 271.2155 77.409434)
		(width 0.202)
		(layer "F.Cu")
		(net 327)
	)
	(segment
		(start 295.199 73.41)
		(end 295.1435 73.3545)
		(width 0.202)
		(layer "F.Cu")
		(net 327)
	)
	(segment
		(start 295.1435 71.968434)
		(end 293.080566 69.9055)
		(width 0.202)
		(layer "F.Cu")
		(net 327)
	)
	(segment
		(start 229.8445 145.369434)
		(end 229.8445 145.124)
		(width 0.202)
		(layer "F.Cu")
		(net 327)
	)
	(segment
		(start 212.9695 167.124)
		(end 213.0935 167)
		(width 0.202)
		(layer "F.Cu")
		(net 327)
	)
	(segment
		(start 293.080566 69.9055)
		(end 278.719434 69.9055)
		(width 0.202)
		(layer "F.Cu")
		(net 327)
	)
	(segment
		(start 268.819434 145.7055)
		(end 230.180566 145.7055)
		(width 0.202)
		(layer "F.Cu")
		(net 327)
	)
	(segment
		(start 230.180566 145.7055)
		(end 229.8445 145.369434)
		(width 0.202)
		(layer "F.Cu")
		(net 327)
	)
	(segment
		(start 213.025 168.685)
		(end 213.025 167.372499)
		(width 0.202)
		(layer "F.Cu")
		(net 327)
	)
	(segment
		(start 212.9695 167.316999)
		(end 212.9695 167.124)
		(width 0.202)
		(layer "F.Cu")
		(net 327)
	)
	(segment
		(start 271.2155 143.309434)
		(end 268.819434 145.7055)
		(width 0.202)
		(layer "F.Cu")
		(net 327)
	)
	(segment
		(start 213.025 167.372499)
		(end 212.9695 167.316999)
		(width 0.202)
		(layer "F.Cu")
		(net 327)
	)
	(segment
		(start 229.8445 145.124)
		(end 229.9685 145)
		(width 0.202)
		(layer "F.Cu")
		(net 327)
	)
	(segment
		(start 271.2155 77.409434)
		(end 271.2155 143.309434)
		(width 0.202)
		(layer "F.Cu")
		(net 327)
	)
	(segment
		(start 295.199 74.035)
		(end 295.199 73.41)
		(width 0.202)
		(layer "F.Cu")
		(net 327)
	)
	(via
		(at 213.0935 167)
		(size 0.45)
		(drill 0.1)
		(layers "F.Cu" "B.Cu")
		(teardrops
			(best_length_ratio 0.4)
			(max_length 1)
			(best_width_ratio 0.9)
			(max_width 2)
			(curved_edges yes)
			(filter_ratio 0.9)
			(enabled yes)
			(allow_two_segments yes)
			(prefer_zone_connections yes)
		)
		(net 327)
	)
	(via
		(at 229.9685 145)
		(size 0.45)
		(drill 0.1)
		(layers "F.Cu" "B.Cu")
		(teardrops
			(best_length_ratio 0.4)
			(max_length 1)
			(best_width_ratio 0.9)
			(max_width 2)
			(curved_edges yes)
			(filter_ratio 0.9)
			(enabled yes)
			(allow_two_segments yes)
			(prefer_zone_connections yes)
		)
		(net 327)
	)
	(segment
		(start 212.962 166.8685)
		(end 213.0935 167)
		(width 0.178)
		(layer "In5.Cu")
		(net 327)
	)
	(segment
		(start 229.837 145.1315)
		(end 229.837 145.877458)
		(width 0.178)
		(layer "In5.Cu")
		(net 327)
	)
	(segment
		(start 215.127458 163.637)
		(end 214.887 163.877458)
		(width 0.178)
		(layer "In5.Cu")
		(net 327)
	)
	(segment
		(start 212.962 166.302458)
		(end 212.962 166.8685)
		(width 0.178)
		(layer "In5.Cu")
		(net 327)
	)
	(segment
		(start 226.187 149.527458)
		(end 226.187 151.977458)
		(width 0.178)
		(layer "In5.Cu")
		(net 327)
	)
	(segment
		(start 221.127458 163.637)
		(end 215.127458 163.637)
		(width 0.178)
		(layer "In5.Cu")
		(net 327)
	)
	(segment
		(start 226.187 151.977458)
		(end 224.687 153.477458)
		(width 0.178)
		(layer "In5.Cu")
		(net 327)
	)
	(segment
		(start 214.887 164.377458)
		(end 212.962 166.302458)
		(width 0.178)
		(layer "In5.Cu")
		(net 327)
	)
	(segment
		(start 224.687 153.477458)
		(end 224.687 160.077458)
		(width 0.178)
		(layer "In5.Cu")
		(net 327)
	)
	(segment
		(start 229.837 145.877458)
		(end 226.187 149.527458)
		(width 0.178)
		(layer "In5.Cu")
		(net 327)
	)
	(segment
		(start 224.687 160.077458)
		(end 221.127458 163.637)
		(width 0.178)
		(layer "In5.Cu")
		(net 327)
	)
	(segment
		(start 214.887 163.877458)
		(end 214.887 164.377458)
		(width 0.178)
		(layer "In5.Cu")
		(net 327)
	)
	(segment
		(start 229.9685 145)
		(end 229.837 145.1315)
		(width 0.178)
		(layer "In5.Cu")
		(net 327)
	)
	(segment
		(start 230.7555 146.9285)
		(end 230.627 146.8)
		(width 0.202)
		(layer "F.Cu")
		(net 328)
	)
	(segment
		(start 291.7545 73.3545)
		(end 291.7545 72.129566)
		(width 0.202)
		(layer "F.Cu")
		(net 328)
	)
	(segment
		(start 273.1045 78.070566)
		(end 273.1045 144.770566)
		(width 0.202)
		(layer "F.Cu")
		(net 328)
	)
	(segment
		(start 214.0805 167.124)
		(end 213.9565 167)
		(width 0.202)
		(layer "F.Cu")
		(net 328)
	)
	(segment
		(start 291.119434 71.4945)
		(end 279.680566 71.4945)
		(width 0.202)
		(layer "F.Cu")
		(net 328)
	)
	(segment
		(start 291.699 73.41)
		(end 291.7545 73.3545)
		(width 0.202)
		(layer "F.Cu")
		(net 328)
	)
	(segment
		(start 232.630566 147.8945)
		(end 231.319434 147.8945)
		(width 0.202)
		(layer "F.Cu")
		(net 328)
	)
	(segment
		(start 230.7555 147.330566)
		(end 230.7555 146.9285)
		(width 0.202)
		(layer "F.Cu")
		(net 328)
	)
	(segment
		(start 214.025 167.372499)
		(end 214.0805 167.316999)
		(width 0.202)
		(layer "F.Cu")
		(net 328)
	)
	(segment
		(start 291.7545 72.129566)
		(end 291.119434 71.4945)
		(width 0.202)
		(layer "F.Cu")
		(net 328)
	)
	(segment
		(start 231.319434 147.8945)
		(end 230.7555 147.330566)
		(width 0.202)
		(layer "F.Cu")
		(net 328)
	)
	(segment
		(start 232.930566 147.5945)
		(end 232.630566 147.8945)
		(width 0.202)
		(layer "F.Cu")
		(net 328)
	)
	(segment
		(start 279.680566 71.4945)
		(end 273.1045 78.070566)
		(width 0.202)
		(layer "F.Cu")
		(net 328)
	)
	(segment
		(start 270.280566 147.5945)
		(end 232.930566 147.5945)
		(width 0.202)
		(layer "F.Cu")
		(net 328)
	)
	(segment
		(start 214.0805 167.316999)
		(end 214.0805 167.124)
		(width 0.202)
		(layer "F.Cu")
		(net 328)
	)
	(segment
		(start 291.699 74.035)
		(end 291.699 73.41)
		(width 0.202)
		(layer "F.Cu")
		(net 328)
	)
	(segment
		(start 214.025 168.685)
		(end 214.025 167.372499)
		(width 0.202)
		(layer "F.Cu")
		(net 328)
	)
	(segment
		(start 273.1045 144.770566)
		(end 270.280566 147.5945)
		(width 0.202)
		(layer "F.Cu")
		(net 328)
	)
	(via
		(at 213.9565 167)
		(size 0.45)
		(drill 0.1)
		(layers "F.Cu" "B.Cu")
		(teardrops
			(best_length_ratio 0.4)
			(max_length 1)
			(best_width_ratio 0.9)
			(max_width 2)
			(curved_edges yes)
			(filter_ratio 0.9)
			(enabled yes)
			(allow_two_segments yes)
			(prefer_zone_connections yes)
		)
		(net 328)
	)
	(via
		(at 230.627 146.8)
		(size 0.45)
		(drill 0.1)
		(layers "F.Cu" "B.Cu")
		(teardrops
			(best_length_ratio 0.4)
			(max_length 1)
			(best_width_ratio 0.9)
			(max_width 2)
			(curved_edges yes)
			(filter_ratio 0.9)
			(enabled yes)
			(allow_two_segments yes)
			(prefer_zone_connections yes)
		)
		(net 328)
	)
	(segment
		(start 226.113 160.822542)
		(end 226.113 154.722542)
		(width 0.178)
		(layer "In5.Cu")
		(net 328)
	)
	(segment
		(start 214.088 166.397542)
		(end 214.772542 165.713)
		(width 0.178)
		(layer "In5.Cu")
		(net 328)
	)
	(segment
		(start 227.713 153.122542)
		(end 227.713 150.422542)
		(width 0.178)
		(layer "In5.Cu")
		(net 328)
	)
	(segment
		(start 214.772542 165.713)
		(end 221.222542 165.713)
		(width 0.178)
		(layer "In5.Cu")
		(net 328)
	)
	(segment
		(start 227.713 150.422542)
		(end 230.763 147.372542)
		(width 0.178)
		(layer "In5.Cu")
		(net 328)
	)
	(segment
		(start 230.763 146.936)
		(end 230.627 146.8)
		(width 0.178)
		(layer "In5.Cu")
		(net 328)
	)
	(segment
		(start 214.088 166.8685)
		(end 214.088 166.397542)
		(width 0.178)
		(layer "In5.Cu")
		(net 328)
	)
	(segment
		(start 230.763 147.372542)
		(end 230.763 146.936)
		(width 0.178)
		(layer "In5.Cu")
		(net 328)
	)
	(segment
		(start 221.222542 165.713)
		(end 226.113 160.822542)
		(width 0.178)
		(layer "In5.Cu")
		(net 328)
	)
	(segment
		(start 226.113 154.722542)
		(end 227.713 153.122542)
		(width 0.178)
		(layer "In5.Cu")
		(net 328)
	)
	(segment
		(start 213.9565 167)
		(end 214.088 166.8685)
		(width 0.178)
		(layer "In5.Cu")
		(net 328)
	)
	(segment
		(start 231.1445 147.169434)
		(end 231.1445 146.9285)
		(width 0.202)
		(layer "F.Cu")
		(net 329)
	)
	(segment
		(start 231.1445 146.9285)
		(end 231.273 146.8)
		(width 0.202)
		(layer "F.Cu")
		(net 329)
	)
	(segment
		(start 270.119434 147.2055)
		(end 232.769434 147.2055)
		(width 0.202)
		(layer "F.Cu")
		(net 329)
	)
	(segment
		(start 232.469434 147.5055)
		(end 231.480566 147.5055)
		(width 0.202)
		(layer "F.Cu")
		(net 329)
	)
	(segment
		(start 292.199 74.035)
		(end 292.199 73.41)
		(width 0.202)
		(layer "F.Cu")
		(net 329)
	)
	(segment
		(start 292.1435 73.3545)
		(end 292.1435 71.968434)
		(width 0.202)
		(layer "F.Cu")
		(net 329)
	)
	(segment
		(start 292.1435 71.968434)
		(end 291.280566 71.1055)
		(width 0.202)
		(layer "F.Cu")
		(net 329)
	)
	(segment
		(start 231.480566 147.5055)
		(end 231.1445 147.169434)
		(width 0.202)
		(layer "F.Cu")
		(net 329)
	)
	(segment
		(start 214.4695 167.316999)
		(end 214.4695 167.124)
		(width 0.202)
		(layer "F.Cu")
		(net 329)
	)
	(segment
		(start 272.7155 77.909434)
		(end 272.7155 144.609434)
		(width 0.202)
		(layer "F.Cu")
		(net 329)
	)
	(segment
		(start 214.525 167.372499)
		(end 214.4695 167.316999)
		(width 0.202)
		(layer "F.Cu")
		(net 329)
	)
	(segment
		(start 214.525 168.685)
		(end 214.525 167.372499)
		(width 0.202)
		(layer "F.Cu")
		(net 329)
	)
	(segment
		(start 279.519434 71.1055)
		(end 272.7155 77.909434)
		(width 0.202)
		(layer "F.Cu")
		(net 329)
	)
	(segment
		(start 214.4695 167.124)
		(end 214.5935 167)
		(width 0.202)
		(layer "F.Cu")
		(net 329)
	)
	(segment
		(start 272.7155 144.609434)
		(end 270.119434 147.2055)
		(width 0.202)
		(layer "F.Cu")
		(net 329)
	)
	(segment
		(start 292.199 73.41)
		(end 292.1435 73.3545)
		(width 0.202)
		(layer "F.Cu")
		(net 329)
	)
	(segment
		(start 232.769434 147.2055)
		(end 232.469434 147.5055)
		(width 0.202)
		(layer "F.Cu")
		(net 329)
	)
	(segment
		(start 291.280566 71.1055)
		(end 279.519434 71.1055)
		(width 0.202)
		(layer "F.Cu")
		(net 329)
	)
	(via
		(at 231.273 146.8)
		(size 0.45)
		(drill 0.1)
		(layers "F.Cu" "B.Cu")
		(teardrops
			(best_length_ratio 0.4)
			(max_length 1)
			(best_width_ratio 0.9)
			(max_width 2)
			(curved_edges yes)
			(filter_ratio 0.9)
			(enabled yes)
			(allow_two_segments yes)
			(prefer_zone_connections yes)
		)
		(net 329)
	)
	(via
		(at 214.5935 167)
		(size 0.45)
		(drill 0.1)
		(layers "F.Cu" "B.Cu")
		(teardrops
			(best_length_ratio 0.4)
			(max_length 1)
			(best_width_ratio 0.9)
			(max_width 2)
			(curved_edges yes)
			(filter_ratio 0.9)
			(enabled yes)
			(allow_two_segments yes)
			(prefer_zone_connections yes)
		)
		(net 329)
	)
	(segment
		(start 214.5935 167)
		(end 214.462 166.8685)
		(width 0.178)
		(layer "In5.Cu")
		(net 329)
	)
	(segment
		(start 226.487 160.977458)
		(end 226.487 154.877458)
		(width 0.178)
		(layer "In5.Cu")
		(net 329)
	)
	(segment
		(start 228.087 150.577458)
		(end 231.137 147.527458)
		(width 0.178)
		(layer "In5.Cu")
		(net 329)
	)
	(segment
		(start 214.462 166.8685)
		(end 214.462 166.552458)
		(width 0.178)
		(layer "In5.Cu")
		(net 329)
	)
	(segment
		(start 228.087 153.277458)
		(end 228.087 150.577458)
		(width 0.178)
		(layer "In5.Cu")
		(net 329)
	)
	(segment
		(start 231.137 147.527458)
		(end 231.137 146.936)
		(width 0.178)
		(layer "In5.Cu")
		(net 329)
	)
	(segment
		(start 214.462 166.552458)
		(end 214.927458 166.087)
		(width 0.178)
		(layer "In5.Cu")
		(net 329)
	)
	(segment
		(start 226.487 154.877458)
		(end 228.087 153.277458)
		(width 0.178)
		(layer "In5.Cu")
		(net 329)
	)
	(segment
		(start 231.137 146.936)
		(end 231.273 146.8)
		(width 0.178)
		(layer "In5.Cu")
		(net 329)
	)
	(segment
		(start 214.927458 166.087)
		(end 221.377458 166.087)
		(width 0.178)
		(layer "In5.Cu")
		(net 329)
	)
	(segment
		(start 221.377458 166.087)
		(end 226.487 160.977458)
		(width 0.178)
		(layer "In5.Cu")
		(net 329)
	)
	(segment
		(start 288.419434 72.6945)
		(end 280.780566 72.6945)
		(width 0.202)
		(layer "F.Cu")
		(net 330)
	)
	(segment
		(start 233.0285 148.9945)
		(end 232.9 149.123)
		(width 0.202)
		(layer "F.Cu")
		(net 330)
	)
	(segment
		(start 216.025 167.372499)
		(end 216.0805 167.316999)
		(width 0.202)
		(layer "F.Cu")
		(net 330)
	)
	(segment
		(start 216.025 168.685)
		(end 216.025 167.372499)
		(width 0.202)
		(layer "F.Cu")
		(net 330)
	)
	(segment
		(start 288.7535 73.3545)
		(end 288.7535 73.028566)
		(width 0.202)
		(layer "F.Cu")
		(net 330)
	)
	(segment
		(start 216.0805 167.174)
		(end 215.9565 167.05)
		(width 0.202)
		(layer "F.Cu")
		(net 330)
	)
	(segment
		(start 288.7535 73.028566)
		(end 288.419434 72.6945)
		(width 0.202)
		(layer "F.Cu")
		(net 330)
	)
	(segment
		(start 288.698 74.035)
		(end 288.698 73.41)
		(width 0.202)
		(layer "F.Cu")
		(net 330)
	)
	(segment
		(start 274.6045 78.870566)
		(end 274.6045 146.670566)
		(width 0.202)
		(layer "F.Cu")
		(net 330)
	)
	(segment
		(start 272.280566 148.9945)
		(end 233.0285 148.9945)
		(width 0.202)
		(layer "F.Cu")
		(net 330)
	)
	(segment
		(start 274.6045 146.670566)
		(end 272.280566 148.9945)
		(width 0.202)
		(layer "F.Cu")
		(net 330)
	)
	(segment
		(start 280.780566 72.6945)
		(end 274.6045 78.870566)
		(width 0.202)
		(layer "F.Cu")
		(net 330)
	)
	(segment
		(start 216.0805 167.316999)
		(end 216.0805 167.174)
		(width 0.202)
		(layer "F.Cu")
		(net 330)
	)
	(segment
		(start 288.698 73.41)
		(end 288.7535 73.3545)
		(width 0.202)
		(layer "F.Cu")
		(net 330)
	)
	(via
		(at 232.9 149.123)
		(size 0.45)
		(drill 0.1)
		(layers "F.Cu" "B.Cu")
		(teardrops
			(best_length_ratio 0.4)
			(max_length 1)
			(best_width_ratio 0.9)
			(max_width 2)
			(curved_edges yes)
			(filter_ratio 0.9)
			(enabled yes)
			(allow_two_segments yes)
			(prefer_zone_connections yes)
		)
		(net 330)
	)
	(via
		(at 215.9565 167.05)
		(size 0.45)
		(drill 0.1)
		(layers "F.Cu" "B.Cu")
		(teardrops
			(best_length_ratio 0.4)
			(max_length 1)
			(best_width_ratio 0.9)
			(max_width 2)
			(curved_edges yes)
			(filter_ratio 0.9)
			(enabled yes)
			(allow_two_segments yes)
			(prefer_zone_connections yes)
		)
		(net 330)
	)
	(segment
		(start 232.027458 148.987)
		(end 229.587 151.427458)
		(width 0.178)
		(layer "In5.Cu")
		(net 330)
	)
	(segment
		(start 216.622542 168.787)
		(end 216.088 168.252458)
		(width 0.178)
		(layer "In5.Cu")
		(net 330)
	)
	(segment
		(start 232.9 149.123)
		(end 232.764 148.987)
		(width 0.178)
		(layer "In5.Cu")
		(net 330)
	)
	(segment
		(start 216.088 168.252458)
		(end 216.088 167.1815)
		(width 0.178)
		(layer "In5.Cu")
		(net 330)
	)
	(segment
		(start 216.088 167.1815)
		(end 215.9565 167.05)
		(width 0.178)
		(layer "In5.Cu")
		(net 330)
	)
	(segment
		(start 222.877458 168.787)
		(end 216.622542 168.787)
		(width 0.178)
		(layer "In5.Cu")
		(net 330)
	)
	(segment
		(start 229.587 151.427458)
		(end 229.587 162.077458)
		(width 0.178)
		(layer "In5.Cu")
		(net 330)
	)
	(segment
		(start 232.764 148.987)
		(end 232.027458 148.987)
		(width 0.178)
		(layer "In5.Cu")
		(net 330)
	)
	(segment
		(start 229.587 162.077458)
		(end 222.877458 168.787)
		(width 0.178)
		(layer "In5.Cu")
		(net 330)
	)
	(segment
		(start 233.0285 148.6055)
		(end 232.9 148.477)
		(width 0.202)
		(layer "F.Cu")
		(net 331)
	)
	(segment
		(start 289.1425 72.867434)
		(end 288.580566 72.3055)
		(width 0.202)
		(layer "F.Cu")
		(net 331)
	)
	(segment
		(start 289.198 74.035)
		(end 289.198 73.41)
		(width 0.202)
		(layer "F.Cu")
		(net 331)
	)
	(segment
		(start 280.619434 72.3055)
		(end 274.2155 78.709434)
		(width 0.202)
		(layer "F.Cu")
		(net 331)
	)
	(segment
		(start 216.4695 167.316999)
		(end 216.4695 167.174)
		(width 0.202)
		(layer "F.Cu")
		(net 331)
	)
	(segment
		(start 272.119434 148.6055)
		(end 233.0285 148.6055)
		(width 0.202)
		(layer "F.Cu")
		(net 331)
	)
	(segment
		(start 288.580566 72.3055)
		(end 280.619434 72.3055)
		(width 0.202)
		(layer "F.Cu")
		(net 331)
	)
	(segment
		(start 216.525 168.685)
		(end 216.525 167.372499)
		(width 0.202)
		(layer "F.Cu")
		(net 331)
	)
	(segment
		(start 216.4695 167.174)
		(end 216.5935 167.05)
		(width 0.202)
		(layer "F.Cu")
		(net 331)
	)
	(segment
		(start 289.198 73.41)
		(end 289.1425 73.3545)
		(width 0.202)
		(layer "F.Cu")
		(net 331)
	)
	(segment
		(start 216.525 167.372499)
		(end 216.4695 167.316999)
		(width 0.202)
		(layer "F.Cu")
		(net 331)
	)
	(segment
		(start 289.1425 73.3545)
		(end 289.1425 72.867434)
		(width 0.202)
		(layer "F.Cu")
		(net 331)
	)
	(segment
		(start 274.2155 78.709434)
		(end 274.2155 146.509434)
		(width 0.202)
		(layer "F.Cu")
		(net 331)
	)
	(segment
		(start 274.2155 146.509434)
		(end 272.119434 148.6055)
		(width 0.202)
		(layer "F.Cu")
		(net 331)
	)
	(via
		(at 216.5935 167.05)
		(size 0.45)
		(drill 0.1)
		(layers "F.Cu" "B.Cu")
		(teardrops
			(best_length_ratio 0.4)
			(max_length 1)
			(best_width_ratio 0.9)
			(max_width 2)
			(curved_edges yes)
			(filter_ratio 0.9)
			(enabled yes)
			(allow_two_segments yes)
			(prefer_zone_connections yes)
		)
		(net 331)
	)
	(via
		(at 232.9 148.477)
		(size 0.45)
		(drill 0.1)
		(layers "F.Cu" "B.Cu")
		(teardrops
			(best_length_ratio 0.4)
			(max_length 1)
			(best_width_ratio 0.9)
			(max_width 2)
			(curved_edges yes)
			(filter_ratio 0.9)
			(enabled yes)
			(allow_two_segments yes)
			(prefer_zone_connections yes)
		)
		(net 331)
	)
	(segment
		(start 229.213 161.922542)
		(end 222.722542 168.413)
		(width 0.178)
		(layer "In5.Cu")
		(net 331)
	)
	(segment
		(start 229.213 151.272542)
		(end 229.213 161.922542)
		(width 0.178)
		(layer "In5.Cu")
		(net 331)
	)
	(segment
		(start 231.872542 148.613)
		(end 229.213 151.272542)
		(width 0.178)
		(layer "In5.Cu")
		(net 331)
	)
	(segment
		(start 216.462 168.097542)
		(end 216.462 167.1815)
		(width 0.178)
		(layer "In5.Cu")
		(net 331)
	)
	(segment
		(start 232.9 148.477)
		(end 232.764 148.613)
		(width 0.178)
		(layer "In5.Cu")
		(net 331)
	)
	(segment
		(start 232.764 148.613)
		(end 231.872542 148.613)
		(width 0.178)
		(layer "In5.Cu")
		(net 331)
	)
	(segment
		(start 216.462 167.1815)
		(end 216.5935 167.05)
		(width 0.178)
		(layer "In5.Cu")
		(net 331)
	)
	(segment
		(start 216.777458 168.413)
		(end 216.462 168.097542)
		(width 0.178)
		(layer "In5.Cu")
		(net 331)
	)
	(segment
		(start 222.722542 168.413)
		(end 216.777458 168.413)
		(width 0.178)
		(layer "In5.Cu")
		(net 331)
	)
	(segment
		(start 218.025 169.875)
		(end 218 169.9)
		(width 0.182)
		(layer "F.Cu")
		(net 333)
	)
	(segment
		(start 111.28 137.4)
		(end 113.49 137.4)
		(width 0.182)
		(layer "F.Cu")
		(net 333)
	)
	(segment
		(start 218.025 168.685)
		(end 218.025 169.875)
		(width 0.182)
		(layer "F.Cu")
		(net 333)
	)
	(segment
		(start 110.77 137.91)
		(end 111.28 137.4)
		(width 0.182)
		(layer "F.Cu")
		(net 333)
	)
	(segment
		(start 109.505 137.91)
		(end 110.77 137.91)
		(width 0.182)
		(layer "F.Cu")
		(net 333)
	)
	(segment
		(start 113.49 137.4)
		(end 113.5 137.41)
		(width 0.182)
		(layer "F.Cu")
		(net 333)
	)
	(via
		(at 218 169.9)
		(size 0.45)
		(drill 0.1)
		(layers "F.Cu" "B.Cu")
		(teardrops
			(best_length_ratio 0.4)
			(max_length 1)
			(best_width_ratio 0.9)
			(max_width 2)
			(curved_edges yes)
			(filter_ratio 0.9)
			(enabled yes)
			(allow_two_segments yes)
			(prefer_zone_connections yes)
		)
		(net 333)
	)
	(via
		(at 113.5 137.41)
		(size 0.45)
		(drill 0.1)
		(layers "F.Cu" "B.Cu")
		(remove_unused_layers yes)
		(keep_end_layers yes)
		(zone_layer_connections "In5.Cu")
		(teardrops
			(best_length_ratio 0.4)
			(max_length 1)
			(best_width_ratio 0.9)
			(max_width 2)
			(curved_edges yes)
			(filter_ratio 0.9)
			(enabled yes)
			(allow_two_segments yes)
			(prefer_zone_connections yes)
		)
		(net 333)
	)
	(via
		(at 165.975 162.675)
		(size 0.45)
		(drill 0.1)
		(layers "F.Cu" "B.Cu")
		(teardrops
			(best_length_ratio 0.4)
			(max_length 1)
			(best_width_ratio 0.9)
			(max_width 2)
			(curved_edges yes)
			(filter_ratio 0.9)
			(enabled yes)
			(allow_two_segments yes)
			(prefer_zone_connections yes)
		)
		(net 333)
	)
	(segment
		(start 165.975 162.675)
		(end 166.3 163)
		(width 0.155)
		(layer "In2.Cu")
		(net 333)
	)
	(segment
		(start 217.1 169)
		(end 218 169.9)
		(width 0.155)
		(layer "In2.Cu")
		(net 333)
	)
	(segment
		(start 185.6 163)
		(end 190.9 168.3)
		(width 0.155)
		(layer "In2.Cu")
		(net 333)
	)
	(segment
		(start 190.9 168.3)
		(end 200.6 168.3)
		(width 0.155)
		(layer "In2.Cu")
		(net 333)
	)
	(segment
		(start 200.6 168.3)
		(end 201.3 169)
		(width 0.155)
		(layer "In2.Cu")
		(net 333)
	)
	(segment
		(start 201.3 169)
		(end 217.1 169)
		(width 0.155)
		(layer "In2.Cu")
		(net 333)
	)
	(segment
		(start 166.3 163)
		(end 185.6 163)
		(width 0.155)
		(layer "In2.Cu")
		(net 333)
	)
	(segment
		(start 154.65 153.95)
		(end 154.65 157.95)
		(width 0.155)
		(layer "In5.Cu")
		(net 333)
	)
	(segment
		(start 117.311 137.41)
		(end 118.43 138.529)
		(width 0.155)
		(layer "In5.Cu")
		(net 333)
	)
	(segment
		(start 129.408 148.45)
		(end 129.408 148.291956)
		(width 0.155)
		(layer "In5.Cu")
		(net 333)
	)
	(segment
		(start 157.25 160.55)
		(end 160.15 160.55)
		(width 0.155)
		(layer "In5.Cu")
		(net 333)
	)
	(segment
		(start 130.348 148.885357)
		(end 130.348 148.45)
		(width 0.155)
		(layer "In5.Cu")
		(net 333)
	)
	(segment
		(start 129.408 148.885357)
		(end 129.408 148.45)
		(width 0.155)
		(layer "In5.Cu")
		(net 333)
	)
	(segment
		(start 124.78 148)
		(end 127.45 148)
		(width 0.155)
		(layer "In5.Cu")
		(net 333)
	)
	(segment
		(start 164.35 162.05)
		(end 165 162.7)
		(width 0.155)
		(layer "In5.Cu")
		(net 333)
	)
	(segment
		(start 118.43 144.755)
		(end 121.925 148.25)
		(width 0.155)
		(layer "In5.Cu")
		(net 333)
	)
	(segment
		(start 132.228 148.885353)
		(end 132.228 148.45)
		(width 0.155)
		(layer "In5.Cu")
		(net 333)
	)
	(segment
		(start 137.968303 148.793303)
		(end 142.175 153)
		(width 0.155)
		(layer "In5.Cu")
		(net 333)
	)
	(segment
		(start 130.348 148.45)
		(end 130.348 148.263684)
		(width 0.155)
		(layer "In5.Cu")
		(net 333)
	)
	(segment
		(start 160.15 160.55)
		(end 161.65 162.05)
		(width 0.155)
		(layer "In5.Cu")
		(net 333)
	)
	(segment
		(start 124.53 148.25)
		(end 124.78 148)
		(width 0.155)
		(layer "In5.Cu")
		(net 333)
	)
	(segment
		(start 128.938 148.263941)
		(end 128.938 148.45)
		(width 0.155)
		(layer "In5.Cu")
		(net 333)
	)
	(segment
		(start 154.65 157.95)
		(end 157.25 160.55)
		(width 0.155)
		(layer "In5.Cu")
		(net 333)
	)
	(segment
		(start 133.168 148.45)
		(end 133.168 148.262)
		(width 0.155)
		(layer "In5.Cu")
		(net 333)
	)
	(segment
		(start 131.288 148.45)
		(end 131.288 148.291965)
		(width 0.155)
		(layer "In5.Cu")
		(net 333)
	)
	(segment
		(start 131.288 148.885353)
		(end 131.288 148.45)
		(width 0.155)
		(layer "In5.Cu")
		(net 333)
	)
	(segment
		(start 130.818 148.45)
		(end 130.818 148.885353)
		(width 0.155)
		(layer "In5.Cu")
		(net 333)
	)
	(segment
		(start 129.878 148.291956)
		(end 129.878 148.45)
		(width 0.155)
		(layer "In5.Cu")
		(net 333)
	)
	(segment
		(start 133.168 148.262)
		(end 133.168 148.114651)
		(width 0.155)
		(layer "In5.Cu")
		(net 333)
	)
	(segment
		(start 133.168 148.885351)
		(end 133.168 148.45)
		(width 0.155)
		(layer "In5.Cu")
		(net 333)
	)
	(segment
		(start 118.43 138.529)
		(end 118.43 144.755)
		(width 0.155)
		(layer "In5.Cu")
		(net 333)
	)
	(segment
		(start 133.826 148.45)
		(end 133.92 148.45)
		(width 0.155)
		(layer "In5.Cu")
		(net 333)
	)
	(segment
		(start 121.925 148.25)
		(end 124.53 148.25)
		(width 0.155)
		(layer "In5.Cu")
		(net 333)
	)
	(segment
		(start 132.414315 148.077369)
		(end 132.511685 148.077369)
		(width 0.155)
		(layer "In5.Cu")
		(net 333)
	)
	(segment
		(start 113.5 137.41)
		(end 117.311 137.41)
		(width 0.155)
		(layer "In5.Cu")
		(net 333)
	)
	(segment
		(start 129.566044 148.133912)
		(end 129.719956 148.133912)
		(width 0.155)
		(layer "In5.Cu")
		(net 333)
	)
	(segment
		(start 129.878 148.45)
		(end 129.878 148.885357)
		(width 0.155)
		(layer "In5.Cu")
		(net 333)
	)
	(segment
		(start 131.758 148.291965)
		(end 131.758 148.45)
		(width 0.155)
		(layer "In5.Cu")
		(net 333)
	)
	(segment
		(start 132.886 149.073351)
		(end 132.98 149.073351)
		(width 0.155)
		(layer "In5.Cu")
		(net 333)
	)
	(segment
		(start 133.92 148.45)
		(end 137.625 148.45)
		(width 0.155)
		(layer "In5.Cu")
		(net 333)
	)
	(segment
		(start 131.946 149.073353)
		(end 132.04 149.073353)
		(width 0.155)
		(layer "In5.Cu")
		(net 333)
	)
	(segment
		(start 132.698 148.45)
		(end 132.698 148.885351)
		(width 0.155)
		(layer "In5.Cu")
		(net 333)
	)
	(segment
		(start 132.228 148.45)
		(end 132.228 148.263684)
		(width 0.155)
		(layer "In5.Cu")
		(net 333)
	)
	(segment
		(start 130.818 148.263684)
		(end 130.818 148.45)
		(width 0.155)
		(layer "In5.Cu")
		(net 333)
	)
	(segment
		(start 128.938 148.45)
		(end 128.938 148.885357)
		(width 0.155)
		(layer "In5.Cu")
		(net 333)
	)
	(segment
		(start 131.446034 148.133931)
		(end 131.599966 148.133931)
		(width 0.155)
		(layer "In5.Cu")
		(net 333)
	)
	(segment
		(start 133.638 148.114651)
		(end 133.638 148.262)
		(width 0.155)
		(layer "In5.Cu")
		(net 333)
	)
	(segment
		(start 133.356 147.926651)
		(end 133.45 147.926651)
		(width 0.155)
		(layer "In5.Cu")
		(net 333)
	)
	(segment
		(start 132.698 148.263684)
		(end 132.698 148.45)
		(width 0.155)
		(layer "In5.Cu")
		(net 333)
	)
	(segment
		(start 161.65 162.05)
		(end 164.35 162.05)
		(width 0.155)
		(layer "In5.Cu")
		(net 333)
	)
	(segment
		(start 131.006 149.073353)
		(end 131.1 149.073353)
		(width 0.155)
		(layer "In5.Cu")
		(net 333)
	)
	(segment
		(start 131.758 148.45)
		(end 131.758 148.885353)
		(width 0.155)
		(layer "In5.Cu")
		(net 333)
	)
	(segment
		(start 137.625 148.45)
		(end 137.968303 148.793303)
		(width 0.155)
		(layer "In5.Cu")
		(net 333)
	)
	(segment
		(start 127.9 148.45)
		(end 128.28 148.45)
		(width 0.155)
		(layer "In5.Cu")
		(net 333)
	)
	(segment
		(start 130.066 149.073357)
		(end 130.16 149.073357)
		(width 0.155)
		(layer "In5.Cu")
		(net 333)
	)
	(segment
		(start 128.652118 148.077882)
		(end 128.751941 148.077882)
		(width 0.155)
		(layer "In5.Cu")
		(net 333)
	)
	(segment
		(start 165 162.7)
		(end 165.95 162.7)
		(width 0.155)
		(layer "In5.Cu")
		(net 333)
	)
	(segment
		(start 127.45 148)
		(end 127.9 148.45)
		(width 0.155)
		(layer "In5.Cu")
		(net 333)
	)
	(segment
		(start 165.95 162.7)
		(end 165.975 162.675)
		(width 0.155)
		(layer "In5.Cu")
		(net 333)
	)
	(segment
		(start 130.534315 148.077369)
		(end 130.631685 148.077369)
		(width 0.155)
		(layer "In5.Cu")
		(net 333)
	)
	(segment
		(start 142.175 153)
		(end 153.7 153)
		(width 0.155)
		(layer "In5.Cu")
		(net 333)
	)
	(segment
		(start 153.7 153)
		(end 154.65 153.95)
		(width 0.155)
		(layer "In5.Cu")
		(net 333)
	)
	(segment
		(start 129.126 149.073357)
		(end 129.22 149.073357)
		(width 0.155)
		(layer "In5.Cu")
		(net 333)
	)
	(arc
		(start 129.22 149.073357)
		(mid 129.352936 149.018293)
		(end 129.408 148.885357)
		(width 0.155)
		(layer "In5.Cu")
		(net 333)
	)
	(arc
		(start 132.511685 148.077369)
		(mid 132.64343 148.131939)
		(end 132.698 148.263684)
		(width 0.155)
		(layer "In5.Cu")
		(net 333)
	)
	(arc
		(start 131.288 148.291965)
		(mid 131.334287 148.180218)
		(end 131.446034 148.133931)
		(width 0.155)
		(layer "In5.Cu")
		(net 333)
	)
	(arc
		(start 130.348 148.263684)
		(mid 130.40257 148.131939)
		(end 130.534315 148.077369)
		(width 0.155)
		(layer "In5.Cu")
		(net 333)
	)
	(arc
		(start 133.168 148.114651)
		(mid 133.223064 147.981715)
		(end 133.356 147.926651)
		(width 0.155)
		(layer "In5.Cu")
		(net 333)
	)
	(arc
		(start 131.1 149.073353)
		(mid 131.232936 149.018289)
		(end 131.288 148.885353)
		(width 0.155)
		(layer "In5.Cu")
		(net 333)
	)
	(arc
		(start 130.16 149.073357)
		(mid 130.292936 149.018293)
		(end 130.348 148.885357)
		(width 0.155)
		(layer "In5.Cu")
		(net 333)
	)
	(arc
		(start 129.719956 148.133912)
		(mid 129.83171 148.180202)
		(end 129.878 148.291956)
		(width 0.155)
		(layer "In5.Cu")
		(net 333)
	)
	(arc
		(start 132.228 148.263684)
		(mid 132.28257 148.131939)
		(end 132.414315 148.077369)
		(width 0.155)
		(layer "In5.Cu")
		(net 333)
	)
	(arc
		(start 128.751941 148.077882)
		(mid 128.883505 148.132377)
		(end 128.938 148.263941)
		(width 0.155)
		(layer "In5.Cu")
		(net 333)
	)
	(arc
		(start 132.98 149.073351)
		(mid 133.112936 149.018287)
		(end 133.168 148.885351)
		(width 0.155)
		(layer "In5.Cu")
		(net 333)
	)
	(arc
		(start 129.878 148.885357)
		(mid 129.933064 149.018293)
		(end 130.066 149.073357)
		(width 0.155)
		(layer "In5.Cu")
		(net 333)
	)
	(arc
		(start 128.28 148.45)
		(mid 128.411564 148.395505)
		(end 128.466059 148.263941)
		(width 0.155)
		(layer "In5.Cu")
		(net 333)
	)
	(arc
		(start 132.04 149.073353)
		(mid 132.172936 149.018289)
		(end 132.228 148.885353)
		(width 0.155)
		(layer "In5.Cu")
		(net 333)
	)
	(arc
		(start 130.818 148.885353)
		(mid 130.873064 149.018289)
		(end 131.006 149.073353)
		(width 0.155)
		(layer "In5.Cu")
		(net 333)
	)
	(arc
		(start 133.638 148.262)
		(mid 133.693064 148.394936)
		(end 133.826 148.45)
		(width 0.155)
		(layer "In5.Cu")
		(net 333)
	)
	(arc
		(start 131.758 148.885353)
		(mid 131.813064 149.018289)
		(end 131.946 149.073353)
		(width 0.155)
		(layer "In5.Cu")
		(net 333)
	)
	(arc
		(start 128.938 148.885357)
		(mid 128.993064 149.018293)
		(end 129.126 149.073357)
		(width 0.155)
		(layer "In5.Cu")
		(net 333)
	)
	(arc
		(start 131.599966 148.133931)
		(mid 131.711713 148.180218)
		(end 131.758 148.291965)
		(width 0.155)
		(layer "In5.Cu")
		(net 333)
	)
	(arc
		(start 132.698 148.885351)
		(mid 132.753064 149.018287)
		(end 132.886 149.073351)
		(width 0.155)
		(layer "In5.Cu")
		(net 333)
	)
	(arc
		(start 130.631685 148.077369)
		(mid 130.76343 148.131939)
		(end 130.818 148.263684)
		(width 0.155)
		(layer "In5.Cu")
		(net 333)
	)
	(arc
		(start 129.408 148.291956)
		(mid 129.45429 148.180202)
		(end 129.566044 148.133912)
		(width 0.155)
		(layer "In5.Cu")
		(net 333)
	)
	(arc
		(start 133.45 147.926651)
		(mid 133.582936 147.981715)
		(end 133.638 148.114651)
		(width 0.155)
		(layer "In5.Cu")
		(net 333)
	)
	(arc
		(start 128.466059 148.263941)
		(mid 128.520554 148.132377)
		(end 128.652118 148.077882)
		(width 0.155)
		(layer "In5.Cu")
		(net 333)
	)
	(segment
		(start 215.4735 122.724)
		(end 215.5975 122.6)
		(width 0.202)
		(layer "F.Cu")
		(net 336)
	)
	(segment
		(start 219.5805 169.4655)
		(end 219.5805 169.876)
		(width 0.202)
		(layer "F.Cu")
		(net 336)
	)
	(segment
		(start 215.4735 125.681999)
		(end 215.4735 122.724)
		(width 0.202)
		(layer "F.Cu")
		(net 336)
	)
	(segment
		(start 215.478 126.249)
		(end 215.478 125.686499)
		(width 0.202)
		(layer "F.Cu")
		(net 336)
	)
	(segment
		(start 219.5805 169.876)
		(end 219.4565 170)
		(width 0.202)
		(layer "F.Cu")
		(net 336)
	)
	(segment
		(start 215.478 125.686499)
		(end 215.4735 125.681999)
		(width 0.202)
		(layer "F.Cu")
		(net 336)
	)
	(segment
		(start 219.525 169.41)
		(end 219.5805 169.4655)
		(width 0.202)
		(layer "F.Cu")
		(net 336)
	)
	(segment
		(start 219.525 168.685)
		(end 219.525 169.41)
		(width 0.202)
		(layer "F.Cu")
		(net 336)
	)
	(via
		(at 215.5975 122.6)
		(size 0.45)
		(drill 0.1)
		(layers "F.Cu" "B.Cu")
		(teardrops
			(best_length_ratio 0.4)
			(max_length 1)
			(best_width_ratio 0.9)
			(max_width 2)
			(curved_edges yes)
			(filter_ratio 0.9)
			(enabled yes)
			(allow_two_segments yes)
			(prefer_zone_connections yes)
		)
		(net 336)
	)
	(via
		(at 219.4565 170)
		(size 0.45)
		(drill 0.1)
		(layers "F.Cu" "B.Cu")
		(teardrops
			(best_length_ratio 0.4)
			(max_length 1)
			(best_width_ratio 0.9)
			(max_width 2)
			(curved_edges yes)
			(filter_ratio 0.9)
			(enabled yes)
			(allow_two_segments yes)
			(prefer_zone_connections yes)
		)
		(net 336)
	)
	(segment
		(start 219.588 170.347542)
		(end 219.588 170.1315)
		(width 0.178)
		(layer "In5.Cu")
		(net 336)
	)
	(segment
		(start 213.695259 169.570586)
		(end 213.765804 169.500038)
		(width 0.178)
		(layer "In5.Cu")
		(net 336)
	)
	(segment
		(start 215.5975 122.6)
		(end 215.466 122.7315)
		(width 0.178)
		(layer "In5.Cu")
		(net 336)
	)
	(segment
		(start 214.02602 169.500039)
		(end 214.091073 169.565092)
		(width 0.178)
		(layer "In5.Cu")
		(net 336)
	)
	(segment
		(start 214.091073 169.825308)
		(end 214.020525 169.895853)
		(width 0.178)
		(layer "In5.Cu")
		(net 336)
	)
	(segment
		(start 213.369989 169.505532)
		(end 213.435043 169.570585)
		(width 0.178)
		(layer "In5.Cu")
		(net 336)
	)
	(segment
		(start 210.477458 168.613)
		(end 212.477458 168.613)
		(width 0.178)
		(layer "In5.Cu")
		(net 336)
	)
	(segment
		(start 212.987 161.377458)
		(end 212.987 161.877458)
		(width 0.178)
		(layer "In5.Cu")
		(net 336)
	)
	(segment
		(start 214.020526 170.156069)
		(end 214.085581 170.221123)
		(width 0.178)
		(layer "In5.Cu")
		(net 336)
	)
	(segment
		(start 212.477458 168.613)
		(end 212.784505 168.920047)
		(width 0.178)
		(layer "In5.Cu")
		(net 336)
	)
	(segment
		(start 209.887 168.022542)
		(end 210.477458 168.613)
		(width 0.178)
		(layer "In5.Cu")
		(net 336)
	)
	(segment
		(start 214.232229 170.367771)
		(end 214.477458 170.613)
		(width 0.178)
		(layer "In5.Cu")
		(net 336)
	)
	(segment
		(start 219.322542 170.613)
		(end 219.588 170.347542)
		(width 0.178)
		(layer "In5.Cu")
		(net 336)
	)
	(segment
		(start 214.085581 170.221123)
		(end 214.232229 170.367771)
		(width 0.178)
		(layer "In5.Cu")
		(net 336)
	)
	(segment
		(start 214.477458 170.613)
		(end 219.322542 170.613)
		(width 0.178)
		(layer "In5.Cu")
		(net 336)
	)
	(segment
		(start 219.588 170.1315)
		(end 219.4565 170)
		(width 0.178)
		(layer "In5.Cu")
		(net 336)
	)
	(segment
		(start 213.375469 168.849513)
		(end 213.440522 168.914566)
		(width 0.178)
		(layer "In5.Cu")
		(net 336)
	)
	(segment
		(start 215.087 159.277458)
		(end 212.987 161.377458)
		(width 0.178)
		(layer "In5.Cu")
		(net 336)
	)
	(segment
		(start 212.987 161.877458)
		(end 211.377458 163.487)
		(width 0.178)
		(layer "In5.Cu")
		(net 336)
	)
	(segment
		(start 211.377458 163.487)
		(end 210.377458 163.487)
		(width 0.178)
		(layer "In5.Cu")
		(net 336)
	)
	(segment
		(start 215.087 127.377458)
		(end 215.087 159.277458)
		(width 0.178)
		(layer "In5.Cu")
		(net 336)
	)
	(segment
		(start 215.466 126.998458)
		(end 215.087 127.377458)
		(width 0.178)
		(layer "In5.Cu")
		(net 336)
	)
	(segment
		(start 209.887 163.977458)
		(end 209.887 168.022542)
		(width 0.178)
		(layer "In5.Cu")
		(net 336)
	)
	(segment
		(start 213.440522 169.174782)
		(end 213.369989 169.245316)
		(width 0.178)
		(layer "In5.Cu")
		(net 336)
	)
	(segment
		(start 215.466 122.7315)
		(end 215.466 126.998458)
		(width 0.178)
		(layer "In5.Cu")
		(net 336)
	)
	(segment
		(start 210.377458 163.487)
		(end 209.887 163.977458)
		(width 0.178)
		(layer "In5.Cu")
		(net 336)
	)
	(segment
		(start 213.044721 168.920048)
		(end 213.115253 168.849513)
		(width 0.178)
		(layer "In5.Cu")
		(net 336)
	)
	(arc
		(start 213.440522 168.914566)
		(mid 213.494414 169.044674)
		(end 213.440522 169.174782)
		(width 0.178)
		(layer "In5.Cu")
		(net 336)
	)
	(arc
		(start 213.369989 169.245316)
		(mid 213.316097 169.375424)
		(end 213.369989 169.505532)
		(width 0.178)
		(layer "In5.Cu")
		(net 336)
	)
	(arc
		(start 214.020525 169.895853)
		(mid 213.966634 170.025961)
		(end 214.020526 170.156069)
		(width 0.178)
		(layer "In5.Cu")
		(net 336)
	)
	(arc
		(start 212.784505 168.920047)
		(mid 212.914613 168.973939)
		(end 213.044721 168.920048)
		(width 0.178)
		(layer "In5.Cu")
		(net 336)
	)
	(arc
		(start 213.435043 169.570585)
		(mid 213.565151 169.624477)
		(end 213.695259 169.570586)
		(width 0.178)
		(layer "In5.Cu")
		(net 336)
	)
	(arc
		(start 214.091073 169.565092)
		(mid 214.144965 169.6952)
		(end 214.091073 169.825308)
		(width 0.178)
		(layer "In5.Cu")
		(net 336)
	)
	(arc
		(start 213.765804 169.500038)
		(mid 213.895912 169.446147)
		(end 214.02602 169.500039)
		(width 0.178)
		(layer "In5.Cu")
		(net 336)
	)
	(arc
		(start 213.115253 168.849513)
		(mid 213.245361 168.795621)
		(end 213.375469 168.849513)
		(width 0.178)
		(layer "In5.Cu")
		(net 336)
	)
	(segment
		(start 219.9695 169.876)
		(end 220.0935 170)
		(width 0.202)
		(layer "F.Cu")
		(net 337)
	)
	(segment
		(start 215.08 125.686499)
		(end 215.0845 125.681999)
		(width 0.202)
		(layer "F.Cu")
		(net 337)
	)
	(segment
		(start 220.025 168.685)
		(end 220.025 169.41)
		(width 0.202)
		(layer "F.Cu")
		(net 337)
	)
	(segment
		(start 215.08 126.249)
		(end 215.08 125.686499)
		(width 0.202)
		(layer "F.Cu")
		(net 337)
	)
	(segment
		(start 215.0845 125.681999)
		(end 215.0845 122.724)
		(width 0.202)
		(layer "F.Cu")
		(net 337)
	)
	(segment
		(start 219.9695 169.4655)
		(end 219.9695 169.876)
		(width 0.202)
		(layer "F.Cu")
		(net 337)
	)
	(segment
		(start 215.0845 122.724)
		(end 214.9605 122.6)
		(width 0.202)
		(layer "F.Cu")
		(net 337)
	)
	(segment
		(start 220.025 169.41)
		(end 219.9695 169.4655)
		(width 0.202)
		(layer "F.Cu")
		(net 337)
	)
	(via
		(at 220.0935 170)
		(size 0.45)
		(drill 0.1)
		(layers "F.Cu" "B.Cu")
		(teardrops
			(best_length_ratio 0.4)
			(max_length 1)
			(best_width_ratio 0.9)
			(max_width 2)
			(curved_edges yes)
			(filter_ratio 0.9)
			(enabled yes)
			(allow_two_segments yes)
			(prefer_zone_connections yes)
		)
		(net 337)
	)
	(via
		(at 214.9605 122.6)
		(size 0.45)
		(drill 0.1)
		(layers "F.Cu" "B.Cu")
		(teardrops
			(best_length_ratio 0.4)
			(max_length 1)
			(best_width_ratio 0.9)
			(max_width 2)
			(curved_edges yes)
			(filter_ratio 0.9)
			(enabled yes)
			(allow_two_segments yes)
			(prefer_zone_connections yes)
		)
		(net 337)
	)
	(segment
		(start 210.322542 168.987)
		(end 212.322542 168.987)
		(width 0.178)
		(layer "In5.Cu")
		(net 337)
	)
	(segment
		(start 212.613 161.722542)
		(end 211.222542 163.113)
		(width 0.178)
		(layer "In5.Cu")
		(net 337)
	)
	(segment
		(start 212.322542 168.987)
		(end 214.322542 170.987)
		(width 0.178)
		(layer "In5.Cu")
		(net 337)
	)
	(segment
		(start 211.222542 163.113)
		(end 210.222542 163.113)
		(width 0.178)
		(layer "In5.Cu")
		(net 337)
	)
	(segment
		(start 219.962 170.1315)
		(end 220.0935 170)
		(width 0.178)
		(layer "In5.Cu")
		(net 337)
	)
	(segment
		(start 214.322542 170.987)
		(end 219.477458 170.987)
		(width 0.178)
		(layer "In5.Cu")
		(net 337)
	)
	(segment
		(start 214.9605 122.6)
		(end 215.092 122.7315)
		(width 0.178)
		(layer "In5.Cu")
		(net 337)
	)
	(segment
		(start 210.222542 163.113)
		(end 209.513 163.822542)
		(width 0.178)
		(layer "In5.Cu")
		(net 337)
	)
	(segment
		(start 219.477458 170.987)
		(end 219.962 170.502458)
		(width 0.178)
		(layer "In5.Cu")
		(net 337)
	)
	(segment
		(start 214.713 127.222542)
		(end 214.713 159.122542)
		(width 0.178)
		(layer "In5.Cu")
		(net 337)
	)
	(segment
		(start 215.092 126.843542)
		(end 214.713 127.222542)
		(width 0.178)
		(layer "In5.Cu")
		(net 337)
	)
	(segment
		(start 209.513 168.177458)
		(end 210.322542 168.987)
		(width 0.178)
		(layer "In5.Cu")
		(net 337)
	)
	(segment
		(start 215.092 122.7315)
		(end 215.092 126.843542)
		(width 0.178)
		(layer "In5.Cu")
		(net 337)
	)
	(segment
		(start 219.962 170.502458)
		(end 219.962 170.1315)
		(width 0.178)
		(layer "In5.Cu")
		(net 337)
	)
	(segment
		(start 214.713 159.122542)
		(end 212.613 161.222542)
		(width 0.178)
		(layer "In5.Cu")
		(net 337)
	)
	(segment
		(start 209.513 163.822542)
		(end 209.513 168.177458)
		(width 0.178)
		(layer "In5.Cu")
		(net 337)
	)
	(segment
		(start 212.613 161.222542)
		(end 212.613 161.722542)
		(width 0.178)
		(layer "In5.Cu")
		(net 337)
	)
	(segment
		(start 221.525 168.685)
		(end 221.525 167.325)
		(width 0.125)
		(layer "F.Cu")
		(net 338)
	)
	(segment
		(start 257.415 162.565)
		(end 256.523145 162.565)
		(width 0.13)
		(layer "F.Cu")
		(net 338)
	)
	(segment
		(start 257.85 163)
		(end 257.415 162.565)
		(width 0.13)
		(layer "F.Cu")
		(net 338)
	)
	(segment
		(start 221.525 167.325)
		(end 221.5 167.3)
		(width 0.125)
		(layer "F.Cu")
		(net 338)
	)
	(via
		(at 221.5 167.3)
		(size 0.45)
		(drill 0.1)
		(layers "F.Cu" "B.Cu")
		(teardrops
			(best_length_ratio 0.4)
			(max_length 1)
			(best_width_ratio 0.9)
			(max_width 2)
			(curved_edges yes)
			(filter_ratio 0.9)
			(enabled yes)
			(allow_two_segments yes)
			(prefer_zone_connections yes)
		)
		(net 338)
	)
	(via
		(at 257.85 163)
		(size 0.45)
		(drill 0.1)
		(layers "F.Cu" "B.Cu")
		(teardrops
			(best_length_ratio 0.4)
			(max_length 1)
			(best_width_ratio 0.9)
			(max_width 2)
			(curved_edges yes)
			(filter_ratio 0.9)
			(enabled yes)
			(allow_two_segments yes)
			(prefer_zone_connections yes)
		)
		(net 338)
	)
	(segment
		(start 226.875 165.725)
		(end 227.8 164.8)
		(width 0.125)
		(layer "In2.Cu")
		(net 338)
	)
	(segment
		(start 246.2 159.1)
		(end 243.56 161.74)
		(width 0.13)
		(layer "In2.Cu")
		(net 338)
	)
	(segment
		(start 257.45 162.6)
		(end 252.6 162.6)
		(width 0.13)
		(layer "In2.Cu")
		(net 338)
	)
	(segment
		(start 249.1 159.1)
		(end 246.2 159.1)
		(width 0.13)
		(layer "In2.Cu")
		(net 338)
	)
	(segment
		(start 252.6 162.6)
		(end 249.1 159.1)
		(width 0.13)
		(layer "In2.Cu")
		(net 338)
	)
	(segment
		(start 221.5 167.3)
		(end 221.5 166.1)
		(width 0.13)
		(layer "In2.Cu")
		(net 338)
	)
	(segment
		(start 257.85 163)
		(end 257.45 162.6)
		(width 0.13)
		(layer "In2.Cu")
		(net 338)
	)
	(segment
		(start 221.5 166.1)
		(end 221.875 165.725)
		(width 0.13)
		(layer "In2.Cu")
		(net 338)
	)
	(segment
		(start 243.56 161.74)
		(end 230.86 161.74)
		(width 0.13)
		(layer "In2.Cu")
		(net 338)
	)
	(segment
		(start 230.86 161.74)
		(end 227.8 164.8)
		(width 0.13)
		(layer "In2.Cu")
		(net 338)
	)
	(segment
		(start 221.875 165.725)
		(end 226.875 165.725)
		(width 0.125)
		(layer "In2.Cu")
		(net 338)
	)
	(segment
		(start 222.025 168.685)
		(end 222.025 169.875)
		(width 0.182)
		(layer "F.Cu")
		(net 339)
	)
	(segment
		(start 222.025 169.875)
		(end 222 169.9)
		(width 0.182)
		(layer "F.Cu")
		(net 339)
	)
	(segment
		(start 111.03 133.65)
		(end 111.28 133.4)
		(width 0.182)
		(layer "F.Cu")
		(net 339)
	)
	(segment
		(start 110.87 134.61)
		(end 111.03 134.45)
		(width 0.182)
		(layer "F.Cu")
		(net 339)
	)
	(segment
		(start 111.03 134.45)
		(end 111.03 133.65)
		(width 0.182)
		(layer "F.Cu")
		(net 339)
	)
	(segment
		(start 109.505 134.61)
		(end 110.87 134.61)
		(width 0.182)
		(layer "F.Cu")
		(net 339)
	)
	(segment
		(start 111.28 133.4)
		(end 113.16 133.4)
		(width 0.182)
		(layer "F.Cu")
		(net 339)
	)
	(segment
		(start 113.16 133.4)
		(end 113.57 133.81)
		(width 0.182)
		(layer "F.Cu")
		(net 339)
	)
	(via
		(at 113.57 133.81)
		(size 0.45)
		(drill 0.1)
		(layers "F.Cu" "B.Cu")
		(remove_unused_layers yes)
		(keep_end_layers yes)
		(zone_layer_connections "In5.Cu")
		(teardrops
			(best_length_ratio 0.4)
			(max_length 1)
			(best_width_ratio 0.9)
			(max_width 2)
			(curved_edges yes)
			(filter_ratio 0.9)
			(enabled yes)
			(allow_two_segments yes)
			(prefer_zone_connections yes)
		)
		(net 339)
	)
	(via
		(at 166.4 160.9)
		(size 0.45)
		(drill 0.1)
		(layers "F.Cu" "B.Cu")
		(teardrops
			(best_length_ratio 0.4)
			(max_length 1)
			(best_width_ratio 0.9)
			(max_width 2)
			(curved_edges yes)
			(filter_ratio 0.9)
			(enabled yes)
			(allow_two_segments yes)
			(prefer_zone_connections yes)
		)
		(net 339)
	)
	(via
		(at 222 169.9)
		(size 0.45)
		(drill 0.1)
		(layers "F.Cu" "B.Cu")
		(teardrops
			(best_length_ratio 0.4)
			(max_length 1)
			(best_width_ratio 0.9)
			(max_width 2)
			(curved_edges yes)
			(filter_ratio 0.9)
			(enabled yes)
			(allow_two_segments yes)
			(prefer_zone_connections yes)
		)
		(net 339)
	)
	(segment
		(start 170.7 160.9)
		(end 171.5 161.7)
		(width 0.155)
		(layer "In2.Cu")
		(net 339)
	)
	(segment
		(start 188.05 162.9)
		(end 197.65 162.9)
		(width 0.155)
		(layer "In2.Cu")
		(net 339)
	)
	(segment
		(start 200.65 165.9)
		(end 200.65 167.55)
		(width 0.155)
		(layer "In2.Cu")
		(net 339)
	)
	(segment
		(start 186.35 161.2)
		(end 188.05 162.9)
		(width 0.155)
		(layer "In2.Cu")
		(net 339)
	)
	(segment
		(start 197.65 162.9)
		(end 200.65 165.9)
		(width 0.155)
		(layer "In2.Cu")
		(net 339)
	)
	(segment
		(start 174.7 161.7)
		(end 175.2 161.2)
		(width 0.155)
		(layer "In2.Cu")
		(net 339)
	)
	(segment
		(start 171.5 161.7)
		(end 174.7 161.7)
		(width 0.155)
		(layer "In2.Cu")
		(net 339)
	)
	(segment
		(start 175.2 161.2)
		(end 186.35 161.2)
		(width 0.155)
		(layer "In2.Cu")
		(net 339)
	)
	(segment
		(start 201.6 168.5)
		(end 220.6 168.5)
		(width 0.155)
		(layer "In2.Cu")
		(net 339)
	)
	(segment
		(start 220.6 168.5)
		(end 222 169.9)
		(width 0.155)
		(layer "In2.Cu")
		(net 339)
	)
	(segment
		(start 200.65 167.55)
		(end 201.6 168.5)
		(width 0.155)
		(layer "In2.Cu")
		(net 339)
	)
	(segment
		(start 166.4 160.9)
		(end 170.7 160.9)
		(width 0.155)
		(layer "In2.Cu")
		(net 339)
	)
	(segment
		(start 120.2 137.246)
		(end 120.2 143.75)
		(width 0.155)
		(layer "In5.Cu")
		(net 339)
	)
	(segment
		(start 139.105 146.35)
		(end 140 147.245)
		(width 0.155)
		(layer "In5.Cu")
		(net 339)
	)
	(segment
		(start 140 147.245)
		(end 140 149.025)
		(width 0.155)
		(layer "In5.Cu")
		(net 339)
	)
	(segment
		(start 156 152.9)
		(end 156 155.27)
		(width 0.155)
		(layer "In5.Cu")
		(net 339)
	)
	(segment
		(start 116.764 133.81)
		(end 120.2 137.246)
		(width 0.155)
		(layer "In5.Cu")
		(net 339)
	)
	(segment
		(start 122.8 146.35)
		(end 139.105 146.35)
		(width 0.155)
		(layer "In5.Cu")
		(net 339)
	)
	(segment
		(start 157 157.7)
		(end 157.8 158.5)
		(width 0.155)
		(layer "In5.Cu")
		(net 339)
	)
	(segment
		(start 160.7 158.5)
		(end 163 160.8)
		(width 0.155)
		(layer "In5.Cu")
		(net 339)
	)
	(segment
		(start 157 156.27)
		(end 157 157.7)
		(width 0.155)
		(layer "In5.Cu")
		(net 339)
	)
	(segment
		(start 163 160.8)
		(end 166.3 160.8)
		(width 0.155)
		(layer "In5.Cu")
		(net 339)
	)
	(segment
		(start 120.2 143.75)
		(end 122.8 146.35)
		(width 0.155)
		(layer "In5.Cu")
		(net 339)
	)
	(segment
		(start 156 155.27)
		(end 157 156.27)
		(width 0.155)
		(layer "In5.Cu")
		(net 339)
	)
	(segment
		(start 113.57 133.81)
		(end 116.764 133.81)
		(width 0.155)
		(layer "In5.Cu")
		(net 339)
	)
	(segment
		(start 166.3 160.8)
		(end 166.4 160.9)
		(width 0.155)
		(layer "In5.Cu")
		(net 339)
	)
	(segment
		(start 154.4 151.3)
		(end 156 152.9)
		(width 0.155)
		(layer "In5.Cu")
		(net 339)
	)
	(segment
		(start 142.275 151.3)
		(end 154.4 151.3)
		(width 0.155)
		(layer "In5.Cu")
		(net 339)
	)
	(segment
		(start 140 149.025)
		(end 142.275 151.3)
		(width 0.155)
		(layer "In5.Cu")
		(net 339)
	)
	(segment
		(start 157.8 158.5)
		(end 160.7 158.5)
		(width 0.155)
		(layer "In5.Cu")
		(net 339)
	)
	(segment
		(start 222.525 167.325)
		(end 222.5 167.3)
		(width 0.125)
		(layer "F.Cu")
		(net 340)
	)
	(segment
		(start 222.525 168.685)
		(end 222.525 167.325)
		(width 0.125)
		(layer "F.Cu")
		(net 340)
	)
	(segment
		(start 247.803 161.297)
		(end 247.8 161.3)
		(width 0.13)
		(layer "F.Cu")
		(net 340)
	)
	(segment
		(start 249.322145 161.297)
		(end 247.803 161.297)
		(width 0.13)
		(layer "F.Cu")
		(net 340)
	)
	(via
		(at 247.8 161.3)
		(size 0.45)
		(drill 0.1)
		(layers "F.Cu" "B.Cu")
		(teardrops
			(best_length_ratio 0.4)
			(max_length 1)
			(best_width_ratio 0.9)
			(max_width 2)
			(curved_edges yes)
			(filter_ratio 0.9)
			(enabled yes)
			(allow_two_segments yes)
			(prefer_zone_connections yes)
		)
		(net 340)
	)
	(via
		(at 222.5 167.3)
		(size 0.45)
		(drill 0.1)
		(layers "F.Cu" "B.Cu")
		(teardrops
			(best_length_ratio 0.4)
			(max_length 1)
			(best_width_ratio 0.9)
			(max_width 2)
			(curved_edges yes)
			(filter_ratio 0.9)
			(enabled yes)
			(allow_two_segments yes)
			(prefer_zone_connections yes)
		)
		(net 340)
	)
	(segment
		(start 222.9 166.2)
		(end 227.5 166.2)
		(width 0.13)
		(layer "In2.Cu")
		(net 340)
	)
	(segment
		(start 248.3 159.4)
		(end 248.5 159.6)
		(width 0.13)
		(layer "In2.Cu")
		(net 340)
	)
	(segment
		(start 231.5 162.2)
		(end 244.1 162.2)
		(width 0.13)
		(layer "In2.Cu")
		(net 340)
	)
	(segment
		(start 246.9 159.4)
		(end 248.3 159.4)
		(width 0.13)
		(layer "In2.Cu")
		(net 340)
	)
	(segment
		(start 227.5 166.2)
		(end 231.5 162.2)
		(width 0.13)
		(layer "In2.Cu")
		(net 340)
	)
	(segment
		(start 244.1 162.2)
		(end 246.9 159.4)
		(width 0.13)
		(layer "In2.Cu")
		(net 340)
	)
	(segment
		(start 222.5 167.3)
		(end 222.5 166.6)
		(width 0.13)
		(layer "In2.Cu")
		(net 340)
	)
	(segment
		(start 222.5 166.6)
		(end 222.9 166.2)
		(width 0.13)
		(layer "In2.Cu")
		(net 340)
	)
	(segment
		(start 248.5 159.6)
		(end 248.5 160.6)
		(width 0.13)
		(layer "In2.Cu")
		(net 340)
	)
	(segment
		(start 248.5 160.6)
		(end 247.8 161.3)
		(width 0.13)
		(layer "In2.Cu")
		(net 340)
	)
	(segment
		(start 249.296145 160)
		(end 249.322145 160.026)
		(width 0.13)
		(layer "F.Cu")
		(net 341)
	)
	(segment
		(start 223.025 168.685)
		(end 223.025 166.925)
		(width 0.125)
		(layer "F.Cu")
		(net 341)
	)
	(segment
		(start 247.5 160)
		(end 249.296145 160)
		(width 0.13)
		(layer "F.Cu")
		(net 341)
	)
	(segment
		(start 223.025 166.925)
		(end 223 166.9)
		(width 0.125)
		(layer "F.Cu")
		(net 341)
	)
	(via
		(at 247.5 160)
		(size 0.45)
		(drill 0.1)
		(layers "F.Cu" "B.Cu")
		(teardrops
			(best_length_ratio 0.4)
			(max_length 1)
			(best_width_ratio 0.9)
			(max_width 2)
			(curved_edges yes)
			(filter_ratio 0.9)
			(enabled yes)
			(allow_two_segments yes)
			(prefer_zone_connections yes)
		)
		(net 341)
	)
	(via
		(at 223 166.9)
		(size 0.45)
		(drill 0.1)
		(layers "F.Cu" "B.Cu")
		(teardrops
			(best_length_ratio 0.4)
			(max_length 1)
			(best_width_ratio 0.9)
			(max_width 2)
			(curved_edges yes)
			(filter_ratio 0.9)
			(enabled yes)
			(allow_two_segments yes)
			(prefer_zone_connections yes)
		)
		(net 341)
	)
	(segment
		(start 227.8 166.9)
		(end 232 162.7)
		(width 0.13)
		(layer "In2.Cu")
		(net 341)
	)
	(segment
		(start 223 166.9)
		(end 227.8 166.9)
		(width 0.13)
		(layer "In2.Cu")
		(net 341)
	)
	(segment
		(start 244.8 162.7)
		(end 247.5 160)
		(width 0.13)
		(layer "In2.Cu")
		(net 341)
	)
	(segment
		(start 232 162.7)
		(end 244.8 162.7)
		(width 0.13)
		(layer "In2.Cu")
		(net 341)
	)
	(segment
		(start 223.525 168.685)
		(end 223.525 165.575)
		(width 0.125)
		(layer "F.Cu")
		(net 342)
	)
	(segment
		(start 223.525 165.575)
		(end 223.2 165.25)
		(width 0.125)
		(layer "F.Cu")
		(net 342)
	)
	(via
		(at 223.2 165.25)
		(size 0.45)
		(drill 0.1)
		(layers "F.Cu" "B.Cu")
		(teardrops
			(best_length_ratio 0.4)
			(max_length 1)
			(best_width_ratio 0.9)
			(max_width 2)
			(curved_edges yes)
			(filter_ratio 0.9)
			(enabled yes)
			(allow_two_segments yes)
			(prefer_zone_connections yes)
		)
		(net 342)
	)
	(segment
		(start 224.025 168.685)
		(end 224.025 165.625)
		(width 0.125)
		(layer "F.Cu")
		(net 343)
	)
	(segment
		(start 224.025 165.625)
		(end 224.4 165.25)
		(width 0.125)
		(layer "F.Cu")
		(net 343)
	)
	(via
		(at 224.4 165.25)
		(size 0.45)
		(drill 0.1)
		(layers "F.Cu" "B.Cu")
		(teardrops
			(best_length_ratio 0.4)
			(max_length 1)
			(best_width_ratio 0.9)
			(max_width 2)
			(curved_edges yes)
			(filter_ratio 0.9)
			(enabled yes)
			(allow_two_segments yes)
			(prefer_zone_connections yes)
		)
		(net 343)
	)
	(segment
		(start 141.2 81.81)
		(end 141.2 89.16)
		(width 0.125)
		(layer "F.Cu")
		(net 344)
	)
	(segment
		(start 124.4 77.08)
		(end 126.53 79.21)
		(width 0.125)
		(layer "F.Cu")
		(net 344)
	)
	(segment
		(start 145.745 93.705)
		(end 151.605 93.705)
		(width 0.125)
		(layer "F.Cu")
		(net 344)
	)
	(segment
		(start 151.605 93.705)
		(end 163.8 105.9)
		(width 0.125)
		(layer "F.Cu")
		(net 344)
	)
	(segment
		(start 141.2 89.16)
		(end 145.745 93.705)
		(width 0.125)
		(layer "F.Cu")
		(net 344)
	)
	(segment
		(start 126.53 79.21)
		(end 138.6 79.21)
		(width 0.125)
		(layer "F.Cu")
		(net 344)
	)
	(segment
		(start 224.525 168.685)
		(end 224.525 169.975)
		(width 0.125)
		(layer "F.Cu")
		(net 344)
	)
	(segment
		(start 124.4 76.29)
		(end 124.4 77.08)
		(width 0.125)
		(layer "F.Cu")
		(net 344)
	)
	(segment
		(start 138.6 79.21)
		(end 141.2 81.81)
		(width 0.125)
		(layer "F.Cu")
		(net 344)
	)
	(segment
		(start 224.525 169.975)
		(end 224.2 170.3)
		(width 0.125)
		(layer "F.Cu")
		(net 344)
	)
	(via
		(at 224.2 170.3)
		(size 0.45)
		(drill 0.1)
		(layers "F.Cu" "B.Cu")
		(teardrops
			(best_length_ratio 0.4)
			(max_length 1)
			(best_width_ratio 0.9)
			(max_width 2)
			(curved_edges yes)
			(filter_ratio 0.9)
			(enabled yes)
			(allow_two_segments yes)
			(prefer_zone_connections yes)
		)
		(net 344)
	)
	(via
		(at 216.7 145.25)
		(size 0.45)
		(drill 0.1)
		(layers "F.Cu" "B.Cu")
		(teardrops
			(best_length_ratio 0.4)
			(max_length 1)
			(best_width_ratio 0.9)
			(max_width 2)
			(curved_edges yes)
			(filter_ratio 0.9)
			(enabled yes)
			(allow_two_segments yes)
			(prefer_zone_connections yes)
		)
		(net 344)
	)
	(via
		(at 163.8 105.9)
		(size 0.45)
		(drill 0.1)
		(layers "F.Cu" "B.Cu")
		(teardrops
			(best_length_ratio 0.4)
			(max_length 1)
			(best_width_ratio 0.9)
			(max_width 2)
			(curved_edges yes)
			(filter_ratio 0.9)
			(enabled yes)
			(allow_two_segments yes)
			(prefer_zone_connections yes)
		)
		(net 344)
	)
	(segment
		(start 204.8 132.8)
		(end 202.55 130.55)
		(width 0.125)
		(layer "In2.Cu")
		(net 344)
	)
	(segment
		(start 200.7 120.1)
		(end 178 120.1)
		(width 0.125)
		(layer "In2.Cu")
		(net 344)
	)
	(segment
		(start 214.5 136.35)
		(end 210.95 132.8)
		(width 0.125)
		(layer "In2.Cu")
		(net 344)
	)
	(segment
		(start 202.55 121.95)
		(end 200.7 120.1)
		(width 0.125)
		(layer "In2.Cu")
		(net 344)
	)
	(segment
		(start 178 120.1)
		(end 163.8 105.9)
		(width 0.125)
		(layer "In2.Cu")
		(net 344)
	)
	(segment
		(start 214.5 143.05)
		(end 214.5 136.35)
		(width 0.125)
		(layer "In2.Cu")
		(net 344)
	)
	(segment
		(start 202.55 130.55)
		(end 202.55 121.95)
		(width 0.125)
		(layer "In2.Cu")
		(net 344)
	)
	(segment
		(start 210.95 132.8)
		(end 204.8 132.8)
		(width 0.125)
		(layer "In2.Cu")
		(net 344)
	)
	(segment
		(start 216.7 145.25)
		(end 214.5 143.05)
		(width 0.125)
		(layer "In2.Cu")
		(net 344)
	)
	(segment
		(start 231 142.4)
		(end 235.65 147.05)
		(width 0.125)
		(layer "In5.Cu")
		(net 344)
	)
	(segment
		(start 216.7 145.25)
		(end 216.85 145.4)
		(width 0.125)
		(layer "In5.Cu")
		(net 344)
	)
	(segment
		(start 226.2 142.4)
		(end 231 142.4)
		(width 0.125)
		(layer "In5.Cu")
		(net 344)
	)
	(segment
		(start 223.2 145.4)
		(end 226.2 142.4)
		(width 0.125)
		(layer "In5.Cu")
		(net 344)
	)
	(segment
		(start 224.2 169.65)
		(end 224.2 170.3)
		(width 0.125)
		(layer "In5.Cu")
		(net 344)
	)
	(segment
		(start 235.65 158.2)
		(end 224.2 169.65)
		(width 0.125)
		(layer "In5.Cu")
		(net 344)
	)
	(segment
		(start 235.65 147.05)
		(end 235.65 158.2)
		(width 0.125)
		(layer "In5.Cu")
		(net 344)
	)
	(segment
		(start 216.85 145.4)
		(end 223.2 145.4)
		(width 0.125)
		(layer "In5.Cu")
		(net 344)
	)
	(segment
		(start 138.19 79.97)
		(end 126.22 79.97)
		(width 0.125)
		(layer "F.Cu")
		(net 345)
	)
	(segment
		(start 140.46 89.55)
		(end 140.46 82.24)
		(width 0.125)
		(layer "F.Cu")
		(net 345)
	)
	(segment
		(start 225.025 168.685)
		(end 225.025 169.975)
		(width 0.125)
		(layer "F.Cu")
		(net 345)
	)
	(segment
		(start 123.38 77.13)
		(end 123.38 76.29)
		(width 0.125)
		(layer "F.Cu")
		(net 345)
	)
	(segment
		(start 151.06 94.36)
		(end 163.6 106.9)
		(width 0.125)
		(layer "F.Cu")
		(net 345)
	)
	(segment
		(start 145.27 94.36)
		(end 151.06 94.36)
		(width 0.125)
		(layer "F.Cu")
		(net 345)
	)
	(segment
		(start 145.27 94.36)
		(end 140.46 89.55)
		(width 0.125)
		(layer "F.Cu")
		(net 345)
	)
	(segment
		(start 225.025 169.975)
		(end 225.35 170.3)
		(width 0.125)
		(layer "F.Cu")
		(net 345)
	)
	(segment
		(start 140.46 82.24)
		(end 138.19 79.97)
		(width 0.125)
		(layer "F.Cu")
		(net 345)
	)
	(segment
		(start 126.22 79.97)
		(end 123.38 77.13)
		(width 0.125)
		(layer "F.Cu")
		(net 345)
	)
	(via
		(at 225.35 170.3)
		(size 0.45)
		(drill 0.1)
		(layers "F.Cu" "B.Cu")
		(teardrops
			(best_length_ratio 0.4)
			(max_length 1)
			(best_width_ratio 0.9)
			(max_width 2)
			(curved_edges yes)
			(filter_ratio 0.9)
			(enabled yes)
			(allow_two_segments yes)
			(prefer_zone_connections yes)
		)
		(net 345)
	)
	(via
		(at 163.6 106.9)
		(size 0.45)
		(drill 0.1)
		(layers "F.Cu" "B.Cu")
		(teardrops
			(best_length_ratio 0.4)
			(max_length 1)
			(best_width_ratio 0.9)
			(max_width 2)
			(curved_edges yes)
			(filter_ratio 0.9)
			(enabled yes)
			(allow_two_segments yes)
			(prefer_zone_connections yes)
		)
		(net 345)
	)
	(via
		(at 216 146.2)
		(size 0.45)
		(drill 0.1)
		(layers "F.Cu" "B.Cu")
		(teardrops
			(best_length_ratio 0.4)
			(max_length 1)
			(best_width_ratio 0.9)
			(max_width 2)
			(curved_edges yes)
			(filter_ratio 0.9)
			(enabled yes)
			(allow_two_segments yes)
			(prefer_zone_connections yes)
		)
		(net 345)
	)
	(segment
		(start 216 146.2)
		(end 214.45 146.2)
		(width 0.125)
		(layer "In2.Cu")
		(net 345)
	)
	(segment
		(start 203.65 133.25)
		(end 201.8 131.4)
		(width 0.125)
		(layer "In2.Cu")
		(net 345)
	)
	(segment
		(start 200.425 120.875)
		(end 177.575 120.875)
		(width 0.125)
		(layer "In2.Cu")
		(net 345)
	)
	(segment
		(start 213.6 145.35)
		(end 213.6 135.9)
		(width 0.125)
		(layer "In2.Cu")
		(net 345)
	)
	(segment
		(start 201.8 131.4)
		(end 201.8 122.25)
		(width 0.125)
		(layer "In2.Cu")
		(net 345)
	)
	(segment
		(start 213.6 135.9)
		(end 210.95 133.25)
		(width 0.125)
		(layer "In2.Cu")
		(net 345)
	)
	(segment
		(start 210.95 133.25)
		(end 203.65 133.25)
		(width 0.125)
		(layer "In2.Cu")
		(net 345)
	)
	(segment
		(start 201.8 122.25)
		(end 200.425 120.875)
		(width 0.125)
		(layer "In2.Cu")
		(net 345)
	)
	(segment
		(start 214.45 146.2)
		(end 213.6 145.35)
		(width 0.125)
		(layer "In2.Cu")
		(net 345)
	)
	(segment
		(start 177.575 120.875)
		(end 163.6 106.9)
		(width 0.125)
		(layer "In2.Cu")
		(net 345)
	)
	(segment
		(start 231.25 141.5)
		(end 236.4 146.65)
		(width 0.125)
		(layer "In5.Cu")
		(net 345)
	)
	(segment
		(start 216.45 144.6)
		(end 222.45 144.6)
		(width 0.125)
		(layer "In5.Cu")
		(net 345)
	)
	(segment
		(start 236.4 146.65)
		(end 236.4 158.95)
		(width 0.125)
		(layer "In5.Cu")
		(net 345)
	)
	(segment
		(start 216 146.2)
		(end 216 145.05)
		(width 0.125)
		(layer "In5.Cu")
		(net 345)
	)
	(segment
		(start 222.45 144.6)
		(end 225.55 141.5)
		(width 0.125)
		(layer "In5.Cu")
		(net 345)
	)
	(segment
		(start 229.4 165.95)
		(end 229.4 167.45)
		(width 0.125)
		(layer "In5.Cu")
		(net 345)
	)
	(segment
		(start 229.4 167.45)
		(end 226.55 170.3)
		(width 0.125)
		(layer "In5.Cu")
		(net 345)
	)
	(segment
		(start 226.55 170.3)
		(end 225.35 170.3)
		(width 0.125)
		(layer "In5.Cu")
		(net 345)
	)
	(segment
		(start 236.4 158.95)
		(end 229.4 165.95)
		(width 0.125)
		(layer "In5.Cu")
		(net 345)
	)
	(segment
		(start 216 145.05)
		(end 216.45 144.6)
		(width 0.125)
		(layer "In5.Cu")
		(net 345)
	)
	(segment
		(start 225.55 141.5)
		(end 231.25 141.5)
		(width 0.125)
		(layer "In5.Cu")
		(net 345)
	)
	(segment
		(start 172.35 149)
		(end 172.35 125.9)
		(width 0.125)
		(layer "F.Cu")
		(net 347)
	)
	(segment
		(start 172.35 149)
		(end 175.45 152.1)
		(width 0.125)
		(layer "F.Cu")
		(net 347)
	)
	(segment
		(start 176.525 163.135)
		(end 176.525 160.425)
		(width 0.125)
		(layer "F.Cu")
		(net 347)
	)
	(segment
		(start 164.3 114.25)
		(end 146.4 96.35)
		(width 0.125)
		(layer "F.Cu")
		(net 347)
	)
	(segment
		(start 173.6 155.9)
		(end 173.95 155.9)
		(width 0.125)
		(layer "F.Cu")
		(net 347)
	)
	(segment
		(start 175.45 154.4)
		(end 175.45 152.1)
		(width 0.125)
		(layer "F.Cu")
		(net 347)
	)
	(segment
		(start 173.95 155.9)
		(end 175.45 154.4)
		(width 0.125)
		(layer "F.Cu")
		(net 347)
	)
	(segment
		(start 164.3 114.6)
		(end 164.3 114.25)
		(width 0.125)
		(layer "F.Cu")
		(net 347)
	)
	(segment
		(start 146.4 96.35)
		(end 125.39 96.35)
		(width 0.125)
		(layer "F.Cu")
		(net 347)
	)
	(segment
		(start 173.05 156.95)
		(end 176.525 160.425)
		(width 0.125)
		(layer "F.Cu")
		(net 347)
	)
	(segment
		(start 173.05 156.95)
		(end 173.05 156.45)
		(width 0.125)
		(layer "F.Cu")
		(net 347)
	)
	(segment
		(start 125.39 96.35)
		(end 123.88 97.86)
		(width 0.125)
		(layer "F.Cu")
		(net 347)
	)
	(segment
		(start 173.05 156.45)
		(end 173.6 155.9)
		(width 0.125)
		(layer "F.Cu")
		(net 347)
	)
	(via
		(at 164.3 114.6)
		(size 0.45)
		(drill 0.1)
		(layers "F.Cu" "B.Cu")
		(teardrops
			(best_length_ratio 0.4)
			(max_length 1)
			(best_width_ratio 0.9)
			(max_width 2)
			(curved_edges yes)
			(filter_ratio 0.9)
			(enabled yes)
			(allow_two_segments yes)
			(prefer_zone_connections yes)
		)
		(net 347)
	)
	(via
		(at 123.88 97.86)
		(size 0.45)
		(drill 0.1)
		(layers "F.Cu" "B.Cu")
		(remove_unused_layers yes)
		(keep_end_layers yes)
		(zone_layer_connections)
		(teardrops
			(best_length_ratio 0.4)
			(max_length 1)
			(best_width_ratio 0.9)
			(max_width 2)
			(curved_edges yes)
			(filter_ratio 0.9)
			(enabled yes)
			(allow_two_segments yes)
			(prefer_zone_connections yes)
		)
		(net 347)
	)
	(via
		(at 172.35 125.9)
		(size 0.45)
		(drill 0.1)
		(layers "F.Cu" "B.Cu")
		(teardrops
			(best_length_ratio 0.4)
			(max_length 1)
			(best_width_ratio 0.9)
			(max_width 2)
			(curved_edges yes)
			(filter_ratio 0.9)
			(enabled yes)
			(allow_two_segments yes)
			(prefer_zone_connections yes)
		)
		(net 347)
	)
	(segment
		(start 172.35 125.9)
		(end 172.35 122.65)
		(width 0.125)
		(layer "B.Cu")
		(net 347)
	)
	(segment
		(start 172.35 122.65)
		(end 164.3 114.6)
		(width 0.125)
		(layer "B.Cu")
		(net 347)
	)
	(segment
		(start 123.88 98.86)
		(end 123.88 97.86)
		(width 0.125)
		(layer "B.Cu")
		(net 347)
	)
	(segment
		(start 176.8 164.6)
		(end 175.8 164.6)
		(width 0.125)
		(layer "F.Cu")
		(net 348)
	)
	(segment
		(start 175.8 164.6)
		(end 175.2 164)
		(width 0.125)
		(layer "F.Cu")
		(net 348)
	)
	(segment
		(start 177.025 164.375)
		(end 176.8 164.6)
		(width 0.125)
		(layer "F.Cu")
		(net 348)
	)
	(segment
		(start 175.2 164)
		(end 175.2 163.8)
		(width 0.125)
		(layer "F.Cu")
		(net 348)
	)
	(segment
		(start 177.025 163.135)
		(end 177.025 164.375)
		(width 0.125)
		(layer "F.Cu")
		(net 348)
	)
	(via
		(at 175.2 163.8)
		(size 0.45)
		(drill 0.1)
		(layers "F.Cu" "B.Cu")
		(teardrops
			(best_length_ratio 0.4)
			(max_length 1)
			(best_width_ratio 0.9)
			(max_width 2)
			(curved_edges yes)
			(filter_ratio 0.9)
			(enabled yes)
			(allow_two_segments yes)
			(prefer_zone_connections yes)
		)
		(net 348)
	)
	(segment
		(start 174 163.85)
		(end 174 164.55)
		(width 0.125)
		(layer "F.Cu")
		(net 349)
	)
	(segment
		(start 177.1 164.9)
		(end 177.525 164.475)
		(width 0.125)
		(layer "F.Cu")
		(net 349)
	)
	(segment
		(start 174.35 164.9)
		(end 177.1 164.9)
		(width 0.125)
		(layer "F.Cu")
		(net 349)
	)
	(segment
		(start 177.525 164.475)
		(end 177.525 163.135)
		(width 0.125)
		(layer "F.Cu")
		(net 349)
	)
	(segment
		(start 174 164.55)
		(end 174.35 164.9)
		(width 0.125)
		(layer "F.Cu")
		(net 349)
	)
	(via
		(at 174 163.85)
		(size 0.45)
		(drill 0.1)
		(layers "F.Cu" "B.Cu")
		(teardrops
			(best_length_ratio 0.4)
			(max_length 1)
			(best_width_ratio 0.9)
			(max_width 2)
			(curved_edges yes)
			(filter_ratio 0.9)
			(enabled yes)
			(allow_two_segments yes)
			(prefer_zone_connections yes)
		)
		(net 349)
	)
	(segment
		(start 178.025 164.475)
		(end 178 164.5)
		(width 0.125)
		(layer "F.Cu")
		(net 350)
	)
	(segment
		(start 178.025 163.135)
		(end 178.025 164.475)
		(width 0.125)
		(layer "F.Cu")
		(net 350)
	)
	(via
		(at 178 164.5)
		(size 0.45)
		(drill 0.1)
		(layers "F.Cu" "B.Cu")
		(teardrops
			(best_length_ratio 0.4)
			(max_length 1)
			(best_width_ratio 0.9)
			(max_width 2)
			(curved_edges yes)
			(filter_ratio 0.9)
			(enabled yes)
			(allow_two_segments yes)
			(prefer_zone_connections yes)
		)
		(net 350)
	)
	(segment
		(start 176.95 164.5)
		(end 178 164.5)
		(width 0.125)
		(layer "B.Cu")
		(net 350)
	)
	(segment
		(start 176.25 163.8)
		(end 176.95 164.5)
		(width 0.125)
		(layer "B.Cu")
		(net 350)
	)
	(segment
		(start 178.525 163.135)
		(end 178.525 165.175)
		(width 0.125)
		(layer "F.Cu")
		(net 351)
	)
	(segment
		(start 178.525 165.175)
		(end 178 165.7)
		(width 0.125)
		(layer "F.Cu")
		(net 351)
	)
	(via
		(at 178 165.7)
		(size 0.45)
		(drill 0.1)
		(layers "F.Cu" "B.Cu")
		(teardrops
			(best_length_ratio 0.4)
			(max_length 1)
			(best_width_ratio 0.9)
			(max_width 2)
			(curved_edges yes)
			(filter_ratio 0.9)
			(enabled yes)
			(allow_two_segments yes)
			(prefer_zone_connections yes)
		)
		(net 351)
	)
	(segment
		(start 176.25 165.05)
		(end 177.35 165.05)
		(width 0.125)
		(layer "B.Cu")
		(net 351)
	)
	(segment
		(start 177.35 165.05)
		(end 178 165.7)
		(width 0.125)
		(layer "B.Cu")
		(net 351)
	)
	(segment
		(start 179.025 164.575)
		(end 179 164.6)
		(width 0.125)
		(layer "F.Cu")
		(net 352)
	)
	(segment
		(start 179.025 163.135)
		(end 179.025 164.575)
		(width 0.125)
		(layer "F.Cu")
		(net 352)
	)
	(via
		(at 179 164.6)
		(size 0.45)
		(drill 0.1)
		(layers "F.Cu" "B.Cu")
		(teardrops
			(best_length_ratio 0.4)
			(max_length 1)
			(best_width_ratio 0.9)
			(max_width 2)
			(curved_edges yes)
			(filter_ratio 0.9)
			(enabled yes)
			(allow_two_segments yes)
			(prefer_zone_connections yes)
		)
		(net 352)
	)
	(segment
		(start 177.35 163.8)
		(end 178.2 163.8)
		(width 0.125)
		(layer "B.Cu")
		(net 352)
	)
	(segment
		(start 178.2 163.8)
		(end 179 164.6)
		(width 0.125)
		(layer "B.Cu")
		(net 352)
	)
	(segment
		(start 179.525 165.075)
		(end 178.9 165.7)
		(width 0.125)
		(layer "F.Cu")
		(net 353)
	)
	(segment
		(start 179.525 163.135)
		(end 179.525 165.075)
		(width 0.125)
		(layer "F.Cu")
		(net 353)
	)
	(via
		(at 178.9 165.7)
		(size 0.45)
		(drill 0.1)
		(layers "F.Cu" "B.Cu")
		(teardrops
			(best_length_ratio 0.4)
			(max_length 1)
			(best_width_ratio 0.9)
			(max_width 2)
			(curved_edges yes)
			(filter_ratio 0.9)
			(enabled yes)
			(allow_two_segments yes)
			(prefer_zone_connections yes)
		)
		(net 353)
	)
	(segment
		(start 178.9 165.7)
		(end 178.45 166.15)
		(width 0.125)
		(layer "B.Cu")
		(net 353)
	)
	(segment
		(start 176.3 166.15)
		(end 176.25 166.1)
		(width 0.125)
		(layer "B.Cu")
		(net 353)
	)
	(segment
		(start 178.45 166.15)
		(end 176.3 166.15)
		(width 0.125)
		(layer "B.Cu")
		(net 353)
	)
	(segment
		(start 180.025 163.135)
		(end 180.025 165.275)
		(width 0.125)
		(layer "F.Cu")
		(net 354)
	)
	(segment
		(start 180.025 165.275)
		(end 179.6 165.7)
		(width 0.125)
		(layer "F.Cu")
		(net 354)
	)
	(via
		(at 179.6 165.7)
		(size 0.45)
		(drill 0.1)
		(layers "F.Cu" "B.Cu")
		(teardrops
			(best_length_ratio 0.4)
			(max_length 1)
			(best_width_ratio 0.9)
			(max_width 2)
			(curved_edges yes)
			(filter_ratio 0.9)
			(enabled yes)
			(allow_two_segments yes)
			(prefer_zone_connections yes)
		)
		(net 354)
	)
	(segment
		(start 178.2 162.55)
		(end 179.6 163.95)
		(width 0.125)
		(layer "B.Cu")
		(net 354)
	)
	(segment
		(start 179.6 163.95)
		(end 179.6 165.7)
		(width 0.125)
		(layer "B.Cu")
		(net 354)
	)
	(segment
		(start 177.35 162.55)
		(end 178.2 162.55)
		(width 0.125)
		(layer "B.Cu")
		(net 354)
	)
	(segment
		(start 180.525 163.135)
		(end 180.525 165.325)
		(width 0.125)
		(layer "F.Cu")
		(net 355)
	)
	(segment
		(start 180.525 165.325)
		(end 180.95 165.75)
		(width 0.125)
		(layer "F.Cu")
		(net 355)
	)
	(via
		(at 180.95 165.75)
		(size 0.45)
		(drill 0.1)
		(layers "F.Cu" "B.Cu")
		(teardrops
			(best_length_ratio 0.4)
			(max_length 1)
			(best_width_ratio 0.9)
			(max_width 2)
			(curved_edges yes)
			(filter_ratio 0.9)
			(enabled yes)
			(allow_two_segments yes)
			(prefer_zone_connections yes)
		)
		(net 355)
	)
	(segment
		(start 182.35 165.75)
		(end 180.95 165.75)
		(width 0.125)
		(layer "B.Cu")
		(net 355)
	)
	(segment
		(start 223.4 145.9)
		(end 223.4 144.3)
		(width 0.125)
		(layer "F.Cu")
		(net 356)
	)
	(segment
		(start 184.1 159.9)
		(end 183.2 159.9)
		(width 0.125)
		(layer "F.Cu")
		(net 356)
	)
	(segment
		(start 183.2 159.9)
		(end 181.525 161.575)
		(width 0.125)
		(layer "F.Cu")
		(net 356)
	)
	(segment
		(start 241.8 132.84)
		(end 241.8 133.6)
		(width 0.125)
		(layer "F.Cu")
		(net 356)
	)
	(segment
		(start 184.4 158.5)
		(end 184.4 159.6)
		(width 0.125)
		(layer "F.Cu")
		(net 356)
	)
	(segment
		(start 223.4 144.3)
		(end 221.9 142.8)
		(width 0.125)
		(layer "F.Cu")
		(net 356)
	)
	(segment
		(start 181.525 161.575)
		(end 181.525 163.135)
		(width 0.125)
		(layer "F.Cu")
		(net 356)
	)
	(segment
		(start 184.4 159.6)
		(end 184.1 159.9)
		(width 0.125)
		(layer "F.Cu")
		(net 356)
	)
	(via
		(at 221.9 142.8)
		(size 0.45)
		(drill 0.1)
		(layers "F.Cu" "B.Cu")
		(teardrops
			(best_length_ratio 0.4)
			(max_length 1)
			(best_width_ratio 0.9)
			(max_width 2)
			(curved_edges yes)
			(filter_ratio 0.9)
			(enabled yes)
			(allow_two_segments yes)
			(prefer_zone_connections yes)
		)
		(net 356)
	)
	(via
		(at 241.8 133.6)
		(size 0.45)
		(drill 0.1)
		(layers "F.Cu" "B.Cu")
		(teardrops
			(best_length_ratio 0.4)
			(max_length 1)
			(best_width_ratio 0.9)
			(max_width 2)
			(curved_edges yes)
			(filter_ratio 0.9)
			(enabled yes)
			(allow_two_segments yes)
			(prefer_zone_connections yes)
		)
		(net 356)
	)
	(via
		(at 184.4 158.5)
		(size 0.45)
		(drill 0.1)
		(layers "F.Cu" "B.Cu")
		(teardrops
			(best_length_ratio 0.4)
			(max_length 1)
			(best_width_ratio 0.9)
			(max_width 2)
			(curved_edges yes)
			(filter_ratio 0.9)
			(enabled yes)
			(allow_two_segments yes)
			(prefer_zone_connections yes)
		)
		(net 356)
	)
	(via
		(at 223.4 145.9)
		(size 0.45)
		(drill 0.1)
		(layers "F.Cu" "B.Cu")
		(teardrops
			(best_length_ratio 0.4)
			(max_length 1)
			(best_width_ratio 0.9)
			(max_width 2)
			(curved_edges yes)
			(filter_ratio 0.9)
			(enabled yes)
			(allow_two_segments yes)
			(prefer_zone_connections yes)
		)
		(net 356)
	)
	(segment
		(start 221.5 133.3)
		(end 222.4 132.4)
		(width 0.125)
		(layer "In2.Cu")
		(net 356)
	)
	(segment
		(start 223.4 148.3)
		(end 223.4 145.9)
		(width 0.125)
		(layer "In2.Cu")
		(net 356)
	)
	(segment
		(start 189.8 153.9)
		(end 191 153.9)
		(width 0.125)
		(layer "In2.Cu")
		(net 356)
	)
	(segment
		(start 214.25 156.1)
		(end 219.75 150.6)
		(width 0.125)
		(layer "In2.Cu")
		(net 356)
	)
	(segment
		(start 191 153.9)
		(end 191.4 154.3)
		(width 0.125)
		(layer "In2.Cu")
		(net 356)
	)
	(segment
		(start 236.6 132.4)
		(end 237.2 133)
		(width 0.125)
		(layer "In2.Cu")
		(net 356)
	)
	(segment
		(start 219.75 150.6)
		(end 221.1 150.6)
		(width 0.125)
		(layer "In2.Cu")
		(net 356)
	)
	(segment
		(start 221.5 134)
		(end 221.5 133.3)
		(width 0.125)
		(layer "In2.Cu")
		(net 356)
	)
	(segment
		(start 241.2 133)
		(end 241.8 133.6)
		(width 0.125)
		(layer "In2.Cu")
		(net 356)
	)
	(segment
		(start 184.4 158.5)
		(end 184.9 159)
		(width 0.125)
		(layer "In2.Cu")
		(net 356)
	)
	(segment
		(start 186.8 156.9)
		(end 189.8 153.9)
		(width 0.125)
		(layer "In2.Cu")
		(net 356)
	)
	(segment
		(start 223.05 135.55)
		(end 221.5 134)
		(width 0.125)
		(layer "In2.Cu")
		(net 356)
	)
	(segment
		(start 192.275 156.1)
		(end 214.25 156.1)
		(width 0.125)
		(layer "In2.Cu")
		(net 356)
	)
	(segment
		(start 222.4 132.4)
		(end 236.6 132.4)
		(width 0.125)
		(layer "In2.Cu")
		(net 356)
	)
	(segment
		(start 191.4 155.225)
		(end 192.275 156.1)
		(width 0.125)
		(layer "In2.Cu")
		(net 356)
	)
	(segment
		(start 221.9 142.8)
		(end 223.05 141.65)
		(width 0.125)
		(layer "In2.Cu")
		(net 356)
	)
	(segment
		(start 186.6 159)
		(end 186.8 158.8)
		(width 0.125)
		(layer "In2.Cu")
		(net 356)
	)
	(segment
		(start 186.8 158.8)
		(end 186.8 156.9)
		(width 0.125)
		(layer "In2.Cu")
		(net 356)
	)
	(segment
		(start 184.9 159)
		(end 186.6 159)
		(width 0.125)
		(layer "In2.Cu")
		(net 356)
	)
	(segment
		(start 237.2 133)
		(end 241.2 133)
		(width 0.125)
		(layer "In2.Cu")
		(net 356)
	)
	(segment
		(start 221.1 150.6)
		(end 223.4 148.3)
		(width 0.125)
		(layer "In2.Cu")
		(net 356)
	)
	(segment
		(start 223.05 141.65)
		(end 223.05 135.55)
		(width 0.125)
		(layer "In2.Cu")
		(net 356)
	)
	(segment
		(start 191.4 154.3)
		(end 191.4 155.225)
		(width 0.125)
		(layer "In2.Cu")
		(net 356)
	)
	(segment
		(start 122.35 153.3)
		(end 123.275 154.225)
		(width 0.125)
		(layer "F.Cu")
		(net 357)
	)
	(segment
		(start 181.6 164.5)
		(end 182.025 164.075)
		(width 0.125)
		(layer "F.Cu")
		(net 357)
	)
	(segment
		(start 126.975 154.225)
		(end 127.825 153.375)
		(width 0.125)
		(layer "F.Cu")
		(net 357)
	)
	(segment
		(start 123.275 154.225)
		(end 126.975 154.225)
		(width 0.125)
		(layer "F.Cu")
		(net 357)
	)
	(segment
		(start 121.1 152.725)
		(end 121.675 153.3)
		(width 0.125)
		(layer "F.Cu")
		(net 357)
	)
	(segment
		(start 182.025 164.075)
		(end 182.025 163.135)
		(width 0.125)
		(layer "F.Cu")
		(net 357)
	)
	(segment
		(start 127.825 150.85)
		(end 127.85 150.825)
		(width 0.125)
		(layer "F.Cu")
		(net 357)
	)
	(segment
		(start 127.825 153.375)
		(end 127.825 150.85)
		(width 0.125)
		(layer "F.Cu")
		(net 357)
	)
	(segment
		(start 121.675 153.3)
		(end 122.35 153.3)
		(width 0.125)
		(layer "F.Cu")
		(net 357)
	)
	(via
		(at 121.1 152.725)
		(size 0.45)
		(drill 0.1)
		(layers "F.Cu" "B.Cu")
		(teardrops
			(best_length_ratio 0.4)
			(max_length 1)
			(best_width_ratio 0.9)
			(max_width 2)
			(curved_edges yes)
			(filter_ratio 0.9)
			(enabled yes)
			(allow_two_segments yes)
			(prefer_zone_connections yes)
		)
		(net 357)
	)
	(via
		(at 109.96 163.53)
		(size 0.45)
		(drill 0.1)
		(layers "F.Cu" "B.Cu")
		(remove_unused_layers yes)
		(keep_end_layers yes)
		(zone_layer_connections "In2.Cu")
		(teardrops
			(best_length_ratio 0.4)
			(max_length 1)
			(best_width_ratio 0.9)
			(max_width 2)
			(curved_edges yes)
			(filter_ratio 0.9)
			(enabled yes)
			(allow_two_segments yes)
			(prefer_zone_connections yes)
		)
		(net 357)
	)
	(via
		(at 132.9 81.280001)
		(size 0.45)
		(drill 0.1)
		(layers "F.Cu" "B.Cu")
		(remove_unused_layers yes)
		(keep_end_layers yes)
		(zone_layer_connections "In2.Cu")
		(teardrops
			(best_length_ratio 0.4)
			(max_length 1)
			(best_width_ratio 0.9)
			(max_width 2)
			(curved_edges yes)
			(filter_ratio 0.9)
			(enabled yes)
			(allow_two_segments yes)
			(prefer_zone_connections yes)
		)
		(net 357)
	)
	(via
		(at 181.6 164.5)
		(size 0.45)
		(drill 0.1)
		(layers "F.Cu" "B.Cu")
		(teardrops
			(best_length_ratio 0.4)
			(max_length 1)
			(best_width_ratio 0.9)
			(max_width 2)
			(curved_edges yes)
			(filter_ratio 0.9)
			(enabled yes)
			(allow_two_segments yes)
			(prefer_zone_connections yes)
		)
		(net 357)
	)
	(via
		(at 127.85 150.825)
		(size 0.45)
		(drill 0.1)
		(layers "F.Cu" "B.Cu")
		(teardrops
			(best_length_ratio 0.4)
			(max_length 1)
			(best_width_ratio 0.9)
			(max_width 2)
			(curved_edges yes)
			(filter_ratio 0.9)
			(enabled yes)
			(allow_two_segments yes)
			(prefer_zone_connections yes)
		)
		(net 357)
	)
	(via
		(at 159.8 147)
		(size 0.45)
		(drill 0.1)
		(layers "F.Cu" "B.Cu")
		(teardrops
			(best_length_ratio 0.4)
			(max_length 1)
			(best_width_ratio 0.9)
			(max_width 2)
			(curved_edges yes)
			(filter_ratio 0.9)
			(enabled yes)
			(allow_two_segments yes)
			(prefer_zone_connections yes)
		)
		(net 357)
	)
	(via
		(at 166.775 163.9)
		(size 0.45)
		(drill 0.1)
		(layers "F.Cu" "B.Cu")
		(teardrops
			(best_length_ratio 0.4)
			(max_length 1)
			(best_width_ratio 0.9)
			(max_width 2)
			(curved_edges yes)
			(filter_ratio 0.9)
			(enabled yes)
			(allow_two_segments yes)
			(prefer_zone_connections yes)
		)
		(net 357)
	)
	(segment
		(start 109.96 163.53)
		(end 109.44 163.01)
		(width 0.125)
		(layer "B.Cu")
		(net 357)
	)
	(segment
		(start 109.44 163.01)
		(end 107.98 163.01)
		(width 0.125)
		(layer "B.Cu")
		(net 357)
	)
	(segment
		(start 153.675 149.275)
		(end 152.21 150.74)
		(width 0.125)
		(layer "In2.Cu")
		(net 357)
	)
	(segment
		(start 169.425 164.925)
		(end 175.53 164.925)
		(width 0.125)
		(layer "In2.Cu")
		(net 357)
	)
	(segment
		(start 160.225 148.25)
		(end 159.2 149.275)
		(width 0.125)
		(layer "In2.Cu")
		(net 357)
	)
	(segment
		(start 159.8 147)
		(end 160.225 147.425)
		(width 0.125)
		(layer "In2.Cu")
		(net 357)
	)
	(segment
		(start 109.96 163.53)
		(end 110.62 162.87)
		(width 0.125)
		(layer "In2.Cu")
		(net 357)
	)
	(segment
		(start 127.935 150.74)
		(end 127.85 150.825)
		(width 0.125)
		(layer "In2.Cu")
		(net 357)
	)
	(segment
		(start 175.53 164.925)
		(end 176.505 163.95)
		(width 0.125)
		(layer "In2.Cu")
		(net 357)
	)
	(segment
		(start 132.9 81.280001)
		(end 132.9 85.56)
		(width 0.125)
		(layer "In2.Cu")
		(net 357)
	)
	(segment
		(start 123.9 144.91)
		(end 122.025 146.785)
		(width 0.125)
		(layer "In2.Cu")
		(net 357)
	)
	(segment
		(start 110.62 159.03)
		(end 116.365 153.285)
		(width 0.125)
		(layer "In2.Cu")
		(net 357)
	)
	(segment
		(start 123.9 111.81)
		(end 123.9 144.91)
		(width 0.125)
		(layer "In2.Cu")
		(net 357)
	)
	(segment
		(start 166.775 163.9)
		(end 168.4 163.9)
		(width 0.125)
		(layer "In2.Cu")
		(net 357)
	)
	(segment
		(start 125.5075 87.6525)
		(end 125.5075 110.2025)
		(width 0.125)
		(layer "In2.Cu")
		(net 357)
	)
	(segment
		(start 168.4 163.9)
		(end 169.425 164.925)
		(width 0.125)
		(layer "In2.Cu")
		(net 357)
	)
	(segment
		(start 125.5075 110.2025)
		(end 123.9 111.81)
		(width 0.125)
		(layer "In2.Cu")
		(net 357)
	)
	(segment
		(start 181.05 163.95)
		(end 181.6 164.5)
		(width 0.125)
		(layer "In2.Cu")
		(net 357)
	)
	(segment
		(start 131.7 86.76)
		(end 126.4 86.76)
		(width 0.125)
		(layer "In2.Cu")
		(net 357)
	)
	(segment
		(start 116.365 153.285)
		(end 120.54 153.285)
		(width 0.125)
		(layer "In2.Cu")
		(net 357)
	)
	(segment
		(start 120.54 153.285)
		(end 121.1 152.725)
		(width 0.125)
		(layer "In2.Cu")
		(net 357)
	)
	(segment
		(start 126.4 86.76)
		(end 125.5075 87.6525)
		(width 0.125)
		(layer "In2.Cu")
		(net 357)
	)
	(segment
		(start 152.21 150.74)
		(end 127.935 150.74)
		(width 0.125)
		(layer "In2.Cu")
		(net 357)
	)
	(segment
		(start 159.2 149.275)
		(end 153.675 149.275)
		(width 0.125)
		(layer "In2.Cu")
		(net 357)
	)
	(segment
		(start 132.9 85.56)
		(end 131.7 86.76)
		(width 0.125)
		(layer "In2.Cu")
		(net 357)
	)
	(segment
		(start 176.505 163.95)
		(end 181.05 163.95)
		(width 0.125)
		(layer "In2.Cu")
		(net 357)
	)
	(segment
		(start 122.025 151.8)
		(end 121.1 152.725)
		(width 0.125)
		(layer "In2.Cu")
		(net 357)
	)
	(segment
		(start 110.62 162.87)
		(end 110.62 159.03)
		(width 0.125)
		(layer "In2.Cu")
		(net 357)
	)
	(segment
		(start 122.025 146.785)
		(end 122.025 151.8)
		(width 0.125)
		(layer "In2.Cu")
		(net 357)
	)
	(segment
		(start 160.225 147.425)
		(end 160.225 148.25)
		(width 0.125)
		(layer "In2.Cu")
		(net 357)
	)
	(segment
		(start 167.35 154.075)
		(end 167.35 157.15)
		(width 0.125)
		(layer "In5.Cu")
		(net 357)
	)
	(segment
		(start 168.025 163.425)
		(end 167.55 163.9)
		(width 0.125)
		(layer "In5.Cu")
		(net 357)
	)
	(segment
		(start 167.35 157.15)
		(end 168.025 157.825)
		(width 0.125)
		(layer "In5.Cu")
		(net 357)
	)
	(segment
		(start 159.8 147)
		(end 160.175 147.375)
		(width 0.125)
		(layer "In5.Cu")
		(net 357)
	)
	(segment
		(start 160.4 152.425)
		(end 165.7 152.425)
		(width 0.125)
		(layer "In5.Cu")
		(net 357)
	)
	(segment
		(start 160.175 152.2)
		(end 160.4 152.425)
		(width 0.125)
		(layer "In5.Cu")
		(net 357)
	)
	(segment
		(start 160.175 147.375)
		(end 160.175 152.2)
		(width 0.125)
		(layer "In5.Cu")
		(net 357)
	)
	(segment
		(start 165.7 152.425)
		(end 167.35 154.075)
		(width 0.125)
		(layer "In5.Cu")
		(net 357)
	)
	(segment
		(start 168.025 157.825)
		(end 168.025 163.425)
		(width 0.125)
		(layer "In5.Cu")
		(net 357)
	)
	(segment
		(start 167.55 163.9)
		(end 166.775 163.9)
		(width 0.125)
		(layer "In5.Cu")
		(net 357)
	)
	(segment
		(start 123.2 153.3)
		(end 122.125 152.225)
		(width 0.125)
		(layer "F.Cu")
		(net 358)
	)
	(segment
		(start 127.1 149.425)
		(end 126.475 150.05)
		(width 0.125)
		(layer "F.Cu")
		(net 358)
	)
	(segment
		(start 126.475 152.85)
		(end 126.025 153.3)
		(width 0.125)
		(layer "F.Cu")
		(net 358)
	)
	(segment
		(start 127.1 148.65)
		(end 127.1 149.425)
		(width 0.125)
		(layer "F.Cu")
		(net 358)
	)
	(segment
		(start 182.525 164.275)
		(end 182.525 163.135)
		(width 0.125)
		(layer "F.Cu")
		(net 358)
	)
	(segment
		(start 122.125 152.225)
		(end 120.625 152.225)
		(width 0.125)
		(layer "F.Cu")
		(net 358)
	)
	(segment
		(start 182.2 164.6)
		(end 182.525 164.275)
		(width 0.125)
		(layer "F.Cu")
		(net 358)
	)
	(segment
		(start 126.475 150.05)
		(end 126.475 152.85)
		(width 0.125)
		(layer "F.Cu")
		(net 358)
	)
	(segment
		(start 126.025 153.3)
		(end 123.2 153.3)
		(width 0.125)
		(layer "F.Cu")
		(net 358)
	)
	(via
		(at 127.1 148.65)
		(size 0.45)
		(drill 0.1)
		(layers "F.Cu" "B.Cu")
		(teardrops
			(best_length_ratio 0.4)
			(max_length 1)
			(best_width_ratio 0.9)
			(max_width 2)
			(curved_edges yes)
			(filter_ratio 0.9)
			(enabled yes)
			(allow_two_segments yes)
			(prefer_zone_connections yes)
		)
		(net 358)
	)
	(via
		(at 182.2 164.6)
		(size 0.45)
		(drill 0.1)
		(layers "F.Cu" "B.Cu")
		(teardrops
			(best_length_ratio 0.4)
			(max_length 1)
			(best_width_ratio 0.9)
			(max_width 2)
			(curved_edges yes)
			(filter_ratio 0.9)
			(enabled yes)
			(allow_two_segments yes)
			(prefer_zone_connections yes)
		)
		(net 358)
	)
	(via
		(at 110.175 162.5725)
		(size 0.45)
		(drill 0.1)
		(layers "F.Cu" "B.Cu")
		(remove_unused_layers yes)
		(keep_end_layers yes)
		(zone_layer_connections "In2.Cu")
		(teardrops
			(best_length_ratio 0.4)
			(max_length 1)
			(best_width_ratio 0.9)
			(max_width 2)
			(curved_edges yes)
			(filter_ratio 0.9)
			(enabled yes)
			(allow_two_segments yes)
			(prefer_zone_connections yes)
		)
		(net 358)
	)
	(via
		(at 158.95 148.225)
		(size 0.45)
		(drill 0.1)
		(layers "F.Cu" "B.Cu")
		(teardrops
			(best_length_ratio 0.4)
			(max_length 1)
			(best_width_ratio 0.9)
			(max_width 2)
			(curved_edges yes)
			(filter_ratio 0.9)
			(enabled yes)
			(allow_two_segments yes)
			(prefer_zone_connections yes)
		)
		(net 358)
	)
	(via
		(at 167.175 163.45)
		(size 0.45)
		(drill 0.1)
		(layers "F.Cu" "B.Cu")
		(teardrops
			(best_length_ratio 0.4)
			(max_length 1)
			(best_width_ratio 0.9)
			(max_width 2)
			(curved_edges yes)
			(filter_ratio 0.9)
			(enabled yes)
			(allow_two_segments yes)
			(prefer_zone_connections yes)
		)
		(net 358)
	)
	(via
		(at 131.9 81.28)
		(size 0.45)
		(drill 0.1)
		(layers "F.Cu" "B.Cu")
		(remove_unused_layers yes)
		(keep_end_layers yes)
		(zone_layer_connections "In2.Cu")
		(teardrops
			(best_length_ratio 0.4)
			(max_length 1)
			(best_width_ratio 0.9)
			(max_width 2)
			(curved_edges yes)
			(filter_ratio 0.9)
			(enabled yes)
			(allow_two_segments yes)
			(prefer_zone_connections yes)
		)
		(net 358)
	)
	(via
		(at 120.625 152.225)
		(size 0.45)
		(drill 0.1)
		(layers "F.Cu" "B.Cu")
		(teardrops
			(best_length_ratio 0.4)
			(max_length 1)
			(best_width_ratio 0.9)
			(max_width 2)
			(curved_edges yes)
			(filter_ratio 0.9)
			(enabled yes)
			(allow_two_segments yes)
			(prefer_zone_connections yes)
		)
		(net 358)
	)
	(segment
		(start 110.175 162.5725)
		(end 109.6625 162.06)
		(width 0.125)
		(layer "B.Cu")
		(net 358)
	)
	(segment
		(start 109.6625 162.06)
		(end 107.98 162.06)
		(width 0.125)
		(layer "B.Cu")
		(net 358)
	)
	(segment
		(start 121.3 146.41)
		(end 121.3 151.55)
		(width 0.125)
		(layer "In2.Cu")
		(net 358)
	)
	(segment
		(start 139.7 150.25)
		(end 149.85 150.25)
		(width 0.125)
		(layer "In2.Cu")
		(net 358)
	)
	(segment
		(start 131.262651 85.66)
		(end 126.7 85.66)
		(width 0.125)
		(layer "In2.Cu")
		(net 358)
	)
	(segment
		(start 176.255 163.65)
		(end 181.55 163.65)
		(width 0.125)
		(layer "In2.Cu")
		(net 358)
	)
	(segment
		(start 127.125 148.675)
		(end 127.1 148.65)
		(width 0.125)
		(layer "In2.Cu")
		(net 358)
	)
	(segment
		(start 126.7 85.66)
		(end 125.05 87.31)
		(width 0.125)
		(layer "In2.Cu")
		(net 358)
	)
	(segment
		(start 182.2 164.3)
		(end 182.2 164.6)
		(width 0.125)
		(layer "In2.Cu")
		(net 358)
	)
	(segment
		(start 120.24 152.61)
		(end 120.625 152.225)
		(width 0.125)
		(layer "In2.Cu")
		(net 358)
	)
	(segment
		(start 116.686446 152.61)
		(end 120.24 152.61)
		(width 0.125)
		(layer "In2.Cu")
		(net 358)
	)
	(segment
		(start 175.48 164.425)
		(end 176.255 163.65)
		(width 0.125)
		(layer "In2.Cu")
		(net 358)
	)
	(segment
		(start 158.95 148.225)
		(end 151.875 148.225)
		(width 0.125)
		(layer "In2.Cu")
		(net 358)
	)
	(segment
		(start 131.9 81.28)
		(end 131.9 85.022651)
		(width 0.125)
		(layer "In2.Cu")
		(net 358)
	)
	(segment
		(start 110.175 159.121446)
		(end 110.175 162.5725)
		(width 0.125)
		(layer "In2.Cu")
		(net 358)
	)
	(segment
		(start 149.85 150.25)
		(end 151.875 148.225)
		(width 0.125)
		(layer "In2.Cu")
		(net 358)
	)
	(segment
		(start 171.4 163.45)
		(end 172.375 164.425)
		(width 0.125)
		(layer "In2.Cu")
		(net 358)
	)
	(segment
		(start 125.05 87.31)
		(end 125.05 109.66)
		(width 0.125)
		(layer "In2.Cu")
		(net 358)
	)
	(segment
		(start 127.125 148.675)
		(end 138.125 148.675)
		(width 0.125)
		(layer "In2.Cu")
		(net 358)
	)
	(segment
		(start 131.9 85.022651)
		(end 131.262651 85.66)
		(width 0.125)
		(layer "In2.Cu")
		(net 358)
	)
	(segment
		(start 172.375 164.425)
		(end 175.48 164.425)
		(width 0.125)
		(layer "In2.Cu")
		(net 358)
	)
	(segment
		(start 116.686446 152.61)
		(end 110.175 159.121446)
		(width 0.125)
		(layer "In2.Cu")
		(net 358)
	)
	(segment
		(start 167.175 163.45)
		(end 171.4 163.45)
		(width 0.125)
		(layer "In2.Cu")
		(net 358)
	)
	(segment
		(start 123.35 111.36)
		(end 123.35 144.36)
		(width 0.125)
		(layer "In2.Cu")
		(net 358)
	)
	(segment
		(start 139.7 150.25)
		(end 138.125 148.675)
		(width 0.125)
		(layer "In2.Cu")
		(net 358)
	)
	(segment
		(start 125.05 109.66)
		(end 123.35 111.36)
		(width 0.125)
		(layer "In2.Cu")
		(net 358)
	)
	(segment
		(start 123.35 144.36)
		(end 121.3 146.41)
		(width 0.125)
		(layer "In2.Cu")
		(net 358)
	)
	(segment
		(start 181.55 163.65)
		(end 182.2 164.3)
		(width 0.125)
		(layer "In2.Cu")
		(net 358)
	)
	(segment
		(start 121.3 151.55)
		(end 120.625 152.225)
		(width 0.125)
		(layer "In2.Cu")
		(net 358)
	)
	(segment
		(start 165.545818 152.745818)
		(end 167.1 154.3)
		(width 0.125)
		(layer "In5.Cu")
		(net 358)
	)
	(segment
		(start 167.775 158.025)
		(end 167.125 157.375)
		(width 0.125)
		(layer "In5.Cu")
		(net 358)
	)
	(segment
		(start 167.1 157.35)
		(end 167.1 154.3)
		(width 0.125)
		(layer "In5.Cu")
		(net 358)
	)
	(segment
		(start 159.9 152.325)
		(end 159.9 149.175)
		(width 0.125)
		(layer "In5.Cu")
		(net 358)
	)
	(segment
		(start 160.320818 152.745818)
		(end 165.545818 152.745818)
		(width 0.125)
		(layer "In5.Cu")
		(net 358)
	)
	(segment
		(start 167.775 162.85)
		(end 167.775 158.025)
		(width 0.125)
		(layer "In5.Cu")
		(net 358)
	)
	(segment
		(start 159.9 149.175)
		(end 158.95 148.225)
		(width 0.125)
		(layer "In5.Cu")
		(net 358)
	)
	(segment
		(start 167.175 163.45)
		(end 167.775 162.85)
		(width 0.125)
		(layer "In5.Cu")
		(net 358)
	)
	(segment
		(start 160.320818 152.745818)
		(end 159.9 152.325)
		(width 0.125)
		(layer "In5.Cu")
		(net 358)
	)
	(segment
		(start 167.125 157.375)
		(end 167.1 157.35)
		(width 0.125)
		(layer "In5.Cu")
		(net 358)
	)
	(segment
		(start 184 145.5)
		(end 183.4 144.9)
		(width 0.125)
		(layer "F.Cu")
		(net 359)
	)
	(segment
		(start 183.025 161.675)
		(end 185.9 158.8)
		(width 0.125)
		(layer "F.Cu")
		(net 359)
	)
	(segment
		(start 186.9 135.4)
		(end 186.9 132)
		(width 0.125)
		(layer "F.Cu")
		(net 359)
	)
	(segment
		(start 183.025 163.135)
		(end 183.025 161.675)
		(width 0.125)
		(layer "F.Cu")
		(net 359)
	)
	(segment
		(start 183.4 138.9)
		(end 186.9 135.4)
		(width 0.125)
		(layer "F.Cu")
		(net 359)
	)
	(segment
		(start 183.4 144.9)
		(end 183.4 138.9)
		(width 0.125)
		(layer "F.Cu")
		(net 359)
	)
	(segment
		(start 185.9 158.8)
		(end 185.9 158.5)
		(width 0.125)
		(layer "F.Cu")
		(net 359)
	)
	(via
		(at 185.9 158.5)
		(size 0.45)
		(drill 0.1)
		(layers "F.Cu" "B.Cu")
		(teardrops
			(best_length_ratio 0.4)
			(max_length 1)
			(best_width_ratio 0.9)
			(max_width 2)
			(curved_edges yes)
			(filter_ratio 0.9)
			(enabled yes)
			(allow_two_segments yes)
			(prefer_zone_connections yes)
		)
		(net 359)
	)
	(via
		(at 200.9 122.3)
		(size 0.45)
		(drill 0.1)
		(layers "F.Cu" "B.Cu")
		(teardrops
			(best_length_ratio 0.4)
			(max_length 1)
			(best_width_ratio 0.9)
			(max_width 2)
			(curved_edges yes)
			(filter_ratio 0.9)
			(enabled yes)
			(allow_two_segments yes)
			(prefer_zone_connections yes)
		)
		(net 359)
	)
	(via
		(at 184 145.5)
		(size 0.45)
		(drill 0.1)
		(layers "F.Cu" "B.Cu")
		(teardrops
			(best_length_ratio 0.4)
			(max_length 1)
			(best_width_ratio 0.9)
			(max_width 2)
			(curved_edges yes)
			(filter_ratio 0.9)
			(enabled yes)
			(allow_two_segments yes)
			(prefer_zone_connections yes)
		)
		(net 359)
	)
	(via
		(at 186.9 132)
		(size 0.45)
		(drill 0.1)
		(layers "F.Cu" "B.Cu")
		(teardrops
			(best_length_ratio 0.4)
			(max_length 1)
			(best_width_ratio 0.9)
			(max_width 2)
			(curved_edges yes)
			(filter_ratio 0.9)
			(enabled yes)
			(allow_two_segments yes)
			(prefer_zone_connections yes)
		)
		(net 359)
	)
	(via
		(at 129.9 81.280001)
		(size 0.45)
		(drill 0.1)
		(layers "F.Cu" "B.Cu")
		(remove_unused_layers yes)
		(keep_end_layers yes)
		(zone_layer_connections "In5.Cu")
		(teardrops
			(best_length_ratio 0.4)
			(max_length 1)
			(best_width_ratio 0.9)
			(max_width 2)
			(curved_edges yes)
			(filter_ratio 0.9)
			(enabled yes)
			(allow_two_segments yes)
			(prefer_zone_connections yes)
		)
		(net 359)
	)
	(segment
		(start 200.9 122.3)
		(end 191.2 132)
		(width 0.125)
		(layer "In2.Cu")
		(net 359)
	)
	(segment
		(start 185.3 154.9)
		(end 185.3 158.3)
		(width 0.125)
		(layer "In2.Cu")
		(net 359)
	)
	(segment
		(start 191.2 132)
		(end 186.9 132)
		(width 0.125)
		(layer "In2.Cu")
		(net 359)
	)
	(segment
		(start 183.4 153)
		(end 185.3 154.9)
		(width 0.125)
		(layer "In2.Cu")
		(net 359)
	)
	(segment
		(start 185.5 158.5)
		(end 185.9 158.5)
		(width 0.125)
		(layer "In2.Cu")
		(net 359)
	)
	(segment
		(start 185.3 158.3)
		(end 185.5 158.5)
		(width 0.125)
		(layer "In2.Cu")
		(net 359)
	)
	(segment
		(start 184 145.5)
		(end 183.4 146.1)
		(width 0.125)
		(layer "In2.Cu")
		(net 359)
	)
	(segment
		(start 183.4 146.1)
		(end 183.4 153)
		(width 0.125)
		(layer "In2.Cu")
		(net 359)
	)
	(segment
		(start 129.9 81.280001)
		(end 129.9 81.21)
		(width 0.125)
		(layer "In5.Cu")
		(net 359)
	)
	(segment
		(start 206.45 102.26)
		(end 206.45 116.75)
		(width 0.125)
		(layer "In5.Cu")
		(net 359)
	)
	(segment
		(start 156.05 79.76)
		(end 158.75 77.06)
		(width 0.125)
		(layer "In5.Cu")
		(net 359)
	)
	(segment
		(start 131.35 79.76)
		(end 156.05 79.76)
		(width 0.125)
		(layer "In5.Cu")
		(net 359)
	)
	(segment
		(start 206.45 116.75)
		(end 200.9 122.3)
		(width 0.125)
		(layer "In5.Cu")
		(net 359)
	)
	(segment
		(start 181.25 77.06)
		(end 206.45 102.26)
		(width 0.125)
		(layer "In5.Cu")
		(net 359)
	)
	(segment
		(start 158.75 77.06)
		(end 181.25 77.06)
		(width 0.125)
		(layer "In5.Cu")
		(net 359)
	)
	(segment
		(start 129.9 81.21)
		(end 131.35 79.76)
		(width 0.125)
		(layer "In5.Cu")
		(net 359)
	)
	(segment
		(start 184.525 165.425)
		(end 185.05 165.95)
		(width 0.125)
		(layer "F.Cu")
		(net 362)
	)
	(segment
		(start 184.525 163.135)
		(end 184.525 165.425)
		(width 0.125)
		(layer "F.Cu")
		(net 362)
	)
	(via
		(at 185.05 165.95)
		(size 0.45)
		(drill 0.1)
		(layers "F.Cu" "B.Cu")
		(teardrops
			(best_length_ratio 0.4)
			(max_length 1)
			(best_width_ratio 0.9)
			(max_width 2)
			(curved_edges yes)
			(filter_ratio 0.9)
			(enabled yes)
			(allow_two_segments yes)
			(prefer_zone_connections yes)
		)
		(net 362)
	)
	(segment
		(start 185.95 137.25)
		(end 188.35 134.85)
		(width 0.125)
		(layer "F.Cu")
		(net 365)
	)
	(segment
		(start 185.95 146.45)
		(end 185.95 137.25)
		(width 0.125)
		(layer "F.Cu")
		(net 365)
	)
	(segment
		(start 187.525 163.135)
		(end 187.525 164.275)
		(width 0.125)
		(layer "F.Cu")
		(net 365)
	)
	(segment
		(start 301.76 127.79)
		(end 301.76 129.06)
		(width 0.125)
		(layer "F.Cu")
		(net 365)
	)
	(segment
		(start 190.9 152.95)
		(end 190.75 152.8)
		(width 0.125)
		(layer "F.Cu")
		(net 365)
	)
	(segment
		(start 205.05 114.15)
		(end 209.55 114.15)
		(width 0.125)
		(layer "F.Cu")
		(net 365)
	)
	(segment
		(start 187.525 164.275)
		(end 187.55 164.3)
		(width 0.125)
		(layer "F.Cu")
		(net 365)
	)
	(segment
		(start 190.9 154.45)
		(end 190.9 152.95)
		(width 0.125)
		(layer "F.Cu")
		(net 365)
	)
	(segment
		(start 188.35 118.5)
		(end 188.9 117.95)
		(width 0.125)
		(layer "F.Cu")
		(net 365)
	)
	(segment
		(start 202.95 112.05)
		(end 205.05 114.15)
		(width 0.125)
		(layer "F.Cu")
		(net 365)
	)
	(segment
		(start 276.739 129.139)
		(end 276.7 129.1)
		(width 0.125)
		(layer "F.Cu")
		(net 365)
	)
	(segment
		(start 276.739 129.139)
		(end 301.839 129.139)
		(width 0.125)
		(layer "F.Cu")
		(net 365)
	)
	(segment
		(start 188.35 134.85)
		(end 188.35 118.5)
		(width 0.125)
		(layer "F.Cu")
		(net 365)
	)
	(via
		(at 190.75 152.8)
		(size 0.45)
		(drill 0.1)
		(layers "F.Cu" "B.Cu")
		(teardrops
			(best_length_ratio 0.4)
			(max_length 1)
			(best_width_ratio 0.9)
			(max_width 2)
			(curved_edges yes)
			(filter_ratio 0.9)
			(enabled yes)
			(allow_two_segments yes)
			(prefer_zone_connections yes)
		)
		(net 365)
	)
	(via
		(at 190.9 154.45)
		(size 0.45)
		(drill 0.1)
		(layers "F.Cu" "B.Cu")
		(teardrops
			(best_length_ratio 0.4)
			(max_length 1)
			(best_width_ratio 0.9)
			(max_width 2)
			(curved_edges yes)
			(filter_ratio 0.9)
			(enabled yes)
			(allow_two_segments yes)
			(prefer_zone_connections yes)
		)
		(net 365)
	)
	(via
		(at 185.95 146.45)
		(size 0.45)
		(drill 0.1)
		(layers "F.Cu" "B.Cu")
		(teardrops
			(best_length_ratio 0.4)
			(max_length 1)
			(best_width_ratio 0.9)
			(max_width 2)
			(curved_edges yes)
			(filter_ratio 0.9)
			(enabled yes)
			(allow_two_segments yes)
			(prefer_zone_connections yes)
		)
		(net 365)
	)
	(via
		(at 188.9 117.95)
		(size 0.45)
		(drill 0.1)
		(layers "F.Cu" "B.Cu")
		(teardrops
			(best_length_ratio 0.4)
			(max_length 1)
			(best_width_ratio 0.9)
			(max_width 2)
			(curved_edges yes)
			(filter_ratio 0.9)
			(enabled yes)
			(allow_two_segments yes)
			(prefer_zone_connections yes)
		)
		(net 365)
	)
	(via
		(at 102.45 72.36)
		(size 0.45)
		(drill 0.1)
		(layers "F.Cu" "B.Cu")
		(remove_unused_layers yes)
		(keep_end_layers yes)
		(zone_layer_connections "In5.Cu")
		(teardrops
			(best_length_ratio 0.4)
			(max_length 1)
			(best_width_ratio 0.9)
			(max_width 2)
			(curved_edges yes)
			(filter_ratio 0.9)
			(enabled yes)
			(allow_two_segments yes)
			(prefer_zone_connections yes)
		)
		(net 365)
	)
	(via
		(at 276.7 129.1)
		(size 0.45)
		(drill 0.1)
		(layers "F.Cu" "B.Cu")
		(teardrops
			(best_length_ratio 0.4)
			(max_length 1)
			(best_width_ratio 0.9)
			(max_width 2)
			(curved_edges yes)
			(filter_ratio 0.9)
			(enabled yes)
			(allow_two_segments yes)
			(prefer_zone_connections yes)
		)
		(net 365)
	)
	(via
		(at 187.55 164.3)
		(size 0.45)
		(drill 0.1)
		(layers "F.Cu" "B.Cu")
		(teardrops
			(best_length_ratio 0.4)
			(max_length 1)
			(best_width_ratio 0.9)
			(max_width 2)
			(curved_edges yes)
			(filter_ratio 0.9)
			(enabled yes)
			(allow_two_segments yes)
			(prefer_zone_connections yes)
		)
		(net 365)
	)
	(via
		(at 202.95 112.05)
		(size 0.45)
		(drill 0.1)
		(layers "F.Cu" "B.Cu")
		(teardrops
			(best_length_ratio 0.4)
			(max_length 1)
			(best_width_ratio 0.9)
			(max_width 2)
			(curved_edges yes)
			(filter_ratio 0.9)
			(enabled yes)
			(allow_two_segments yes)
			(prefer_zone_connections yes)
		)
		(net 365)
	)
	(via
		(at 209.55 114.15)
		(size 0.45)
		(drill 0.1)
		(layers "F.Cu" "B.Cu")
		(teardrops
			(best_length_ratio 0.4)
			(max_length 1)
			(best_width_ratio 0.9)
			(max_width 2)
			(curved_edges yes)
			(filter_ratio 0.9)
			(enabled yes)
			(allow_two_segments yes)
			(prefer_zone_connections yes)
		)
		(net 365)
	)
	(via
		(at 187.5 158.55)
		(size 0.45)
		(drill 0.1)
		(layers "F.Cu" "B.Cu")
		(teardrops
			(best_length_ratio 0.4)
			(max_length 1)
			(best_width_ratio 0.9)
			(max_width 2)
			(curved_edges yes)
			(filter_ratio 0.9)
			(enabled yes)
			(allow_two_segments yes)
			(prefer_zone_connections yes)
		)
		(net 365)
	)
	(segment
		(start 187.55 164.3)
		(end 187.55 158.6)
		(width 0.125)
		(layer "B.Cu")
		(net 365)
	)
	(segment
		(start 187.55 158.6)
		(end 187.5 158.55)
		(width 0.125)
		(layer "B.Cu")
		(net 365)
	)
	(segment
		(start 102.45 72.36)
		(end 102.001 72.809)
		(width 0.125)
		(layer "B.Cu")
		(net 365)
	)
	(segment
		(start 187.85 158.55)
		(end 189 157.4)
		(width 0.125)
		(layer "In2.Cu")
		(net 365)
	)
	(segment
		(start 197.05 117.95)
		(end 202.95 112.05)
		(width 0.125)
		(layer "In2.Cu")
		(net 365)
	)
	(segment
		(start 189.75 151.8)
		(end 189.75 150.7)
		(width 0.125)
		(layer "In2.Cu")
		(net 365)
	)
	(segment
		(start 189.75 150.7)
		(end 185.95 146.9)
		(width 0.125)
		(layer "In2.Cu")
		(net 365)
	)
	(segment
		(start 189 157.4)
		(end 189 156.35)
		(width 0.125)
		(layer "In2.Cu")
		(net 365)
	)
	(segment
		(start 188.9 117.95)
		(end 197.05 117.95)
		(width 0.125)
		(layer "In2.Cu")
		(net 365)
	)
	(segment
		(start 190.75 152.8)
		(end 189.75 151.8)
		(width 0.125)
		(layer "In2.Cu")
		(net 365)
	)
	(segment
		(start 189 156.35)
		(end 190.9 154.45)
		(width 0.125)
		(layer "In2.Cu")
		(net 365)
	)
	(segment
		(start 187.5 158.55)
		(end 187.85 158.55)
		(width 0.125)
		(layer "In2.Cu")
		(net 365)
	)
	(segment
		(start 185.95 146.9)
		(end 185.95 146.45)
		(width 0.125)
		(layer "In2.Cu")
		(net 365)
	)
	(segment
		(start 231.31 113.31)
		(end 243.2 125.2)
		(width 0.125)
		(layer "In5.Cu")
		(net 365)
	)
	(segment
		(start 243.2 125.2)
		(end 271.98 125.2)
		(width 0.125)
		(layer "In5.Cu")
		(net 365)
	)
	(segment
		(start 182.41 76.56)
		(end 207 101.15)
		(width 0.125)
		(layer "In5.Cu")
		(net 365)
	)
	(segment
		(start 207 112.11)
		(end 208.2 113.31)
		(width 0.125)
		(layer "In5.Cu")
		(net 365)
	)
	(segment
		(start 128.8 76.56)
		(end 146.41 76.56)
		(width 0.125)
		(layer "In5.Cu")
		(net 365)
	)
	(segment
		(start 121.9 69.66)
		(end 128.8 76.56)
		(width 0.125)
		(layer "In5.Cu")
		(net 365)
	)
	(segment
		(start 209.55 113.31)
		(end 231.31 113.31)
		(width 0.125)
		(layer "In5.Cu")
		(net 365)
	)
	(segment
		(start 208.2 113.31)
		(end 209.55 113.31)
		(width 0.125)
		(layer "In5.Cu")
		(net 365)
	)
	(segment
		(start 104.25 69.66)
		(end 121.9 69.66)
		(width 0.125)
		(layer "In5.Cu")
		(net 365)
	)
	(segment
		(start 146.65 76.8)
		(end 148.81 76.8)
		(width 0.125)
		(layer "In5.Cu")
		(net 365)
	)
	(segment
		(start 102.45 72.36)
		(end 102.45 71.46)
		(width 0.125)
		(layer "In5.Cu")
		(net 365)
	)
	(segment
		(start 209.55 114.15)
		(end 209.55 113.31)
		(width 0.125)
		(layer "In5.Cu")
		(net 365)
	)
	(segment
		(start 102.45 71.46)
		(end 104.25 69.66)
		(width 0.125)
		(layer "In5.Cu")
		(net 365)
	)
	(segment
		(start 149.05 76.56)
		(end 182.41 76.56)
		(width 0.125)
		(layer "In5.Cu")
		(net 365)
	)
	(segment
		(start 146.41 76.56)
		(end 146.65 76.8)
		(width 0.125)
		(layer "In5.Cu")
		(net 365)
	)
	(segment
		(start 271.98 125.2)
		(end 275.88 129.1)
		(width 0.125)
		(layer "In5.Cu")
		(net 365)
	)
	(segment
		(start 207 101.15)
		(end 207 112.11)
		(width 0.125)
		(layer "In5.Cu")
		(net 365)
	)
	(segment
		(start 275.88 129.1)
		(end 276.7 129.1)
		(width 0.125)
		(layer "In5.Cu")
		(net 365)
	)
	(segment
		(start 148.81 76.8)
		(end 149.05 76.56)
		(width 0.125)
		(layer "In5.Cu")
		(net 365)
	)
	(segment
		(start 189.025 164.175)
		(end 189.1 164.25)
		(width 0.125)
		(layer "F.Cu")
		(net 366)
	)
	(segment
		(start 189.025 163.135)
		(end 189.025 164.175)
		(width 0.125)
		(layer "F.Cu")
		(net 366)
	)
	(via
		(at 189.1 164.25)
		(size 0.45)
		(drill 0.1)
		(layers "F.Cu" "B.Cu")
		(teardrops
			(best_length_ratio 0.4)
			(max_length 1)
			(best_width_ratio 0.9)
			(max_width 2)
			(curved_edges yes)
			(filter_ratio 0.9)
			(enabled yes)
			(allow_two_segments yes)
			(prefer_zone_connections yes)
		)
		(net 366)
	)
	(segment
		(start 191.525 163.135)
		(end 191.525 164.275)
		(width 0.125)
		(layer "F.Cu")
		(net 370)
	)
	(segment
		(start 191.525 164.275)
		(end 191.55 164.3)
		(width 0.125)
		(layer "F.Cu")
		(net 370)
	)
	(via
		(at 191.55 164.3)
		(size 0.45)
		(drill 0.1)
		(layers "F.Cu" "B.Cu")
		(teardrops
			(best_length_ratio 0.4)
			(max_length 1)
			(best_width_ratio 0.9)
			(max_width 2)
			(curved_edges yes)
			(filter_ratio 0.9)
			(enabled yes)
			(allow_two_segments yes)
			(prefer_zone_connections yes)
		)
		(net 370)
	)
	(segment
		(start 191.55 163.4)
		(end 191.55 164.3)
		(width 0.125)
		(layer "B.Cu")
		(net 370)
	)
	(segment
		(start 192.025 163.135)
		(end 192.025 161.975)
		(width 0.125)
		(layer "F.Cu")
		(net 371)
	)
	(segment
		(start 238.96 153.1)
		(end 238.749 153.311)
		(width 0.125)
		(layer "F.Cu")
		(net 371)
	)
	(segment
		(start 304.15 151.91)
		(end 241.89 151.91)
		(width 0.125)
		(layer "F.Cu")
		(net 371)
	)
	(segment
		(start 259.14 88.909999)
		(end 259.98 88.909999)
		(width 0.125)
		(layer "F.Cu")
		(net 371)
	)
	(segment
		(start 302.177 107.41)
		(end 302.177 108.24)
		(width 0.45)
		(layer "F.Cu")
		(net 371)
	)
	(segment
		(start 241.89 151.91)
		(end 240.7 153.1)
		(width 0.125)
		(layer "F.Cu")
		(net 371)
	)
	(segment
		(start 304.527 151.533)
		(end 304.15 151.91)
		(width 0.125)
		(layer "F.Cu")
		(net 371)
	)
	(segment
		(start 304.527 150.41)
		(end 304.527 151.24)
		(width 0.45)
		(layer "F.Cu")
		(net 371)
	)
	(segment
		(start 240.7 153.1)
		(end 240.175 153.1)
		(width 0.125)
		(layer "F.Cu")
		(net 371)
	)
	(segment
		(start 302.177 93.86)
		(end 302.177 94.69)
		(width 0.45)
		(layer "F.Cu")
		(net 371)
	)
	(segment
		(start 304.527 150.41)
		(end 304.527 151.533)
		(width 0.125)
		(layer "F.Cu")
		(net 371)
	)
	(segment
		(start 238.749 153.311)
		(end 238.749 153.962)
		(width 0.125)
		(layer "F.Cu")
		(net 371)
	)
	(segment
		(start 192.025 161.975)
		(end 192.275 161.725)
		(width 0.125)
		(layer "F.Cu")
		(net 371)
	)
	(segment
		(start 240.175 153.1)
		(end 238.96 153.1)
		(width 0.125)
		(layer "F.Cu")
		(net 371)
	)
	(via
		(at 302.177 108.24)
		(size 0.45)
		(drill 0.1)
		(layers "F.Cu" "B.Cu")
		(remove_unused_layers yes)
		(keep_end_layers yes)
		(zone_layer_connections "In5.Cu")
		(teardrops
			(best_length_ratio 0.4)
			(max_length 1)
			(best_width_ratio 0.9)
			(max_width 2)
			(curved_edges yes)
			(filter_ratio 0.9)
			(enabled yes)
			(allow_two_segments yes)
			(prefer_zone_connections yes)
		)
		(net 371)
	)
	(via
		(at 304.527 151.24)
		(size 0.45)
		(drill 0.1)
		(layers "F.Cu" "B.Cu")
		(remove_unused_layers yes)
		(keep_end_layers yes)
		(zone_layer_connections "In5.Cu")
		(teardrops
			(best_length_ratio 0.4)
			(max_length 1)
			(best_width_ratio 0.9)
			(max_width 2)
			(curved_edges yes)
			(filter_ratio 0.9)
			(enabled yes)
			(allow_two_segments yes)
			(prefer_zone_connections yes)
		)
		(net 371)
	)
	(via
		(at 302.177 94.69)
		(size 0.45)
		(drill 0.1)
		(layers "F.Cu" "B.Cu")
		(remove_unused_layers yes)
		(keep_end_layers yes)
		(zone_layer_connections "In5.Cu")
		(teardrops
			(best_length_ratio 0.4)
			(max_length 1)
			(best_width_ratio 0.9)
			(max_width 2)
			(curved_edges yes)
			(filter_ratio 0.9)
			(enabled yes)
			(allow_two_segments yes)
			(prefer_zone_connections yes)
		)
		(net 371)
	)
	(via
		(at 240.175 153.1)
		(size 0.45)
		(drill 0.1)
		(layers "F.Cu" "B.Cu")
		(teardrops
			(best_length_ratio 0.4)
			(max_length 1)
			(best_width_ratio 0.9)
			(max_width 2)
			(curved_edges yes)
			(filter_ratio 0.9)
			(enabled yes)
			(allow_two_segments yes)
			(prefer_zone_connections yes)
		)
		(net 371)
	)
	(via
		(at 259.14 88.909999)
		(size 0.45)
		(drill 0.1)
		(layers "F.Cu" "B.Cu")
		(remove_unused_layers yes)
		(keep_end_layers yes)
		(zone_layer_connections "In5.Cu")
		(teardrops
			(best_length_ratio 0.4)
			(max_length 1)
			(best_width_ratio 0.9)
			(max_width 2)
			(curved_edges yes)
			(filter_ratio 0.9)
			(enabled yes)
			(allow_two_segments yes)
			(prefer_zone_connections yes)
		)
		(net 371)
	)
	(via
		(at 192.275 161.725)
		(size 0.45)
		(drill 0.1)
		(layers "F.Cu" "B.Cu")
		(teardrops
			(best_length_ratio 0.4)
			(max_length 1)
			(best_width_ratio 0.9)
			(max_width 2)
			(curved_edges yes)
			(filter_ratio 0.9)
			(enabled yes)
			(allow_two_segments yes)
			(prefer_zone_connections yes)
		)
		(net 371)
	)
	(segment
		(start 198.95 160.725)
		(end 201.55 163.325)
		(width 0.125)
		(layer "In2.Cu")
		(net 371)
	)
	(segment
		(start 209.29 162.85)
		(end 227.0875 162.85)
		(width 0.125)
		(layer "In2.Cu")
		(net 371)
	)
	(segment
		(start 205.2 163.325)
		(end 206.6 164.725)
		(width 0.125)
		(layer "In2.Cu")
		(net 371)
	)
	(segment
		(start 233.975 155.9625)
		(end 233.975 154.675)
		(width 0.125)
		(layer "In2.Cu")
		(net 371)
	)
	(segment
		(start 235.55 153.1)
		(end 240.175 153.1)
		(width 0.125)
		(layer "In2.Cu")
		(net 371)
	)
	(segment
		(start 233.975 154.675)
		(end 235.55 153.1)
		(width 0.125)
		(layer "In2.Cu")
		(net 371)
	)
	(segment
		(start 227.0875 162.85)
		(end 233.975 155.9625)
		(width 0.125)
		(layer "In2.Cu")
		(net 371)
	)
	(segment
		(start 192.275 161.725)
		(end 193.275 160.725)
		(width 0.125)
		(layer "In2.Cu")
		(net 371)
	)
	(segment
		(start 193.275 160.725)
		(end 198.95 160.725)
		(width 0.125)
		(layer "In2.Cu")
		(net 371)
	)
	(segment
		(start 207.415 164.725)
		(end 209.29 162.85)
		(width 0.125)
		(layer "In2.Cu")
		(net 371)
	)
	(segment
		(start 206.6 164.725)
		(end 207.415 164.725)
		(width 0.125)
		(layer "In2.Cu")
		(net 371)
	)
	(segment
		(start 201.55 163.325)
		(end 205.2 163.325)
		(width 0.125)
		(layer "In2.Cu")
		(net 371)
	)
	(segment
		(start 269.3 90.3)
		(end 260.530001 90.3)
		(width 0.125)
		(layer "In5.Cu")
		(net 371)
	)
	(segment
		(start 302.177 107.483)
		(end 302.177 108.24)
		(width 0.125)
		(layer "In5.Cu")
		(net 371)
	)
	(segment
		(start 302.177 110.183)
		(end 298.65 113.71)
		(width 0.125)
		(layer "In5.Cu")
		(net 371)
	)
	(segment
		(start 298.65 145.363)
		(end 304.527 151.24)
		(width 0.125)
		(layer "In5.Cu")
		(net 371)
	)
	(segment
		(start 301.8795 94.3925)
		(end 299.4425 94.3925)
		(width 0.125)
		(layer "In5.Cu")
		(net 371)
	)
	(segment
		(start 274.51 95.51)
		(end 269.3 90.3)
		(width 0.125)
		(layer "In5.Cu")
		(net 371)
	)
	(segment
		(start 302.177 94.69)
		(end 301.8795 94.3925)
		(width 0.125)
		(layer "In5.Cu")
		(net 371)
	)
	(segment
		(start 302.177 94.69)
		(end 303.75 96.263)
		(width 0.125)
		(layer "In5.Cu")
		(net 371)
	)
	(segment
		(start 303.75 105.91)
		(end 302.177 107.483)
		(width 0.125)
		(layer "In5.Cu")
		(net 371)
	)
	(segment
		(start 303.75 96.263)
		(end 303.75 105.91)
		(width 0.125)
		(layer "In5.Cu")
		(net 371)
	)
	(segment
		(start 299.4425 94.3925)
		(end 298.325 95.51)
		(width 0.125)
		(layer "In5.Cu")
		(net 371)
	)
	(segment
		(start 302.177 108.24)
		(end 302.177 110.183)
		(width 0.125)
		(layer "In5.Cu")
		(net 371)
	)
	(segment
		(start 298.325 95.51)
		(end 274.51 95.51)
		(width 0.125)
		(layer "In5.Cu")
		(net 371)
	)
	(segment
		(start 298.65 113.71)
		(end 298.65 145.363)
		(width 0.125)
		(layer "In5.Cu")
		(net 371)
	)
	(segment
		(start 260.530001 90.3)
		(end 259.14 88.909999)
		(width 0.125)
		(layer "In5.Cu")
		(net 371)
	)
	(segment
		(start 192.525 162.1)
		(end 192.875 161.75)
		(width 0.125)
		(layer "F.Cu")
		(net 372)
	)
	(segment
		(start 240.2 154.5)
		(end 240.2 153.962)
		(width 0.125)
		(layer "F.Cu")
		(net 372)
	)
	(segment
		(start 240.738 153.962)
		(end 242.09 152.61)
		(width 0.125)
		(layer "F.Cu")
		(net 372)
	)
	(segment
		(start 303.477 93.157)
		(end 303.330001 93.01)
		(width 0.125)
		(layer "F.Cu")
		(net 372)
	)
	(segment
		(start 302.98 93.01)
		(end 303.330001 93.01)
		(width 0.125)
		(layer "F.Cu")
		(net 372)
	)
	(segment
		(start 240.738 153.962)
		(end 240.2 153.962)
		(width 0.125)
		(layer "F.Cu")
		(net 372)
	)
	(segment
		(start 242.09 152.61)
		(end 304.5 152.61)
		(width 0.125)
		(layer "F.Cu")
		(net 372)
	)
	(segment
		(start 302.825 93.86)
		(end 302.825 94.69)
		(width 0.45)
		(layer "F.Cu")
		(net 372)
	)
	(segment
		(start 302.825 107.41)
		(end 302.825 108.24)
		(width 0.45)
		(layer "F.Cu")
		(net 372)
	)
	(segment
		(start 302.825 93.165)
		(end 302.98 93.01)
		(width 0.125)
		(layer "F.Cu")
		(net 372)
	)
	(segment
		(start 258.65 89.539999)
		(end 259.98 89.539999)
		(width 0.125)
		(layer "F.Cu")
		(net 372)
	)
	(segment
		(start 304.5 152.61)
		(end 305.175 151.935)
		(width 0.125)
		(layer "F.Cu")
		(net 372)
	)
	(segment
		(start 240.2 153.962)
		(end 239.25 153.962)
		(width 0.125)
		(layer "F.Cu")
		(net 372)
	)
	(segment
		(start 240.15 154.55)
		(end 240.2 154.5)
		(width 0.125)
		(layer "F.Cu")
		(net 372)
	)
	(segment
		(start 305.175 150.41)
		(end 305.175 151.24)
		(width 0.45)
		(layer "F.Cu")
		(net 372)
	)
	(segment
		(start 302.825 93.86)
		(end 302.825 93.165)
		(width 0.125)
		(layer "F.Cu")
		(net 372)
	)
	(segment
		(start 192.525 163.135)
		(end 192.525 162.1)
		(width 0.125)
		(layer "F.Cu")
		(net 372)
	)
	(segment
		(start 305.175 151.935)
		(end 305.175 150.41)
		(width 0.125)
		(layer "F.Cu")
		(net 372)
	)
	(segment
		(start 192.875 161.75)
		(end 193.025 161.75)
		(width 0.125)
		(layer "F.Cu")
		(net 372)
	)
	(segment
		(start 303.477 93.86)
		(end 303.477 93.157)
		(width 0.125)
		(layer "F.Cu")
		(net 372)
	)
	(via
		(at 302.825 108.24)
		(size 0.45)
		(drill 0.1)
		(layers "F.Cu" "B.Cu")
		(remove_unused_layers yes)
		(keep_end_layers yes)
		(zone_layer_connections "In5.Cu")
		(teardrops
			(best_length_ratio 0.4)
			(max_length 1)
			(best_width_ratio 0.9)
			(max_width 2)
			(curved_edges yes)
			(filter_ratio 0.9)
			(enabled yes)
			(allow_two_segments yes)
			(prefer_zone_connections yes)
		)
		(net 372)
	)
	(via
		(at 302.825 94.69)
		(size 0.45)
		(drill 0.1)
		(layers "F.Cu" "B.Cu")
		(remove_unused_layers yes)
		(keep_end_layers yes)
		(zone_layer_connections "In5.Cu")
		(teardrops
			(best_length_ratio 0.4)
			(max_length 1)
			(best_width_ratio 0.9)
			(max_width 2)
			(curved_edges yes)
			(filter_ratio 0.9)
			(enabled yes)
			(allow_two_segments yes)
			(prefer_zone_connections yes)
		)
		(net 372)
	)
	(via
		(at 305.175 151.24)
		(size 0.45)
		(drill 0.1)
		(layers "F.Cu" "B.Cu")
		(remove_unused_layers yes)
		(keep_end_layers yes)
		(zone_layer_connections "In5.Cu")
		(teardrops
			(best_length_ratio 0.4)
			(max_length 1)
			(best_width_ratio 0.9)
			(max_width 2)
			(curved_edges yes)
			(filter_ratio 0.9)
			(enabled yes)
			(allow_two_segments yes)
			(prefer_zone_connections yes)
		)
		(net 372)
	)
	(via
		(at 193.025 161.75)
		(size 0.45)
		(drill 0.1)
		(layers "F.Cu" "B.Cu")
		(teardrops
			(best_length_ratio 0.4)
			(max_length 1)
			(best_width_ratio 0.9)
			(max_width 2)
			(curved_edges yes)
			(filter_ratio 0.9)
			(enabled yes)
			(allow_two_segments yes)
			(prefer_zone_connections yes)
		)
		(net 372)
	)
	(via
		(at 258.65 89.539999)
		(size 0.45)
		(drill 0.1)
		(layers "F.Cu" "B.Cu")
		(remove_unused_layers yes)
		(keep_end_layers yes)
		(zone_layer_connections "In5.Cu")
		(teardrops
			(best_length_ratio 0.4)
			(max_length 1)
			(best_width_ratio 0.9)
			(max_width 2)
			(curved_edges yes)
			(filter_ratio 0.9)
			(enabled yes)
			(allow_two_segments yes)
			(prefer_zone_connections yes)
		)
		(net 372)
	)
	(via
		(at 240.15 154.55)
		(size 0.45)
		(drill 0.1)
		(layers "F.Cu" "B.Cu")
		(teardrops
			(best_length_ratio 0.4)
			(max_length 1)
			(best_width_ratio 0.9)
			(max_width 2)
			(curved_edges yes)
			(filter_ratio 0.9)
			(enabled yes)
			(allow_two_segments yes)
			(prefer_zone_connections yes)
		)
		(net 372)
	)
	(segment
		(start 210.345 163.48)
		(end 209.675 164.15)
		(width 0.125)
		(layer "In2.Cu")
		(net 372)
	)
	(segment
		(start 202.125 165.3)
		(end 202.125 164.3)
		(width 0.125)
		(layer "In2.Cu")
		(net 372)
	)
	(segment
		(start 203.525 166.275)
		(end 203.1 166.275)
		(width 0.125)
		(layer "In2.Cu")
		(net 372)
	)
	(segment
		(start 209.675 164.15)
		(end 209.675 165.675)
		(width 0.125)
		(layer "In2.Cu")
		(net 372)
	)
	(segment
		(start 193.725 161.05)
		(end 193.025 161.75)
		(width 0.125)
		(layer "In2.Cu")
		(net 372)
	)
	(segment
		(start 237.1 153.95)
		(end 227.57 163.48)
		(width 0.125)
		(layer "In2.Cu")
		(net 372)
	)
	(segment
		(start 202.125 164.3)
		(end 198.875 161.05)
		(width 0.125)
		(layer "In2.Cu")
		(net 372)
	)
	(segment
		(start 239.55 153.95)
		(end 237.1 153.95)
		(width 0.125)
		(layer "In2.Cu")
		(net 372)
	)
	(segment
		(start 240.15 154.55)
		(end 239.55 153.95)
		(width 0.125)
		(layer "In2.Cu")
		(net 372)
	)
	(segment
		(start 227.57 163.48)
		(end 210.345 163.48)
		(width 0.125)
		(layer "In2.Cu")
		(net 372)
	)
	(segment
		(start 205.3 168.05)
		(end 203.525 166.275)
		(width 0.125)
		(layer "In2.Cu")
		(net 372)
	)
	(segment
		(start 203.1 166.275)
		(end 202.125 165.3)
		(width 0.125)
		(layer "In2.Cu")
		(net 372)
	)
	(segment
		(start 209.675 165.675)
		(end 207.3 168.05)
		(width 0.125)
		(layer "In2.Cu")
		(net 372)
	)
	(segment
		(start 198.875 161.05)
		(end 193.725 161.05)
		(width 0.125)
		(layer "In2.Cu")
		(net 372)
	)
	(segment
		(start 207.3 168.05)
		(end 205.3 168.05)
		(width 0.125)
		(layer "In2.Cu")
		(net 372)
	)
	(segment
		(start 304.2 106.16)
		(end 302.825 107.535)
		(width 0.125)
		(layer "In5.Cu")
		(net 372)
	)
	(segment
		(start 302.825 107.535)
		(end 302.825 108.24)
		(width 0.125)
		(layer "In5.Cu")
		(net 372)
	)
	(segment
		(start 302.825 108.24)
		(end 302.825 110.285)
		(width 0.125)
		(layer "In5.Cu")
		(net 372)
	)
	(segment
		(start 258.65 88.552272)
		(end 258.65 89.539999)
		(width 0.125)
		(layer "In5.Cu")
		(net 372)
	)
	(segment
		(start 302.825 110.285)
		(end 299.125 113.985)
		(width 0.125)
		(layer "In5.Cu")
		(net 372)
	)
	(segment
		(start 302.825 94.69)
		(end 304.2 96.065)
		(width 0.125)
		(layer "In5.Cu")
		(net 372)
	)
	(segment
		(start 299.25 93.86)
		(end 298.1 95.01)
		(width 0.125)
		(layer "In5.Cu")
		(net 372)
	)
	(segment
		(start 304.2 96.065)
		(end 304.2 106.16)
		(width 0.125)
		(layer "In5.Cu")
		(net 372)
	)
	(segment
		(start 301.995 93.86)
		(end 299.25 93.86)
		(width 0.125)
		(layer "In5.Cu")
		(net 372)
	)
	(segment
		(start 299.125 113.985)
		(end 299.125 145.19)
		(width 0.125)
		(layer "In5.Cu")
		(net 372)
	)
	(segment
		(start 302.825 94.69)
		(end 301.995 93.86)
		(width 0.125)
		(layer "In5.Cu")
		(net 372)
	)
	(segment
		(start 299.125 145.19)
		(end 305.175 151.24)
		(width 0.125)
		(layer "In5.Cu")
		(net 372)
	)
	(segment
		(start 269.54 89.8)
		(end 261 89.8)
		(width 0.125)
		(layer "In5.Cu")
		(net 372)
	)
	(segment
		(start 298.1 95.01)
		(end 274.75 95.01)
		(width 0.125)
		(layer "In5.Cu")
		(net 372)
	)
	(segment
		(start 259.5 88.3)
		(end 258.902272 88.3)
		(width 0.125)
		(layer "In5.Cu")
		(net 372)
	)
	(segment
		(start 258.902272 88.3)
		(end 258.65 88.552272)
		(width 0.125)
		(layer "In5.Cu")
		(net 372)
	)
	(segment
		(start 261 89.8)
		(end 259.5 88.3)
		(width 0.125)
		(layer "In5.Cu")
		(net 372)
	)
	(segment
		(start 274.75 95.01)
		(end 269.54 89.8)
		(width 0.125)
		(layer "In5.Cu")
		(net 372)
	)
	(segment
		(start 193.025 163.135)
		(end 193.025 164.275)
		(width 0.125)
		(layer "F.Cu")
		(net 373)
	)
	(segment
		(start 193.025 164.275)
		(end 193 164.3)
		(width 0.125)
		(layer "F.Cu")
		(net 373)
	)
	(via
		(at 193 164.3)
		(size 0.45)
		(drill 0.1)
		(layers "F.Cu" "B.Cu")
		(teardrops
			(best_length_ratio 0.4)
			(max_length 1)
			(best_width_ratio 0.9)
			(max_width 2)
			(curved_edges yes)
			(filter_ratio 0.9)
			(enabled yes)
			(allow_two_segments yes)
			(prefer_zone_connections yes)
		)
		(net 373)
	)
	(segment
		(start 193 164.3)
		(end 193 165.42)
		(width 0.125)
		(layer "B.Cu")
		(net 373)
	)
	(segment
		(start 196.585 162.35)
		(end 196.585 161.6325)
		(width 0.185)
		(layer "F.Cu")
		(net 374)
	)
	(segment
		(start 152.528042 115.177726)
		(end 152.528042 114.971958)
		(width 0.185)
		(layer "F.Cu")
		(net 374)
	)
	(segment
		(start 132.571958 115.459341)
		(end 132.571958 115.271958)
		(width 0.185)
		(layer "F.Cu")
		(net 374)
	)
	(segment
		(start 130.585 115.6)
		(end 130.895 115.91)
		(width 0.185)
		(layer "F.Cu")
		(net 374)
	)
	(segment
		(start 130.895 115.91)
		(end 132.121299 115.91)
		(width 0.185)
		(layer "F.Cu")
		(net 374)
	)
	(segment
		(start 130.56 115.6)
		(end 130.585 115.6)
		(width 0.185)
		(layer "F.Cu")
		(net 374)
	)
	(segment
		(start 155.277 117.926684)
		(end 152.528042 115.177726)
		(width 0.185)
		(layer "F.Cu")
		(net 374)
	)
	(segment
		(start 196.525 163.135)
		(end 196.525 162.41)
		(width 0.185)
		(layer "F.Cu")
		(net 374)
	)
	(segment
		(start 155.427 123)
		(end 155.277 122.85)
		(width 0.185)
		(layer "F.Cu")
		(net 374)
	)
	(segment
		(start 155.277 122.85)
		(end 155.277 117.926684)
		(width 0.185)
		(layer "F.Cu")
		(net 374)
	)
	(segment
		(start 196.525 162.41)
		(end 196.585 162.35)
		(width 0.185)
		(layer "F.Cu")
		(net 374)
	)
	(segment
		(start 196.585 161.6325)
		(end 196.4525 161.5)
		(width 0.185)
		(layer "F.Cu")
		(net 374)
	)
	(segment
		(start 132.121299 115.91)
		(end 132.571958 115.459341)
		(width 0.185)
		(layer "F.Cu")
		(net 374)
	)
	(via
		(at 152.528042 114.971958)
		(size 0.45)
		(drill 0.1)
		(layers "F.Cu" "B.Cu")
		(teardrops
			(best_length_ratio 0.4)
			(max_length 1)
			(best_width_ratio 0.9)
			(max_width 2)
			(curved_edges yes)
			(filter_ratio 0.9)
			(enabled yes)
			(allow_two_segments yes)
			(prefer_zone_connections yes)
		)
		(net 374)
	)
	(via
		(at 196.4525 161.5)
		(size 0.45)
		(drill 0.1)
		(layers "F.Cu" "B.Cu")
		(teardrops
			(best_length_ratio 0.4)
			(max_length 1)
			(best_width_ratio 0.9)
			(max_width 2)
			(curved_edges yes)
			(filter_ratio 0.9)
			(enabled yes)
			(allow_two_segments yes)
			(prefer_zone_connections yes)
		)
		(net 374)
	)
	(via
		(at 155.427 123)
		(size 0.45)
		(drill 0.1)
		(layers "F.Cu" "B.Cu")
		(teardrops
			(best_length_ratio 0.4)
			(max_length 1)
			(best_width_ratio 0.9)
			(max_width 2)
			(curved_edges yes)
			(filter_ratio 0.9)
			(enabled yes)
			(allow_two_segments yes)
			(prefer_zone_connections yes)
		)
		(net 374)
	)
	(via
		(at 132.571958 115.271958)
		(size 0.45)
		(drill 0.1)
		(layers "F.Cu" "B.Cu")
		(teardrops
			(best_length_ratio 0.4)
			(max_length 1)
			(best_width_ratio 0.9)
			(max_width 2)
			(curved_edges yes)
			(filter_ratio 0.9)
			(enabled yes)
			(allow_two_segments yes)
			(prefer_zone_connections yes)
		)
		(net 374)
	)
	(segment
		(start 149.578702 115.31)
		(end 150.721298 115.31)
		(width 0.185)
		(layer "B.Cu")
		(net 374)
	)
	(segment
		(start 134.321299 113.71)
		(end 147.978702 113.71)
		(width 0.185)
		(layer "B.Cu")
		(net 374)
	)
	(segment
		(start 147.978702 113.71)
		(end 149.578702 115.31)
		(width 0.185)
		(layer "B.Cu")
		(net 374)
	)
	(segment
		(start 150.721298 115.31)
		(end 151.321298 114.71)
		(width 0.185)
		(layer "B.Cu")
		(net 374)
	)
	(segment
		(start 132.571958 115.271958)
		(end 132.759341 115.271958)
		(width 0.185)
		(layer "B.Cu")
		(net 374)
	)
	(segment
		(start 151.321298 114.71)
		(end 152.078701 114.71)
		(width 0.185)
		(layer "B.Cu")
		(net 374)
	)
	(segment
		(start 152.078701 114.71)
		(end 152.340659 114.971958)
		(width 0.185)
		(layer "B.Cu")
		(net 374)
	)
	(segment
		(start 152.340659 114.971958)
		(end 152.528042 114.971958)
		(width 0.185)
		(layer "B.Cu")
		(net 374)
	)
	(segment
		(start 132.759341 115.271958)
		(end 134.321299 113.71)
		(width 0.185)
		(layer "B.Cu")
		(net 374)
	)
	(segment
		(start 178.47518 160.2185)
		(end 182.37518 160.2185)
		(width 0.159)
		(layer "In5.Cu")
		(net 374)
	)
	(segment
		(start 184.2815 166.62482)
		(end 185.87518 168.2185)
		(width 0.159)
		(layer "In5.Cu")
		(net 374)
	)
	(segment
		(start 177.3815 156.67518)
		(end 177.3815 159.12482)
		(width 0.159)
		(layer "In5.Cu")
		(net 374)
	)
	(segment
		(start 155.2815 123.72482)
		(end 155.87518 124.3185)
		(width 0.159)
		(layer "In5.Cu")
		(net 374)
	)
	(segment
		(start 159.857773 124.3185)
		(end 160.67518 124.3185)
		(width 0.159)
		(layer "In5.Cu")
		(net 374)
	)
	(segment
		(start 155.2815 123.1455)
		(end 155.2815 123.72482)
		(width 0.159)
		(layer "In5.Cu")
		(net 374)
	)
	(segment
		(start 157.864991 124.1185)
		(end 157.864991 124.038655)
		(width 0.159)
		(layer "In5.Cu")
		(net 374)
	)
	(segment
		(start 155.427 123)
		(end 155.2815 123.1455)
		(width 0.159)
		(layer "In5.Cu")
		(net 374)
	)
	(segment
		(start 171.4815 135.12482)
		(end 171.4815 147.02482)
		(width 0.159)
		(layer "In5.Cu")
		(net 374)
	)
	(segment
		(start 184.2815 162.12482)
		(end 184.2815 166.62482)
		(width 0.159)
		(layer "In5.Cu")
		(net 374)
	)
	(segment
		(start 177.3815 159.12482)
		(end 178.47518 160.2185)
		(width 0.159)
		(layer "In5.Cu")
		(net 374)
	)
	(segment
		(start 182.37518 160.2185)
		(end 184.2815 162.12482)
		(width 0.159)
		(layer "In5.Cu")
		(net 374)
	)
	(segment
		(start 196.5935 161.641)
		(end 196.4525 161.5)
		(width 0.159)
		(layer "In5.Cu")
		(net 374)
	)
	(segment
		(start 177.7815 156.27518)
		(end 177.3815 156.67518)
		(width 0.159)
		(layer "In5.Cu")
		(net 374)
	)
	(segment
		(start 171.4815 147.02482)
		(end 177.7815 153.32482)
		(width 0.159)
		(layer "In5.Cu")
		(net 374)
	)
	(segment
		(start 155.87518 124.3185)
		(end 157.664991 124.3185)
		(width 0.159)
		(layer "In5.Cu")
		(net 374)
	)
	(segment
		(start 177.7815 153.32482)
		(end 177.7815 156.27518)
		(width 0.159)
		(layer "In5.Cu")
		(net 374)
	)
	(segment
		(start 158.064991 123.838655)
		(end 158.164991 123.838655)
		(width 0.159)
		(layer "In5.Cu")
		(net 374)
	)
	(segment
		(start 158.564991 124.3185)
		(end 158.664991 124.3185)
		(width 0.159)
		(layer "In5.Cu")
		(net 374)
	)
	(segment
		(start 158.664991 124.3185)
		(end 159.857773 124.3185)
		(width 0.159)
		(layer "In5.Cu")
		(net 374)
	)
	(segment
		(start 185.87518 168.2185)
		(end 191.006434 168.2185)
		(width 0.159)
		(layer "In5.Cu")
		(net 374)
	)
	(segment
		(start 160.67518 124.3185)
		(end 171.4815 135.12482)
		(width 0.159)
		(layer "In5.Cu")
		(net 374)
	)
	(segment
		(start 191.006434 168.2185)
		(end 196.5935 162.631434)
		(width 0.159)
		(layer "In5.Cu")
		(net 374)
	)
	(segment
		(start 158.364991 124.038655)
		(end 158.364991 124.1185)
		(width 0.159)
		(layer "In5.Cu")
		(net 374)
	)
	(segment
		(start 196.5935 162.631434)
		(end 196.5935 161.641)
		(width 0.159)
		(layer "In5.Cu")
		(net 374)
	)
	(arc
		(start 157.664991 124.3185)
		(mid 157.806412 124.259921)
		(end 157.864991 124.1185)
		(width 0.159)
		(layer "In5.Cu")
		(net 374)
	)
	(arc
		(start 158.364991 124.1185)
		(mid 158.42357 124.259921)
		(end 158.564991 124.3185)
		(width 0.159)
		(layer "In5.Cu")
		(net 374)
	)
	(arc
		(start 158.164991 123.838655)
		(mid 158.306412 123.897234)
		(end 158.364991 124.038655)
		(width 0.159)
		(layer "In5.Cu")
		(net 374)
	)
	(arc
		(start 157.864991 124.038655)
		(mid 157.92357 123.897234)
		(end 158.064991 123.838655)
		(width 0.159)
		(layer "In5.Cu")
		(net 374)
	)
	(segment
		(start 130.585 116.6)
		(end 130.895 116.29)
		(width 0.185)
		(layer "F.Cu")
		(net 375)
	)
	(segment
		(start 152.277726 115.428042)
		(end 152.071958 115.428042)
		(width 0.185)
		(layer "F.Cu")
		(net 375)
	)
	(segment
		(start 132.278701 116.29)
		(end 132.840659 115.728042)
		(width 0.185)
		(layer "F.Cu")
		(net 375)
	)
	(segment
		(start 197.025 163.135)
		(end 197.025 162.41)
		(width 0.185)
		(layer "F.Cu")
		(net 375)
	)
	(segment
		(start 154.923 122.85)
		(end 154.923 118.073316)
		(width 0.185)
		(layer "F.Cu")
		(net 375)
	)
	(segment
		(start 154.773 123)
		(end 154.923 122.85)
		(width 0.185)
		(layer "F.Cu")
		(net 375)
	)
	(segment
		(start 154.923 118.073316)
		(end 152.277726 115.428042)
		(width 0.185)
		(layer "F.Cu")
		(net 375)
	)
	(segment
		(start 132.840659 115.728042)
		(end 133.028042 115.728042)
		(width 0.185)
		(layer "F.Cu")
		(net 375)
	)
	(segment
		(start 130.895 116.29)
		(end 132.278701 116.29)
		(width 0.185)
		(layer "F.Cu")
		(net 375)
	)
	(segment
		(start 197.025 162.41)
		(end 196.965 162.35)
		(width 0.185)
		(layer "F.Cu")
		(net 375)
	)
	(segment
		(start 196.965 161.6325)
		(end 197.0975 161.5)
		(width 0.185)
		(layer "F.Cu")
		(net 375)
	)
	(segment
		(start 130.56 116.6)
		(end 130.585 116.6)
		(width 0.185)
		(layer "F.Cu")
		(net 375)
	)
	(segment
		(start 196.965 162.35)
		(end 196.965 161.6325)
		(width 0.185)
		(layer "F.Cu")
		(net 375)
	)
	(via
		(at 154.773 123)
		(size 0.45)
		(drill 0.1)
		(layers "F.Cu" "B.Cu")
		(teardrops
			(best_length_ratio 0.4)
			(max_length 1)
			(best_width_ratio 0.9)
			(max_width 2)
			(curved_edges yes)
			(filter_ratio 0.9)
			(enabled yes)
			(allow_two_segments yes)
			(prefer_zone_connections yes)
		)
		(net 375)
	)
	(via
		(at 133.028042 115.728042)
		(size 0.45)
		(drill 0.1)
		(layers "F.Cu" "B.Cu")
		(teardrops
			(best_length_ratio 0.4)
			(max_length 1)
			(best_width_ratio 0.9)
			(max_width 2)
			(curved_edges yes)
			(filter_ratio 0.9)
			(enabled yes)
			(allow_two_segments yes)
			(prefer_zone_connections yes)
		)
		(net 375)
	)
	(via
		(at 197.0975 161.5)
		(size 0.45)
		(drill 0.1)
		(layers "F.Cu" "B.Cu")
		(teardrops
			(best_length_ratio 0.4)
			(max_length 1)
			(best_width_ratio 0.9)
			(max_width 2)
			(curved_edges yes)
			(filter_ratio 0.9)
			(enabled yes)
			(allow_two_segments yes)
			(prefer_zone_connections yes)
		)
		(net 375)
	)
	(via
		(at 152.071958 115.428042)
		(size 0.45)
		(drill 0.1)
		(layers "F.Cu" "B.Cu")
		(teardrops
			(best_length_ratio 0.4)
			(max_length 1)
			(best_width_ratio 0.9)
			(max_width 2)
			(curved_edges yes)
			(filter_ratio 0.9)
			(enabled yes)
			(allow_two_segments yes)
			(prefer_zone_connections yes)
		)
		(net 375)
	)
	(segment
		(start 149.421298 115.69)
		(end 150.878702 115.69)
		(width 0.185)
		(layer "B.Cu")
		(net 375)
	)
	(segment
		(start 152.071958 115.240659)
		(end 152.071958 115.428042)
		(width 0.185)
		(layer "B.Cu")
		(net 375)
	)
	(segment
		(start 151.921299 115.09)
		(end 152.071958 115.240659)
		(width 0.185)
		(layer "B.Cu")
		(net 375)
	)
	(segment
		(start 133.028042 115.540659)
		(end 134.478701 114.09)
		(width 0.185)
		(layer "B.Cu")
		(net 375)
	)
	(segment
		(start 133.028042 115.728042)
		(end 133.028042 115.540659)
		(width 0.185)
		(layer "B.Cu")
		(net 375)
	)
	(segment
		(start 134.478701 114.09)
		(end 147.821298 114.09)
		(width 0.185)
		(layer "B.Cu")
		(net 375)
	)
	(segment
		(start 147.821298 114.09)
		(end 149.421298 115.69)
		(width 0.185)
		(layer "B.Cu")
		(net 375)
	)
	(segment
		(start 150.878702 115.69)
		(end 151.478702 115.09)
		(width 0.185)
		(layer "B.Cu")
		(net 375)
	)
	(segment
		(start 151.478702 115.09)
		(end 151.921299 115.09)
		(width 0.185)
		(layer "B.Cu")
		(net 375)
	)
	(segment
		(start 191.193566 168.5815)
		(end 185.72482 168.5815)
		(width 0.159)
		(layer "In5.Cu")
		(net 375)
	)
	(segment
		(start 183.9185 162.27518)
		(end 182.22482 160.5815)
		(width 0.159)
		(layer "In5.Cu")
		(net 375)
	)
	(segment
		(start 154.9185 123.87518)
		(end 154.9185 123.1455)
		(width 0.159)
		(layer "In5.Cu")
		(net 375)
	)
	(segment
		(start 196.9565 162.818566)
		(end 191.193566 168.5815)
		(width 0.159)
		(layer "In5.Cu")
		(net 375)
	)
	(segment
		(start 197.0975 161.5)
		(end 196.9565 161.641)
		(width 0.159)
		(layer "In5.Cu")
		(net 375)
	)
	(segment
		(start 171.1185 147.17518)
		(end 171.1185 135.27518)
		(width 0.159)
		(layer "In5.Cu")
		(net 375)
	)
	(segment
		(start 183.9185 166.77518)
		(end 183.9185 162.27518)
		(width 0.159)
		(layer "In5.Cu")
		(net 375)
	)
	(segment
		(start 185.72482 168.5815)
		(end 183.9185 166.77518)
		(width 0.159)
		(layer "In5.Cu")
		(net 375)
	)
	(segment
		(start 177.4185 153.47518)
		(end 171.1185 147.17518)
		(width 0.159)
		(layer "In5.Cu")
		(net 375)
	)
	(segment
		(start 178.32482 160.5815)
		(end 177.0185 159.27518)
		(width 0.159)
		(layer "In5.Cu")
		(net 375)
	)
	(segment
		(start 196.9565 161.641)
		(end 196.9565 162.818566)
		(width 0.159)
		(layer "In5.Cu")
		(net 375)
	)
	(segment
		(start 154.9185 123.1455)
		(end 154.773 123)
		(width 0.159)
		(layer "In5.Cu")
		(net 375)
	)
	(segment
		(start 155.72482 124.6815)
		(end 154.9185 123.87518)
		(width 0.159)
		(layer "In5.Cu")
		(net 375)
	)
	(segment
		(start 177.0185 156.52482)
		(end 177.4185 156.12482)
		(width 0.159)
		(layer "In5.Cu")
		(net 375)
	)
	(segment
		(start 182.22482 160.5815)
		(end 178.32482 160.5815)
		(width 0.159)
		(layer "In5.Cu")
		(net 375)
	)
	(segment
		(start 177.4185 156.12482)
		(end 177.4185 153.47518)
		(width 0.159)
		(layer "In5.Cu")
		(net 375)
	)
	(segment
		(start 177.0185 159.27518)
		(end 177.0185 156.52482)
		(width 0.159)
		(layer "In5.Cu")
		(net 375)
	)
	(segment
		(start 171.1185 135.27518)
		(end 160.52482 124.6815)
		(width 0.159)
		(layer "In5.Cu")
		(net 375)
	)
	(segment
		(start 160.52482 124.6815)
		(end 155.72482 124.6815)
		(width 0.159)
		(layer "In5.Cu")
		(net 375)
	)
	(segment
		(start 198.085 163.92)
		(end 198.085 164.196299)
		(width 0.185)
		(layer "F.Cu")
		(net 377)
	)
	(segment
		(start 157.755418 71.99)
		(end 158.5175 71.99)
		(width 0.185)
		(layer "F.Cu")
		(net 377)
	)
	(segment
		(start 157.29 72)
		(end 157.745418 72)
		(width 0.185)
		(layer "F.Cu")
		(net 377)
	)
	(segment
		(start 198.025 163.135)
		(end 198.025 163.86)
		(width 0.185)
		(layer "F.Cu")
		(net 377)
	)
	(segment
		(start 156.955 72.31)
		(end 156.98 72.31)
		(width 0.185)
		(layer "F.Cu")
		(net 377)
	)
	(segment
		(start 156.98 72.31)
		(end 157.29 72)
		(width 0.185)
		(layer "F.Cu")
		(net 377)
	)
	(segment
		(start 198.025 163.86)
		(end 198.085 163.92)
		(width 0.185)
		(layer "F.Cu")
		(net 377)
	)
	(segment
		(start 198.085 164.196299)
		(end 197.409341 164.871958)
		(width 0.185)
		(layer "F.Cu")
		(net 377)
	)
	(segment
		(start 197.409341 164.871958)
		(end 197.221958 164.871958)
		(width 0.185)
		(layer "F.Cu")
		(net 377)
	)
	(segment
		(start 157.745418 72)
		(end 157.755418 71.99)
		(width 0.185)
		(layer "F.Cu")
		(net 377)
	)
	(segment
		(start 158.5175 71.99)
		(end 158.65 72.1225)
		(width 0.185)
		(layer "F.Cu")
		(net 377)
	)
	(via
		(at 197.221958 164.871958)
		(size 0.45)
		(drill 0.1)
		(layers "F.Cu" "B.Cu")
		(teardrops
			(best_length_ratio 0.4)
			(max_length 1)
			(best_width_ratio 0.9)
			(max_width 2)
			(curved_edges yes)
			(filter_ratio 0.9)
			(enabled yes)
			(allow_two_segments yes)
			(prefer_zone_connections yes)
		)
		(net 377)
	)
	(via
		(at 204.323 142.25)
		(size 0.45)
		(drill 0.1)
		(layers "F.Cu" "B.Cu")
		(teardrops
			(best_length_ratio 0.4)
			(max_length 1)
			(best_width_ratio 0.9)
			(max_width 2)
			(curved_edges yes)
			(filter_ratio 0.9)
			(enabled yes)
			(allow_two_segments yes)
			(prefer_zone_connections yes)
		)
		(net 377)
	)
	(via
		(at 158.65 72.1225)
		(size 0.45)
		(drill 0.1)
		(layers "F.Cu" "B.Cu")
		(teardrops
			(best_length_ratio 0.4)
			(max_length 1)
			(best_width_ratio 0.9)
			(max_width 2)
			(curved_edges yes)
			(filter_ratio 0.9)
			(enabled yes)
			(allow_two_segments yes)
			(prefer_zone_connections yes)
		)
		(net 377)
	)
	(segment
		(start 204.46 137.871298)
		(end 209.36 132.971298)
		(width 0.185)
		(layer "B.Cu")
		(net 377)
	)
	(segment
		(start 162.571298 74.79)
		(end 159.771298 71.99)
		(width 0.185)
		(layer "B.Cu")
		(net 377)
	)
	(segment
		(start 189.06 111.178702)
		(end 189.06 88.878702)
		(width 0.185)
		(layer "B.Cu")
		(net 377)
	)
	(segment
		(start 158.7825 71.99)
		(end 158.65 72.1225)
		(width 0.185)
		(layer "B.Cu")
		(net 377)
	)
	(segment
		(start 192.471298 114.59)
		(end 189.06 111.178702)
		(width 0.185)
		(layer "B.Cu")
		(net 377)
	)
	(segment
		(start 209.36 132.971298)
		(end 209.36 125.628702)
		(width 0.185)
		(layer "B.Cu")
		(net 377)
	)
	(segment
		(start 198.321298 114.59)
		(end 192.471298 114.59)
		(width 0.185)
		(layer "B.Cu")
		(net 377)
	)
	(segment
		(start 159.771298 71.99)
		(end 158.7825 71.99)
		(width 0.185)
		(layer "B.Cu")
		(net 377)
	)
	(segment
		(start 204.46 142.113)
		(end 204.46 137.871298)
		(width 0.185)
		(layer "B.Cu")
		(net 377)
	)
	(segment
		(start 204.323 142.25)
		(end 204.46 142.113)
		(width 0.185)
		(layer "B.Cu")
		(net 377)
	)
	(segment
		(start 209.36 125.628702)
		(end 198.321298 114.59)
		(width 0.185)
		(layer "B.Cu")
		(net 377)
	)
	(segment
		(start 189.06 88.878702)
		(end 174.971298 74.79)
		(width 0.185)
		(layer "B.Cu")
		(net 377)
	)
	(segment
		(start 174.971298 74.79)
		(end 162.571298 74.79)
		(width 0.185)
		(layer "B.Cu")
		(net 377)
	)
	(segment
		(start 199.305801 162.98752)
		(end 199.351044 162.942276)
		(width 0.159)
		(layer "In5.Cu")
		(net 377)
	)
	(segment
		(start 197.421362 164.871958)
		(end 198.004721 164.288599)
		(width 0.159)
		(layer "In5.Cu")
		(net 377)
	)
	(segment
		(start 198.258405 163.631529)
		(end 198.329992 163.703116)
		(width 0.159)
		(layer "In5.Cu")
		(net 377)
	)
	(segment
		(start 198.004722 164.028383)
		(end 197.933136 163.956797)
		(width 0.159)
		(layer "In5.Cu")
		(net 377)
	)
	(segment
		(start 198.590208 163.703115)
		(end 198.655261 163.63806)
		(width 0.159)
		(layer "In5.Cu")
		(net 377)
	)
	(segment
		(start 199.5685 162.72482)
		(end 199.5685 161.02482)
		(width 0.159)
		(layer "In5.Cu")
		(net 377)
	)
	(segment
		(start 203.1685 156.27482)
		(end 203.1685 145.52482)
		(width 0.159)
		(layer "In5.Cu")
		(net 377)
	)
	(segment
		(start 197.221958 164.871958)
		(end 197.421362 164.871958)
		(width 0.159)
		(layer "In5.Cu")
		(net 377)
	)
	(segment
		(start 202.0685 157.37482)
		(end 203.1685 156.27482)
		(width 0.159)
		(layer "In5.Cu")
		(net 377)
	)
	(segment
		(start 204.4685 142.3955)
		(end 204.323 142.25)
		(width 0.159)
		(layer "In5.Cu")
		(net 377)
	)
	(segment
		(start 199.5685 161.02482)
		(end 202.0685 158.52482)
		(width 0.159)
		(layer "In5.Cu")
		(net 377)
	)
	(segment
		(start 204.4685 144.22482)
		(end 204.4685 142.3955)
		(width 0.159)
		(layer "In5.Cu")
		(net 377)
	)
	(segment
		(start 198.655262 163.377843)
		(end 198.583669 163.30625)
		(width 0.159)
		(layer "In5.Cu")
		(net 377)
	)
	(segment
		(start 198.655261 163.63806)
		(end 198.655261 163.638059)
		(width 0.159)
		(layer "In5.Cu")
		(net 377)
	)
	(segment
		(start 198.908939 162.98098)
		(end 198.980533 163.052574)
		(width 0.159)
		(layer "In5.Cu")
		(net 377)
	)
	(segment
		(start 198.583669 163.046034)
		(end 198.648723 162.980981)
		(width 0.159)
		(layer "In5.Cu")
		(net 377)
	)
	(segment
		(start 203.1685 145.52482)
		(end 204.4685 144.22482)
		(width 0.159)
		(layer "In5.Cu")
		(net 377)
	)
	(segment
		(start 202.0685 158.52482)
		(end 202.0685 157.37482)
		(width 0.159)
		(layer "In5.Cu")
		(net 377)
	)
	(segment
		(start 199.240749 163.052574)
		(end 199.305801 162.98752)
		(width 0.159)
		(layer "In5.Cu")
		(net 377)
	)
	(segment
		(start 199.351044 162.942276)
		(end 199.5685 162.72482)
		(width 0.159)
		(layer "In5.Cu")
		(net 377)
	)
	(segment
		(start 197.933135 163.696583)
		(end 197.998191 163.631528)
		(width 0.159)
		(layer "In5.Cu")
		(net 377)
	)
	(arc
		(start 198.004721 164.288599)
		(mid 198.058614 164.158491)
		(end 198.004722 164.028383)
		(width 0.159)
		(layer "In5.Cu")
		(net 377)
	)
	(arc
		(start 198.980533 163.052574)
		(mid 199.110641 163.106466)
		(end 199.240749 163.052574)
		(width 0.159)
		(layer "In5.Cu")
		(net 377)
	)
	(arc
		(start 197.933136 163.956797)
		(mid 197.879244 163.826689)
		(end 197.933135 163.696583)
		(width 0.159)
		(layer "In5.Cu")
		(net 377)
	)
	(arc
		(start 198.329992 163.703116)
		(mid 198.460099 163.757009)
		(end 198.590208 163.703115)
		(width 0.159)
		(layer "In5.Cu")
		(net 377)
	)
	(arc
		(start 197.998191 163.631528)
		(mid 198.128299 163.577636)
		(end 198.258405 163.631529)
		(width 0.159)
		(layer "In5.Cu")
		(net 377)
	)
	(arc
		(start 198.583669 163.30625)
		(mid 198.529777 163.176142)
		(end 198.583669 163.046034)
		(width 0.159)
		(layer "In5.Cu")
		(net 377)
	)
	(arc
		(start 198.655261 163.638059)
		(mid 198.709154 163.507951)
		(end 198.655262 163.377843)
		(width 0.159)
		(layer "In5.Cu")
		(net 377)
	)
	(arc
		(start 198.648723 162.980981)
		(mid 198.778831 162.927089)
		(end 198.908939 162.98098)
		(width 0.159)
		(layer "In5.Cu")
		(net 377)
	)
	(segment
		(start 156.955 71.31)
		(end 156.98 71.31)
		(width 0.185)
		(layer "F.Cu")
		(net 378)
	)
	(segment
		(start 157.29 71.62)
		(end 157.6 71.62)
		(width 0.185)
		(layer "F.Cu")
		(net 378)
	)
	(segment
		(start 157.6 71.62)
		(end 157.61 71.61)
		(width 0.185)
		(layer "F.Cu")
		(net 378)
	)
	(segment
		(start 197.678042 165.140659)
		(end 197.678042 165.328042)
		(width 0.185)
		(layer "F.Cu")
		(net 378)
	)
	(segment
		(start 198.525 163.86)
		(end 198.465 163.92)
		(width 0.185)
		(layer "F.Cu")
		(net 378)
	)
	(segment
		(start 157.61 71.61)
		(end 158.5175 71.61)
		(width 0.185)
		(layer "F.Cu")
		(net 378)
	)
	(segment
		(start 158.5175 71.61)
		(end 158.65 71.4775)
		(width 0.185)
		(layer "F.Cu")
		(net 378)
	)
	(segment
		(start 198.465 164.353701)
		(end 197.678042 165.140659)
		(width 0.185)
		(layer "F.Cu")
		(net 378)
	)
	(segment
		(start 198.525 163.135)
		(end 198.525 163.86)
		(width 0.185)
		(layer "F.Cu")
		(net 378)
	)
	(segment
		(start 198.465 163.92)
		(end 198.465 164.353701)
		(width 0.185)
		(layer "F.Cu")
		(net 378)
	)
	(segment
		(start 156.98 71.31)
		(end 157.29 71.62)
		(width 0.185)
		(layer "F.Cu")
		(net 378)
	)
	(via
		(at 204.977 142.25)
		(size 0.45)
		(drill 0.1)
		(layers "F.Cu" "B.Cu")
		(teardrops
			(best_length_ratio 0.4)
			(max_length 1)
			(best_width_ratio 0.9)
			(max_width 2)
			(curved_edges yes)
			(filter_ratio 0.9)
			(enabled yes)
			(allow_two_segments yes)
			(prefer_zone_connections yes)
		)
		(net 378)
	)
	(via
		(at 197.678042 165.328042)
		(size 0.45)
		(drill 0.1)
		(layers "F.Cu" "B.Cu")
		(teardrops
			(best_length_ratio 0.4)
			(max_length 1)
			(best_width_ratio 0.9)
			(max_width 2)
			(curved_edges yes)
			(filter_ratio 0.9)
			(enabled yes)
			(allow_two_segments yes)
			(prefer_zone_connections yes)
		)
		(net 378)
	)
	(via
		(at 158.65 71.4775)
		(size 0.45)
		(drill 0.1)
		(layers "F.Cu" "B.Cu")
		(teardrops
			(best_length_ratio 0.4)
			(max_length 1)
			(best_width_ratio 0.9)
			(max_width 2)
			(curved_edges yes)
			(filter_ratio 0.9)
			(enabled yes)
			(allow_two_segments yes)
			(prefer_zone_connections yes)
		)
		(net 378)
	)
	(segment
		(start 204.84 142.113)
		(end 204.84 138.028702)
		(width 0.185)
		(layer "B.Cu")
		(net 378)
	)
	(segment
		(start 189.44 111.021298)
		(end 189.44 88.721298)
		(width 0.185)
		(layer "B.Cu")
		(net 378)
	)
	(segment
		(start 189.44 88.721298)
		(end 175.128702 74.41)
		(width 0.185)
		(layer "B.Cu")
		(net 378)
	)
	(segment
		(start 198.478702 114.21)
		(end 192.628702 114.21)
		(width 0.185)
		(layer "B.Cu")
		(net 378)
	)
	(segment
		(start 159.928702 71.61)
		(end 158.7825 71.61)
		(width 0.185)
		(layer "B.Cu")
		(net 378)
	)
	(segment
		(start 204.977 142.25)
		(end 204.84 142.113)
		(width 0.185)
		(layer "B.Cu")
		(net 378)
	)
	(segment
		(start 175.128702 74.41)
		(end 162.728702 74.41)
		(width 0.185)
		(layer "B.Cu")
		(net 378)
	)
	(segment
		(start 192.628702 114.21)
		(end 189.44 111.021298)
		(width 0.185)
		(layer "B.Cu")
		(net 378)
	)
	(segment
		(start 204.84 138.028702)
		(end 209.74 133.128702)
		(width 0.185)
		(layer "B.Cu")
		(net 378)
	)
	(segment
		(start 162.728702 74.41)
		(end 159.928702 71.61)
		(width 0.185)
		(layer "B.Cu")
		(net 378)
	)
	(segment
		(start 209.74 125.471298)
		(end 198.478702 114.21)
		(width 0.185)
		(layer "B.Cu")
		(net 378)
	)
	(segment
		(start 209.74 133.128702)
		(end 209.74 125.471298)
		(width 0.185)
		(layer "B.Cu")
		(net 378)
	)
	(segment
		(start 158.7825 71.61)
		(end 158.65 71.4775)
		(width 0.185)
		(layer "B.Cu")
		(net 378)
	)
	(segment
		(start 203.5315 145.67518)
		(end 204.8315 144.37518)
		(width 0.159)
		(layer "In5.Cu")
		(net 378)
	)
	(segment
		(start 202.4315 158.67518)
		(end 202.4315 157.52518)
		(width 0.159)
		(layer "In5.Cu")
		(net 378)
	)
	(segment
		(start 204.8315 142.3955)
		(end 204.977 142.25)
		(width 0.159)
		(layer "In5.Cu")
		(net 378)
	)
	(segment
		(start 203.5315 156.42518)
		(end 203.5315 145.67518)
		(width 0.159)
		(layer "In5.Cu")
		(net 378)
	)
	(segment
		(start 197.678042 165.128638)
		(end 199.9315 162.87518)
		(width 0.159)
		(layer "In5.Cu")
		(net 378)
	)
	(segment
		(start 202.4315 157.52518)
		(end 203.5315 156.42518)
		(width 0.159)
		(layer "In5.Cu")
		(net 378)
	)
	(segment
		(start 204.8315 144.37518)
		(end 204.8315 142.3955)
		(width 0.159)
		(layer "In5.Cu")
		(net 378)
	)
	(segment
		(start 199.9315 162.87518)
		(end 199.9315 161.17518)
		(width 0.159)
		(layer "In5.Cu")
		(net 378)
	)
	(segment
		(start 199.9315 161.17518)
		(end 202.4315 158.67518)
		(width 0.159)
		(layer "In5.Cu")
		(net 378)
	)
	(segment
		(start 197.678042 165.328042)
		(end 197.678042 165.128638)
		(width 0.159)
		(layer "In5.Cu")
		(net 378)
	)
	(segment
		(start 198.6 161.5)
		(end 199.025 161.925)
		(width 0.125)
		(layer "F.Cu")
		(net 379)
	)
	(segment
		(start 198.6 161.5)
		(end 198.05 161.5)
		(width 0.125)
		(layer "F.Cu")
		(net 379)
	)
	(segment
		(start 199.025 163.135)
		(end 199.025 161.925)
		(width 0.125)
		(layer "F.Cu")
		(net 379)
	)
	(via
		(at 198.05 161.5)
		(size 0.45)
		(drill 0.1)
		(layers "F.Cu" "B.Cu")
		(teardrops
			(best_length_ratio 0.4)
			(max_length 1)
			(best_width_ratio 0.9)
			(max_width 2)
			(curved_edges yes)
			(filter_ratio 0.9)
			(enabled yes)
			(allow_two_segments yes)
			(prefer_zone_connections yes)
		)
		(net 379)
	)
	(segment
		(start 195.65 162.5)
		(end 197.725 162.5)
		(width 0.125)
		(layer "B.Cu")
		(net 379)
	)
	(segment
		(start 198.05 162.175)
		(end 198.05 161.5)
		(width 0.125)
		(layer "B.Cu")
		(net 379)
	)
	(segment
		(start 197.725 162.5)
		(end 198.05 162.175)
		(width 0.125)
		(layer "B.Cu")
		(net 379)
	)
	(segment
		(start 195.45 162.7)
		(end 195.65 162.5)
		(width 0.125)
		(layer "B.Cu")
		(net 379)
	)
	(segment
		(start 195.45 163.325)
		(end 195.45 162.7)
		(width 0.125)
		(layer "B.Cu")
		(net 379)
	)
	(segment
		(start 199.525 162.05)
		(end 198.475 161)
		(width 0.125)
		(layer "F.Cu")
		(net 380)
	)
	(segment
		(start 198.475 161)
		(end 197.375 161)
		(width 0.125)
		(layer "F.Cu")
		(net 380)
	)
	(segment
		(start 199.525 163.135)
		(end 199.525 162.05)
		(width 0.125)
		(layer "F.Cu")
		(net 380)
	)
	(segment
		(start 197.375 161)
		(end 196.175 159.8)
		(width 0.125)
		(layer "F.Cu")
		(net 380)
	)
	(via
		(at 196.175 159.8)
		(size 0.45)
		(drill 0.1)
		(layers "F.Cu" "B.Cu")
		(teardrops
			(best_length_ratio 0.4)
			(max_length 1)
			(best_width_ratio 0.9)
			(max_width 2)
			(curved_edges yes)
			(filter_ratio 0.9)
			(enabled yes)
			(allow_two_segments yes)
			(prefer_zone_connections yes)
		)
		(net 380)
	)
	(segment
		(start 194.05 161.525)
		(end 194.8 160.775)
		(width 0.125)
		(layer "B.Cu")
		(net 380)
	)
	(segment
		(start 194.25 162.45)
		(end 194.05 162.25)
		(width 0.125)
		(layer "B.Cu")
		(net 380)
	)
	(segment
		(start 196.175 159.825)
		(end 196.175 159.8)
		(width 0.125)
		(layer "B.Cu")
		(net 380)
	)
	(segment
		(start 195.225 160.775)
		(end 196.175 159.825)
		(width 0.125)
		(layer "B.Cu")
		(net 380)
	)
	(segment
		(start 194.8 160.775)
		(end 195.225 160.775)
		(width 0.125)
		(layer "B.Cu")
		(net 380)
	)
	(segment
		(start 194.25 163.325)
		(end 194.25 162.45)
		(width 0.125)
		(layer "B.Cu")
		(net 380)
	)
	(segment
		(start 194.05 162.25)
		(end 194.05 161.525)
		(width 0.125)
		(layer "B.Cu")
		(net 380)
	)
	(segment
		(start 197.775 160.65)
		(end 197.725 160.65)
		(width 0.125)
		(layer "F.Cu")
		(net 381)
	)
	(segment
		(start 200.025 163.135)
		(end 200.025 162.025)
		(width 0.125)
		(layer "F.Cu")
		(net 381)
	)
	(segment
		(start 193.45 158.5)
		(end 195.575 158.5)
		(width 0.125)
		(layer "F.Cu")
		(net 381)
	)
	(segment
		(start 198.65 160.65)
		(end 200.025 162.025)
		(width 0.125)
		(layer "F.Cu")
		(net 381)
	)
	(segment
		(start 195.575 158.5)
		(end 197.725 160.65)
		(width 0.125)
		(layer "F.Cu")
		(net 381)
	)
	(segment
		(start 193.45 158.5)
		(end 192.9 159.05)
		(width 0.125)
		(layer "F.Cu")
		(net 381)
	)
	(segment
		(start 198.65 160.65)
		(end 197.775 160.65)
		(width 0.125)
		(layer "F.Cu")
		(net 381)
	)
	(via
		(at 192.9 159.05)
		(size 0.45)
		(drill 0.1)
		(layers "F.Cu" "B.Cu")
		(teardrops
			(best_length_ratio 0.4)
			(max_length 1)
			(best_width_ratio 0.9)
			(max_width 2)
			(curved_edges yes)
			(filter_ratio 0.9)
			(enabled yes)
			(allow_two_segments yes)
			(prefer_zone_connections yes)
		)
		(net 381)
	)
	(segment
		(start 193.575 162.825)
		(end 193.575 159.725)
		(width 0.125)
		(layer "B.Cu")
		(net 381)
	)
	(segment
		(start 193.575 159.725)
		(end 192.9 159.05)
		(width 0.125)
		(layer "B.Cu")
		(net 381)
	)
	(segment
		(start 193.05 163.35)
		(end 193.575 162.825)
		(width 0.125)
		(layer "B.Cu")
		(net 381)
	)
	(segment
		(start 286.15 153.35)
		(end 286.1 153.3)
		(width 0.125)
		(layer "F.Cu")
		(net 382)
	)
	(segment
		(start 307.72 156.19)
		(end 306.65 156.19)
		(width 0.125)
		(layer "F.Cu")
		(net 382)
	)
	(segment
		(start 289.46 153.86)
		(end 299.95 153.86)
		(width 0.125)
		(layer "F.Cu")
		(net 382)
	)
	(segment
		(start 289.46 153.86)
		(end 288.95 153.35)
		(width 0.125)
		(layer "F.Cu")
		(net 382)
	)
	(segment
		(start 302.28 156.19)
		(end 306.65 156.19)
		(width 0.125)
		(layer "F.Cu")
		(net 382)
	)
	(segment
		(start 308.256 155.182)
		(end 308.256 156.004)
		(width 0.125)
		(layer "F.Cu")
		(net 382)
	)
	(segment
		(start 308.256 156.004)
		(end 308.07 156.19)
		(width 0.125)
		(layer "F.Cu")
		(net 382)
	)
	(segment
		(start 308.07 156.19)
		(end 307.6 156.19)
		(width 0.125)
		(layer "F.Cu")
		(net 382)
	)
	(segment
		(start 299.95 153.86)
		(end 302.28 156.19)
		(width 0.125)
		(layer "F.Cu")
		(net 382)
	)
	(segment
		(start 200.525 164.475)
		(end 201.4 165.35)
		(width 0.125)
		(layer "F.Cu")
		(net 382)
	)
	(segment
		(start 200.525 163.135)
		(end 200.525 164.475)
		(width 0.125)
		(layer "F.Cu")
		(net 382)
	)
	(segment
		(start 201.4 165.35)
		(end 203.2 165.35)
		(width 0.125)
		(layer "F.Cu")
		(net 382)
	)
	(segment
		(start 307.758 156.152)
		(end 307.72 156.19)
		(width 0.125)
		(layer "F.Cu")
		(net 382)
	)
	(segment
		(start 307.758 155.182)
		(end 307.758 156.152)
		(width 0.125)
		(layer "F.Cu")
		(net 382)
	)
	(segment
		(start 288.95 153.35)
		(end 286.15 153.35)
		(width 0.125)
		(layer "F.Cu")
		(net 382)
	)
	(via
		(at 203.2 165.35)
		(size 0.45)
		(drill 0.1)
		(layers "F.Cu" "B.Cu")
		(teardrops
			(best_length_ratio 0.4)
			(max_length 1)
			(best_width_ratio 0.9)
			(max_width 2)
			(curved_edges yes)
			(filter_ratio 0.9)
			(enabled yes)
			(allow_two_segments yes)
			(prefer_zone_connections yes)
		)
		(net 382)
	)
	(via
		(at 286.1 153.3)
		(size 0.45)
		(drill 0.1)
		(layers "F.Cu" "B.Cu")
		(teardrops
			(best_length_ratio 0.4)
			(max_length 1)
			(best_width_ratio 0.9)
			(max_width 2)
			(curved_edges yes)
			(filter_ratio 0.9)
			(enabled yes)
			(allow_two_segments yes)
			(prefer_zone_connections yes)
		)
		(net 382)
	)
	(segment
		(start 209.88 163.17)
		(end 209.01 164.04)
		(width 0.125)
		(layer "In2.Cu")
		(net 382)
	)
	(segment
		(start 243.75 152.4)
		(end 242.6 153.55)
		(width 0.125)
		(layer "In2.Cu")
		(net 382)
	)
	(segment
		(start 227.3 163.17)
		(end 209.88 163.17)
		(width 0.125)
		(layer "In2.Cu")
		(net 382)
	)
	(segment
		(start 259.05 152.4)
		(end 243.75 152.4)
		(width 0.125)
		(layer "In2.Cu")
		(net 382)
	)
	(segment
		(start 209.01 164.04)
		(end 209.01 165.69)
		(width 0.125)
		(layer "In2.Cu")
		(net 382)
	)
	(segment
		(start 236.92 153.55)
		(end 227.3 163.17)
		(width 0.125)
		(layer "In2.Cu")
		(net 382)
	)
	(segment
		(start 242.6 153.55)
		(end 236.92 153.55)
		(width 0.125)
		(layer "In2.Cu")
		(net 382)
	)
	(segment
		(start 205.45 167.6)
		(end 203.2 165.35)
		(width 0.125)
		(layer "In2.Cu")
		(net 382)
	)
	(segment
		(start 209.01 165.69)
		(end 207.1 167.6)
		(width 0.125)
		(layer "In2.Cu")
		(net 382)
	)
	(segment
		(start 207.1 167.6)
		(end 205.45 167.6)
		(width 0.125)
		(layer "In2.Cu")
		(net 382)
	)
	(segment
		(start 259.95 153.3)
		(end 259.05 152.4)
		(width 0.125)
		(layer "In2.Cu")
		(net 382)
	)
	(segment
		(start 286.1 153.3)
		(end 259.95 153.3)
		(width 0.125)
		(layer "In2.Cu")
		(net 382)
	)
	(segment
		(start 110.94 136.81)
		(end 111.03 136.9)
		(width 0.182)
		(layer "F.Cu")
		(net 385)
	)
	(segment
		(start 109.505 136.81)
		(end 110.94 136.81)
		(width 0.182)
		(layer "F.Cu")
		(net 385)
	)
	(segment
		(start 111.03 136.9)
		(end 113.26 136.9)
		(width 0.182)
		(layer "F.Cu")
		(net 385)
	)
	(segment
		(start 113.26 136.9)
		(end 113.5 136.66)
		(width 0.182)
		(layer "F.Cu")
		(net 385)
	)
	(segment
		(start 202.525 161.925)
		(end 202.55 161.9)
		(width 0.182)
		(layer "F.Cu")
		(net 385)
	)
	(segment
		(start 202.525 163.135)
		(end 202.525 161.925)
		(width 0.182)
		(layer "F.Cu")
		(net 385)
	)
	(via
		(at 113.5 136.66)
		(size 0.45)
		(drill 0.1)
		(layers "F.Cu" "B.Cu")
		(remove_unused_layers yes)
		(keep_end_layers yes)
		(zone_layer_connections "In5.Cu")
		(teardrops
			(best_length_ratio 0.4)
			(max_length 1)
			(best_width_ratio 0.9)
			(max_width 2)
			(curved_edges yes)
			(filter_ratio 0.9)
			(enabled yes)
			(allow_two_segments yes)
			(prefer_zone_connections yes)
		)
		(net 385)
	)
	(via
		(at 202.55 161.9)
		(size 0.45)
		(drill 0.1)
		(layers "F.Cu" "B.Cu")
		(teardrops
			(best_length_ratio 0.4)
			(max_length 1)
			(best_width_ratio 0.9)
			(max_width 2)
			(curved_edges yes)
			(filter_ratio 0.9)
			(enabled yes)
			(allow_two_segments yes)
			(prefer_zone_connections yes)
		)
		(net 385)
	)
	(via
		(at 165.6 162)
		(size 0.45)
		(drill 0.1)
		(layers "F.Cu" "B.Cu")
		(teardrops
			(best_length_ratio 0.4)
			(max_length 1)
			(best_width_ratio 0.9)
			(max_width 2)
			(curved_edges yes)
			(filter_ratio 0.9)
			(enabled yes)
			(allow_two_segments yes)
			(prefer_zone_connections yes)
		)
		(net 385)
	)
	(segment
		(start 165.6 162)
		(end 164.8 161.2)
		(width 0.155)
		(layer "In2.Cu")
		(net 385)
	)
	(segment
		(start 200.975 160.325)
		(end 202.55 161.9)
		(width 0.155)
		(layer "In2.Cu")
		(net 385)
	)
	(segment
		(start 195.4 158.35)
		(end 197.375 160.325)
		(width 0.155)
		(layer "In2.Cu")
		(net 385)
	)
	(segment
		(start 189 159.8)
		(end 190.45 158.35)
		(width 0.155)
		(layer "In2.Cu")
		(net 385)
	)
	(segment
		(start 197.375 160.325)
		(end 200.975 160.325)
		(width 0.155)
		(layer "In2.Cu")
		(net 385)
	)
	(segment
		(start 164.8 160.05)
		(end 165.45 159.4)
		(width 0.155)
		(layer "In2.Cu")
		(net 385)
	)
	(segment
		(start 180.1 159.8)
		(end 189 159.8)
		(width 0.155)
		(layer "In2.Cu")
		(net 385)
	)
	(segment
		(start 165.8 158.4)
		(end 178.7 158.4)
		(width 0.155)
		(layer "In2.Cu")
		(net 385)
	)
	(segment
		(start 165.45 158.75)
		(end 165.8 158.4)
		(width 0.155)
		(layer "In2.Cu")
		(net 385)
	)
	(segment
		(start 178.7 158.4)
		(end 180.1 159.8)
		(width 0.155)
		(layer "In2.Cu")
		(net 385)
	)
	(segment
		(start 165.45 159.4)
		(end 165.45 158.75)
		(width 0.155)
		(layer "In2.Cu")
		(net 385)
	)
	(segment
		(start 190.45 158.35)
		(end 195.4 158.35)
		(width 0.155)
		(layer "In2.Cu")
		(net 385)
	)
	(segment
		(start 164.8 161.2)
		(end 164.8 160.05)
		(width 0.155)
		(layer "In2.Cu")
		(net 385)
	)
	(segment
		(start 119.89995 140.956)
		(end 119.89995 141.04)
		(width 0.155)
		(layer "In5.Cu")
		(net 385)
	)
	(segment
		(start 121.039069 146.189069)
		(end 120.768982 146.459155)
		(width 0.155)
		(layer "In5.Cu")
		(net 385)
	)
	(segment
		(start 120.623292 146.010878)
		(end 120.742086 145.892084)
		(width 0.155)
		(layer "In5.Cu")
		(net 385)
	)
	(segment
		(start 119.4 143.308)
		(end 119.568 143.308)
		(width 0.155)
		(layer "In5.Cu")
		(net 385)
	)
	(segment
		(start 153.95 151.8)
		(end 155.4 153.25)
		(width 0.155)
		(layer "In5.Cu")
		(net 385)
	)
	(segment
		(start 136.5175 147.2625)
		(end 136.73 147.05)
		(width 0.155)
		(layer "In5.Cu")
		(net 385)
	)
	(segment
		(start 118.75005 141.376)
		(end 118.75005 141.46)
		(width 0.155)
		(layer "In5.Cu")
		(net 385)
	)
	(segment
		(start 120.742086 145.892084)
		(end 120.742086 145.892086)
		(width 0.155)
		(layer "In5.Cu")
		(net 385)
	)
	(segment
		(start 119.568 138.268)
		(end 119.731953 138.268)
		(width 0.155)
		(layer "In5.Cu")
		(net 385)
	)
	(segment
		(start 132.83 147.075)
		(end 133.08 147.325)
		(width 0.155)
		(layer "In5.Cu")
		(net 385)
	)
	(segment
		(start 122.05 147.2)
		(end 125.13 147.2)
		(width 0.155)
		(layer "In5.Cu")
		(net 385)
	)
	(segment
		(start 119.899953 138.436)
		(end 119.899953 138.52)
		(width 0.155)
		(layer "In5.Cu")
		(net 385)
	)
	(segment
		(start 119.899949 143.476)
		(end 119.899949 143.56)
		(width 0.155)
		(layer "In5.Cu")
		(net 385)
	)
	(segment
		(start 119.73234 145.119927)
		(end 119.581065 145.271201)
		(width 0.155)
		(layer "In5.Cu")
		(net 385)
	)
	(segment
		(start 119.731949 143.728)
		(end 119.568 143.728)
		(width 0.155)
		(layer "In5.Cu")
		(net 385)
	)
	(segment
		(start 127.78 147.05)
		(end 129.83 147.05)
		(width 0.155)
		(layer "In5.Cu")
		(net 385)
	)
	(segment
		(start 135.805 147.025)
		(end 136.0425 147.2625)
		(width 0.155)
		(layer "In5.Cu")
		(net 385)
	)
	(segment
		(start 119.4 137.95)
		(end 119.4 138.1)
		(width 0.155)
		(layer "In5.Cu")
		(net 385)
	)
	(segment
		(start 118.750049 140.536)
		(end 118.750049 140.62)
		(width 0.155)
		(layer "In5.Cu")
		(net 385)
	)
	(segment
		(start 133.73 147.025)
		(end 135.805 147.025)
		(width 0.155)
		(layer "In5.Cu")
		(net 385)
	)
	(segment
		(start 129.83 147.05)
		(end 130.13 147.35)
		(width 0.155)
		(layer "In5.Cu")
		(net 385)
	)
	(segment
		(start 119.568 138.688)
		(end 119.4 138.688)
		(width 0.155)
		(layer "In5.Cu")
		(net 385)
	)
	(segment
		(start 119.899953 140.116)
		(end 119.899953 140.2)
		(width 0.155)
		(layer "In5.Cu")
		(net 385)
	)
	(segment
		(start 136.73 147.05)
		(end 139.03 147.05)
		(width 0.155)
		(layer "In5.Cu")
		(net 385)
	)
	(segment
		(start 119.4 144.55)
		(end 119.73234 144.88234)
		(width 0.155)
		(layer "In5.Cu")
		(net 385)
	)
	(segment
		(start 120.742086 145.892086)
		(end 121.224257 145.409912)
		(width 0.155)
		(layer "In5.Cu")
		(net 385)
	)
	(segment
		(start 125.18 147.25)
		(end 127.58 147.25)
		(width 0.155)
		(layer "In5.Cu")
		(net 385)
	)
	(segment
		(start 127.58 147.25)
		(end 127.78 147.05)
		(width 0.155)
		(layer "In5.Cu")
		(net 385)
	)
	(segment
		(start 119.568 143.308)
		(end 119.731949 143.308)
		(width 0.155)
		(layer "In5.Cu")
		(net 385)
	)
	(segment
		(start 125.13 147.2)
		(end 125.18 147.25)
		(width 0.155)
		(layer "In5.Cu")
		(net 385)
	)
	(segment
		(start 156.25 158.25)
		(end 157.2 159.2)
		(width 0.155)
		(layer "In5.Cu")
		(net 385)
	)
	(segment
		(start 119.73195 141.208)
		(end 119.4 141.208)
		(width 0.155)
		(layer "In5.Cu")
		(net 385)
	)
	(segment
		(start 160 159.2)
		(end 162.2 161.4)
		(width 0.155)
		(layer "In5.Cu")
		(net 385)
	)
	(segment
		(start 121.454844 146.367257)
		(end 121.818297 146.003804)
		(width 0.155)
		(layer "In5.Cu")
		(net 385)
	)
	(segment
		(start 157.2 159.2)
		(end 160 159.2)
		(width 0.155)
		(layer "In5.Cu")
		(net 385)
	)
	(segment
		(start 119.4 142.888)
		(end 118.918049 142.888)
		(width 0.155)
		(layer "In5.Cu")
		(net 385)
	)
	(segment
		(start 155.4 156.1)
		(end 156.25 156.95)
		(width 0.155)
		(layer "In5.Cu")
		(net 385)
	)
	(segment
		(start 119.878049 145.568185)
		(end 120.029323 145.41691)
		(width 0.155)
		(layer "In5.Cu")
		(net 385)
	)
	(segment
		(start 121.336052 146.486052)
		(end 121.454844 146.367257)
		(width 0.155)
		(layer "In5.Cu")
		(net 385)
	)
	(segment
		(start 121.065966 146.756139)
		(end 121.336052 146.486052)
		(width 0.155)
		(layer "In5.Cu")
		(net 385)
	)
	(segment
		(start 118.91805 141.628)
		(end 119.4 141.628)
		(width 0.155)
		(layer "In5.Cu")
		(net 385)
	)
	(segment
		(start 118.918049 142.468)
		(end 119.4 142.468)
		(width 0.155)
		(layer "In5.Cu")
		(net 385)
	)
	(segment
		(start 121.751829 146.901829)
		(end 121.811226 146.961226)
		(width 0.155)
		(layer "In5.Cu")
		(net 385)
	)
	(segment
		(start 139.25 147.27)
		(end 139.25 149.225)
		(width 0.155)
		(layer "In5.Cu")
		(net 385)
	)
	(segment
		(start 119.4 141.628)
		(end 119.731949 141.628)
		(width 0.155)
		(layer "In5.Cu")
		(net 385)
	)
	(segment
		(start 120.266911 145.41691)
		(end 120.326309 145.476309)
		(width 0.155)
		(layer "In5.Cu")
		(net 385)
	)
	(segment
		(start 141.825 151.8)
		(end 153.95 151.8)
		(width 0.155)
		(layer "In5.Cu")
		(net 385)
	)
	(segment
		(start 119.4 141.208)
		(end 118.91805 141.208)
		(width 0.155)
		(layer "In5.Cu")
		(net 385)
	)
	(segment
		(start 120.175041 146.10275)
		(end 120.234437 146.162146)
		(width 0.155)
		(layer "In5.Cu")
		(net 385)
	)
	(segment
		(start 119.4 143.98)
		(end 119.4 144.55)
		(width 0.155)
		(layer "In5.Cu")
		(net 385)
	)
	(segment
		(start 119.581065 145.508789)
		(end 119.640461 145.568185)
		(width 0.155)
		(layer "In5.Cu")
		(net 385)
	)
	(segment
		(start 162.2 161.4)
		(end 165 161.4)
		(width 0.155)
		(layer "In5.Cu")
		(net 385)
	)
	(segment
		(start 133.43 147.325)
		(end 133.73 147.025)
		(width 0.155)
		(layer "In5.Cu")
		(net 385)
	)
	(segment
		(start 139.25 149.225)
		(end 141.825 151.8)
		(width 0.155)
		(layer "In5.Cu")
		(net 385)
	)
	(segment
		(start 156.25 156.95)
		(end 156.25 158.25)
		(width 0.155)
		(layer "In5.Cu")
		(net 385)
	)
	(segment
		(start 121.461847 145.409914)
		(end 121.521243 145.46931)
		(width 0.155)
		(layer "In5.Cu")
		(net 385)
	)
	(segment
		(start 119.4 138.688)
		(end 118.918049 138.688)
		(width 0.155)
		(layer "In5.Cu")
		(net 385)
	)
	(segment
		(start 139.03 147.05)
		(end 139.25 147.27)
		(width 0.155)
		(layer "In5.Cu")
		(net 385)
	)
	(segment
		(start 118.750049 138.856)
		(end 118.750049 138.94)
		(width 0.155)
		(layer "In5.Cu")
		(net 385)
	)
	(segment
		(start 119.899953 139.276)
		(end 119.899953 139.36)
		(width 0.155)
		(layer "In5.Cu")
		(net 385)
	)
	(segment
		(start 136.0425 147.2625)
		(end 136.5175 147.2625)
		(width 0.155)
		(layer "In5.Cu")
		(net 385)
	)
	(segment
		(start 119.4 139.108)
		(end 119.731953 139.108)
		(width 0.155)
		(layer "In5.Cu")
		(net 385)
	)
	(segment
		(start 118.918049 139.948)
		(end 119.4 139.948)
		(width 0.155)
		(layer "In5.Cu")
		(net 385)
	)
	(segment
		(start 118.918049 140.788)
		(end 119.4 140.788)
		(width 0.155)
		(layer "In5.Cu")
		(net 385)
	)
	(segment
		(start 118.750049 139.696)
		(end 118.750049 139.78)
		(width 0.155)
		(layer "In5.Cu")
		(net 385)
	)
	(segment
		(start 119.4 140.788)
		(end 119.73195 140.788)
		(width 0.155)
		(layer "In5.Cu")
		(net 385)
	)
	(segment
		(start 155.4 153.25)
		(end 155.4 156.1)
		(width 0.155)
		(layer "In5.Cu")
		(net 385)
	)
	(segment
		(start 130.13 147.35)
		(end 130.405 147.35)
		(width 0.155)
		(layer "In5.Cu")
		(net 385)
	)
	(segment
		(start 119.4 139.948)
		(end 119.731953 139.948)
		(width 0.155)
		(layer "In5.Cu")
		(net 385)
	)
	(segment
		(start 118.918049 143.308)
		(end 119.4 143.308)
		(width 0.155)
		(layer "In5.Cu")
		(net 385)
	)
	(segment
		(start 119.731953 138.688)
		(end 119.568 138.688)
		(width 0.155)
		(layer "In5.Cu")
		(net 385)
	)
	(segment
		(start 120.768982 146.696743)
		(end 120.828378 146.756139)
		(width 0.155)
		(layer "In5.Cu")
		(net 385)
	)
	(segment
		(start 119.731949 142.888)
		(end 119.4 142.888)
		(width 0.155)
		(layer "In5.Cu")
		(net 385)
	)
	(segment
		(start 130.68 147.075)
		(end 132.83 147.075)
		(width 0.155)
		(layer "In5.Cu")
		(net 385)
	)
	(segment
		(start 130.405 147.35)
		(end 130.68 147.075)
		(width 0.155)
		(layer "In5.Cu")
		(net 385)
	)
	(segment
		(start 121.811226 146.961226)
		(end 122.05 147.2)
		(width 0.155)
		(layer "In5.Cu")
		(net 385)
	)
	(segment
		(start 113.5 136.66)
		(end 118.11 136.66)
		(width 0.155)
		(layer "In5.Cu")
		(net 385)
	)
	(segment
		(start 118.11 136.66)
		(end 119.4 137.95)
		(width 0.155)
		(layer "In5.Cu")
		(net 385)
	)
	(segment
		(start 119.4 142.048)
		(end 118.918049 142.048)
		(width 0.155)
		(layer "In5.Cu")
		(net 385)
	)
	(segment
		(start 119.731953 139.528)
		(end 119.4 139.528)
		(width 0.155)
		(layer "In5.Cu")
		(net 385)
	)
	(segment
		(start 120.472025 146.162146)
		(end 120.623292 146.010878)
		(width 0.155)
		(layer "In5.Cu")
		(net 385)
	)
	(segment
		(start 119.899949 142.636)
		(end 119.899949 142.72)
		(width 0.155)
		(layer "In5.Cu")
		(net 385)
	)
	(segment
		(start 119.731953 140.368)
		(end 119.4 140.368)
		(width 0.155)
		(layer "In5.Cu")
		(net 385)
	)
	(segment
		(start 121.521243 145.706898)
		(end 121.039069 146.189069)
		(width 0.155)
		(layer "In5.Cu")
		(net 385)
	)
	(segment
		(start 119.4 140.368)
		(end 118.918049 140.368)
		(width 0.155)
		(layer "In5.Cu")
		(net 385)
	)
	(segment
		(start 118.918049 139.108)
		(end 119.4 139.108)
		(width 0.155)
		(layer "In5.Cu")
		(net 385)
	)
	(segment
		(start 165 161.4)
		(end 165.6 162)
		(width 0.155)
		(layer "In5.Cu")
		(net 385)
	)
	(segment
		(start 122.055887 146.003806)
		(end 122.115283 146.063202)
		(width 0.155)
		(layer "In5.Cu")
		(net 385)
	)
	(segment
		(start 119.4 143.896)
		(end 119.4 143.98)
		(width 0.155)
		(layer "In5.Cu")
		(net 385)
	)
	(segment
		(start 119.731949 142.048)
		(end 119.4 142.048)
		(width 0.155)
		(layer "In5.Cu")
		(net 385)
	)
	(segment
		(start 122.115283 146.30079)
		(end 121.751829 146.664241)
		(width 0.155)
		(layer "In5.Cu")
		(net 385)
	)
	(segment
		(start 119.4 139.528)
		(end 118.918049 139.528)
		(width 0.155)
		(layer "In5.Cu")
		(net 385)
	)
	(segment
		(start 118.750049 142.216)
		(end 118.750049 142.3)
		(width 0.155)
		(layer "In5.Cu")
		(net 385)
	)
	(segment
		(start 119.4 142.468)
		(end 119.731949 142.468)
		(width 0.155)
		(layer "In5.Cu")
		(net 385)
	)
	(segment
		(start 118.750049 143.056)
		(end 118.750049 143.14)
		(width 0.155)
		(layer "In5.Cu")
		(net 385)
	)
	(segment
		(start 120.326309 145.713896)
		(end 120.175041 145.865163)
		(width 0.155)
		(layer "In5.Cu")
		(net 385)
	)
	(segment
		(start 119.899949 141.796)
		(end 119.899949 141.88)
		(width 0.155)
		(layer "In5.Cu")
		(net 385)
	)
	(segment
		(start 133.08 147.325)
		(end 133.43 147.325)
		(width 0.155)
		(layer "In5.Cu")
		(net 385)
	)
	(arc
		(start 119.73195 140.788)
		(mid 119.850744 140.837206)
		(end 119.89995 140.956)
		(width 0.155)
		(layer "In5.Cu")
		(net 385)
	)
	(arc
		(start 118.75005 141.46)
		(mid 118.799256 141.578794)
		(end 118.91805 141.628)
		(width 0.155)
		(layer "In5.Cu")
		(net 385)
	)
	(arc
		(start 118.750049 140.62)
		(mid 118.799255 140.738794)
		(end 118.918049 140.788)
		(width 0.155)
		(layer "In5.Cu")
		(net 385)
	)
	(arc
		(start 119.899949 141.88)
		(mid 119.850743 141.998794)
		(end 119.731949 142.048)
		(width 0.155)
		(layer "In5.Cu")
		(net 385)
	)
	(arc
		(start 118.91805 141.208)
		(mid 118.799256 141.257206)
		(end 118.75005 141.376)
		(width 0.155)
		(layer "In5.Cu")
		(net 385)
	)
	(arc
		(start 119.899949 142.72)
		(mid 119.850743 142.838794)
		(end 119.731949 142.888)
		(width 0.155)
		(layer "In5.Cu")
		(net 385)
	)
	(arc
		(start 118.918049 140.368)
		(mid 118.799255 140.417206)
		(end 118.750049 140.536)
		(width 0.155)
		(layer "In5.Cu")
		(net 385)
	)
	(arc
		(start 119.731953 138.268)
		(mid 119.850747 138.317206)
		(end 119.899953 138.436)
		(width 0.155)
		(layer "In5.Cu")
		(net 385)
	)
	(arc
		(start 119.731949 141.628)
		(mid 119.850743 141.677206)
		(end 119.899949 141.796)
		(width 0.155)
		(layer "In5.Cu")
		(net 385)
	)
	(arc
		(start 120.326309 145.476309)
		(mid 120.375514 145.595103)
		(end 120.326309 145.713896)
		(width 0.155)
		(layer "In5.Cu")
		(net 385)
	)
	(arc
		(start 118.918049 139.528)
		(mid 118.799255 139.577206)
		(end 118.750049 139.696)
		(width 0.155)
		(layer "In5.Cu")
		(net 385)
	)
	(arc
		(start 121.751829 146.664241)
		(mid 121.702623 146.783035)
		(end 121.751829 146.901829)
		(width 0.155)
		(layer "In5.Cu")
		(net 385)
	)
	(arc
		(start 120.234437 146.162146)
		(mid 120.353231 146.211352)
		(end 120.472025 146.162146)
		(width 0.155)
		(layer "In5.Cu")
		(net 385)
	)
	(arc
		(start 118.750049 142.3)
		(mid 118.799255 142.418794)
		(end 118.918049 142.468)
		(width 0.155)
		(layer "In5.Cu")
		(net 385)
	)
	(arc
		(start 119.899949 143.56)
		(mid 119.850743 143.678794)
		(end 119.731949 143.728)
		(width 0.155)
		(layer "In5.Cu")
		(net 385)
	)
	(arc
		(start 119.640461 145.568185)
		(mid 119.759255 145.617391)
		(end 119.878049 145.568185)
		(width 0.155)
		(layer "In5.Cu")
		(net 385)
	)
	(arc
		(start 119.73234 144.88234)
		(mid 119.781545 145.001134)
		(end 119.73234 145.119927)
		(width 0.155)
		(layer "In5.Cu")
		(net 385)
	)
	(arc
		(start 118.750049 138.94)
		(mid 118.799255 139.058794)
		(end 118.918049 139.108)
		(width 0.155)
		(layer "In5.Cu")
		(net 385)
	)
	(arc
		(start 119.4 138.1)
		(mid 119.449206 138.218794)
		(end 119.568 138.268)
		(width 0.155)
		(layer "In5.Cu")
		(net 385)
	)
	(arc
		(start 121.224257 145.409912)
		(mid 121.343053 145.360708)
		(end 121.461847 145.409914)
		(width 0.155)
		(layer "In5.Cu")
		(net 385)
	)
	(arc
		(start 119.581065 145.271201)
		(mid 119.531859 145.389995)
		(end 119.581065 145.508789)
		(width 0.155)
		(layer "In5.Cu")
		(net 385)
	)
	(arc
		(start 120.029323 145.41691)
		(mid 120.148117 145.367704)
		(end 120.266911 145.41691)
		(width 0.155)
		(layer "In5.Cu")
		(net 385)
	)
	(arc
		(start 119.89995 141.04)
		(mid 119.850744 141.158794)
		(end 119.73195 141.208)
		(width 0.155)
		(layer "In5.Cu")
		(net 385)
	)
	(arc
		(start 120.768982 146.459155)
		(mid 120.719776 146.577949)
		(end 120.768982 146.696743)
		(width 0.155)
		(layer "In5.Cu")
		(net 385)
	)
	(arc
		(start 118.918049 142.888)
		(mid 118.799255 142.937206)
		(end 118.750049 143.056)
		(width 0.155)
		(layer "In5.Cu")
		(net 385)
	)
	(arc
		(start 122.115283 146.063202)
		(mid 122.164489 146.181996)
		(end 122.115283 146.30079)
		(width 0.155)
		(layer "In5.Cu")
		(net 385)
	)
	(arc
		(start 119.899953 139.36)
		(mid 119.850747 139.478794)
		(end 119.731953 139.528)
		(width 0.155)
		(layer "In5.Cu")
		(net 385)
	)
	(arc
		(start 118.750049 139.78)
		(mid 118.799255 139.898794)
		(end 118.918049 139.948)
		(width 0.155)
		(layer "In5.Cu")
		(net 385)
	)
	(arc
		(start 118.918049 138.688)
		(mid 118.799255 138.737206)
		(end 118.750049 138.856)
		(width 0.155)
		(layer "In5.Cu")
		(net 385)
	)
	(arc
		(start 118.750049 143.14)
		(mid 118.799255 143.258794)
		(end 118.918049 143.308)
		(width 0.155)
		(layer "In5.Cu")
		(net 385)
	)
	(arc
		(start 120.175041 145.865163)
		(mid 120.125835 145.983956)
		(end 120.175041 146.10275)
		(width 0.155)
		(layer "In5.Cu")
		(net 385)
	)
	(arc
		(start 119.731949 143.308)
		(mid 119.850743 143.357206)
		(end 119.899949 143.476)
		(width 0.155)
		(layer "In5.Cu")
		(net 385)
	)
	(arc
		(start 119.731949 142.468)
		(mid 119.850743 142.517206)
		(end 119.899949 142.636)
		(width 0.155)
		(layer "In5.Cu")
		(net 385)
	)
	(arc
		(start 121.521243 145.46931)
		(mid 121.570449 145.588104)
		(end 121.521243 145.706898)
		(width 0.155)
		(layer "In5.Cu")
		(net 385)
	)
	(arc
		(start 119.899953 140.2)
		(mid 119.850747 140.318794)
		(end 119.731953 140.368)
		(width 0.155)
		(layer "In5.Cu")
		(net 385)
	)
	(arc
		(start 119.731953 139.108)
		(mid 119.850747 139.157206)
		(end 119.899953 139.276)
		(width 0.155)
		(layer "In5.Cu")
		(net 385)
	)
	(arc
		(start 119.731953 139.948)
		(mid 119.850747 139.997206)
		(end 119.899953 140.116)
		(width 0.155)
		(layer "In5.Cu")
		(net 385)
	)
	(arc
		(start 119.899953 138.52)
		(mid 119.850747 138.638794)
		(end 119.731953 138.688)
		(width 0.155)
		(layer "In5.Cu")
		(net 385)
	)
	(arc
		(start 118.918049 142.048)
		(mid 118.799255 142.097206)
		(end 118.750049 142.216)
		(width 0.155)
		(layer "In5.Cu")
		(net 385)
	)
	(arc
		(start 120.828378 146.756139)
		(mid 120.947172 146.805345)
		(end 121.065966 146.756139)
		(width 0.155)
		(layer "In5.Cu")
		(net 385)
	)
	(arc
		(start 119.568 143.728)
		(mid 119.449206 143.777206)
		(end 119.4 143.896)
		(width 0.155)
		(layer "In5.Cu")
		(net 385)
	)
	(arc
		(start 121.818297 146.003804)
		(mid 121.937093 145.9546)
		(end 122.055887 146.003806)
		(width 0.155)
		(layer "In5.Cu")
		(net 385)
	)
	(segment
		(start 204.025 163.135)
		(end 204.025 162.325)
		(width 0.125)
		(layer "F.Cu")
		(net 386)
	)
	(segment
		(start 203.25 160.175)
		(end 203.075 160)
		(width 0.125)
		(layer "F.Cu")
		(net 386)
	)
	(segment
		(start 203.075 160)
		(end 202.48 160)
		(width 0.125)
		(layer "F.Cu")
		(net 386)
	)
	(segment
		(start 203.25 161.8725)
		(end 203.25 160.175)
		(width 0.125)
		(layer "F.Cu")
		(net 386)
	)
	(segment
		(start 204.025 162.325)
		(end 203.7725 162.0725)
		(width 0.125)
		(layer "F.Cu")
		(net 386)
	)
	(segment
		(start 203.45 162.0725)
		(end 203.25 161.8725)
		(width 0.125)
		(layer "F.Cu")
		(net 386)
	)
	(segment
		(start 203.7725 162.0725)
		(end 203.45 162.0725)
		(width 0.125)
		(layer "F.Cu")
		(net 386)
	)
	(segment
		(start 219.5 163.16)
		(end 219.525 163.135)
		(width 0.2)
		(layer "F.Cu")
		(net 389)
	)
	(segment
		(start 219.5 164.5)
		(end 219.5 163.16)
		(width 0.2)
		(layer "F.Cu")
		(net 389)
	)
	(via
		(at 219.5 164.5)
		(size 0.45)
		(drill 0.1)
		(layers "F.Cu" "B.Cu")
		(teardrops
			(best_length_ratio 0.4)
			(max_length 1)
			(best_width_ratio 0.9)
			(max_width 2)
			(curved_edges yes)
			(filter_ratio 0.9)
			(enabled yes)
			(allow_two_segments yes)
			(prefer_zone_connections yes)
		)
		(net 389)
	)
	(segment
		(start 219.5 165.22)
		(end 219.5 164.5)
		(width 0.2)
		(layer "B.Cu")
		(net 389)
	)
	(segment
		(start 257.865 163.835)
		(end 257.9 163.8)
		(width 0.13)
		(layer "F.Cu")
		(net 397)
	)
	(segment
		(start 224.025 164.325)
		(end 224.05 164.35)
		(width 0.125)
		(layer "F.Cu")
		(net 397)
	)
	(segment
		(start 224.025 163.135)
		(end 224.025 164.325)
		(width 0.125)
		(layer "F.Cu")
		(net 397)
	)
	(segment
		(start 256.523145 163.835)
		(end 257.865 163.835)
		(width 0.13)
		(layer "F.Cu")
		(net 397)
	)
	(via
		(at 257.9 163.8)
		(size 0.45)
		(drill 0.1)
		(layers "F.Cu" "B.Cu")
		(teardrops
			(best_length_ratio 0.4)
			(max_length 1)
			(best_width_ratio 0.9)
			(max_width 2)
			(curved_edges yes)
			(filter_ratio 0.9)
			(enabled yes)
			(allow_two_segments yes)
			(prefer_zone_connections yes)
		)
		(net 397)
	)
	(via
		(at 224.05 164.35)
		(size 0.45)
		(drill 0.1)
		(layers "F.Cu" "B.Cu")
		(teardrops
			(best_length_ratio 0.4)
			(max_length 1)
			(best_width_ratio 0.9)
			(max_width 2)
			(curved_edges yes)
			(filter_ratio 0.9)
			(enabled yes)
			(allow_two_segments yes)
			(prefer_zone_connections yes)
		)
		(net 397)
	)
	(segment
		(start 249.35 158.8)
		(end 252.75 162.2)
		(width 0.125)
		(layer "In2.Cu")
		(net 397)
	)
	(segment
		(start 258.38 162.77)
		(end 258.38 163.32)
		(width 0.125)
		(layer "In2.Cu")
		(net 397)
	)
	(segment
		(start 257.81 162.2)
		(end 258.38 162.77)
		(width 0.125)
		(layer "In2.Cu")
		(net 397)
	)
	(segment
		(start 224.65 164.35)
		(end 225.2 164.9)
		(width 0.125)
		(layer "In2.Cu")
		(net 397)
	)
	(segment
		(start 230.7525 161.3475)
		(end 243.0025 161.3475)
		(width 0.125)
		(layer "In2.Cu")
		(net 397)
	)
	(segment
		(start 225.2 164.9)
		(end 227.2 164.9)
		(width 0.125)
		(layer "In2.Cu")
		(net 397)
	)
	(segment
		(start 243.0025 161.3475)
		(end 245.55 158.8)
		(width 0.125)
		(layer "In2.Cu")
		(net 397)
	)
	(segment
		(start 245.55 158.8)
		(end 249.35 158.8)
		(width 0.125)
		(layer "In2.Cu")
		(net 397)
	)
	(segment
		(start 224.05 164.35)
		(end 224.65 164.35)
		(width 0.125)
		(layer "In2.Cu")
		(net 397)
	)
	(segment
		(start 258.38 163.32)
		(end 257.9 163.8)
		(width 0.125)
		(layer "In2.Cu")
		(net 397)
	)
	(segment
		(start 252.75 162.2)
		(end 257.81 162.2)
		(width 0.125)
		(layer "In2.Cu")
		(net 397)
	)
	(segment
		(start 227.2 164.9)
		(end 230.7525 161.3475)
		(width 0.125)
		(layer "In2.Cu")
		(net 397)
	)
	(segment
		(start 232.822707 79.072)
		(end 234.070708 79.072)
		(width 0.125)
		(layer "F.Cu")
		(net 400)
	)
	(segment
		(start 240.415 77.185)
		(end 241.420708 77.185)
		(width 0.125)
		(layer "F.Cu")
		(net 400)
	)
	(segment
		(start 226.025 162.075)
		(end 226.1 162)
		(width 0.125)
		(layer "F.Cu")
		(net 400)
	)
	(segment
		(start 240 77.6)
		(end 240.415 77.185)
		(width 0.125)
		(layer "F.Cu")
		(net 400)
	)
	(segment
		(start 226.025 163.135)
		(end 226.025 162.075)
		(width 0.125)
		(layer "F.Cu")
		(net 400)
	)
	(segment
		(start 240 78.02)
		(end 240 77.6)
		(width 0.125)
		(layer "F.Cu")
		(net 400)
	)
	(via
		(at 226.1 162)
		(size 0.45)
		(drill 0.1)
		(layers "F.Cu" "B.Cu")
		(teardrops
			(best_length_ratio 0.4)
			(max_length 1)
			(best_width_ratio 0.9)
			(max_width 2)
			(curved_edges yes)
			(filter_ratio 0.9)
			(enabled yes)
			(allow_two_segments yes)
			(prefer_zone_connections yes)
		)
		(net 400)
	)
	(via
		(at 255.150707 77.185)
		(size 0.45)
		(drill 0.1)
		(layers "F.Cu" "B.Cu")
		(remove_unused_layers yes)
		(keep_end_layers yes)
		(zone_layer_connections "In5.Cu")
		(teardrops
			(best_length_ratio 0.4)
			(max_length 1)
			(best_width_ratio 0.9)
			(max_width 2)
			(curved_edges yes)
			(filter_ratio 0.9)
			(enabled yes)
			(allow_two_segments yes)
			(prefer_zone_connections yes)
		)
		(net 400)
	)
	(via
		(at 234.070708 79.072)
		(size 0.45)
		(drill 0.1)
		(layers "F.Cu" "B.Cu")
		(remove_unused_layers yes)
		(keep_end_layers yes)
		(zone_layer_connections "In2.Cu" "In5.Cu")
		(teardrops
			(best_length_ratio 0.4)
			(max_length 1)
			(best_width_ratio 0.9)
			(max_width 2)
			(curved_edges yes)
			(filter_ratio 0.9)
			(enabled yes)
			(allow_two_segments yes)
			(prefer_zone_connections yes)
		)
		(net 400)
	)
	(via
		(at 241.420708 77.185)
		(size 0.45)
		(drill 0.1)
		(layers "F.Cu" "B.Cu")
		(remove_unused_layers yes)
		(keep_end_layers yes)
		(zone_layer_connections "In5.Cu")
		(teardrops
			(best_length_ratio 0.4)
			(max_length 1)
			(best_width_ratio 0.9)
			(max_width 2)
			(curved_edges yes)
			(filter_ratio 0.9)
			(enabled yes)
			(allow_two_segments yes)
			(prefer_zone_connections yes)
		)
		(net 400)
	)
	(segment
		(start 213.15 131.46)
		(end 213.15 125.51)
		(width 0.125)
		(layer "In2.Cu")
		(net 400)
	)
	(segment
		(start 218.3 144.3)
		(end 217.3875 143.3875)
		(width 0.125)
		(layer "In2.Cu")
		(net 400)
	)
	(segment
		(start 218.1 136.41)
		(end 213.15 131.46)
		(width 0.125)
		(layer "In2.Cu")
		(net 400)
	)
	(segment
		(start 218.1 141.6)
		(end 218.1 136.41)
		(width 0.125)
		(layer "In2.Cu")
		(net 400)
	)
	(segment
		(start 217.3875 142.3125)
		(end 218.1 141.6)
		(width 0.125)
		(layer "In2.Cu")
		(net 400)
	)
	(segment
		(start 229.725 143.775)
		(end 229.725 143.1)
		(width 0.125)
		(layer "In2.Cu")
		(net 400)
	)
	(segment
		(start 213.15 125.51)
		(end 204.75 117.11)
		(width 0.125)
		(layer "In2.Cu")
		(net 400)
	)
	(segment
		(start 226.425 162.325)
		(end 226.725 162.325)
		(width 0.125)
		(layer "In2.Cu")
		(net 400)
	)
	(segment
		(start 224.3 142.6)
		(end 222.6 144.3)
		(width 0.125)
		(layer "In2.Cu")
		(net 400)
	)
	(segment
		(start 215.575 81.26)
		(end 231.882708 81.26)
		(width 0.125)
		(layer "In2.Cu")
		(net 400)
	)
	(segment
		(start 204.75 92.085)
		(end 215.575 81.26)
		(width 0.125)
		(layer "In2.Cu")
		(net 400)
	)
	(segment
		(start 229.225 142.6)
		(end 224.3 142.6)
		(width 0.125)
		(layer "In2.Cu")
		(net 400)
	)
	(segment
		(start 231.882708 81.26)
		(end 234.070708 79.072)
		(width 0.125)
		(layer "In2.Cu")
		(net 400)
	)
	(segment
		(start 228.4 160.65)
		(end 228.4 145.1)
		(width 0.125)
		(layer "In2.Cu")
		(net 400)
	)
	(segment
		(start 228.4 145.1)
		(end 229.725 143.775)
		(width 0.125)
		(layer "In2.Cu")
		(net 400)
	)
	(segment
		(start 217.3875 143.3875)
		(end 217.3875 142.3125)
		(width 0.125)
		(layer "In2.Cu")
		(net 400)
	)
	(segment
		(start 204.75 117.11)
		(end 204.75 92.085)
		(width 0.125)
		(layer "In2.Cu")
		(net 400)
	)
	(segment
		(start 222.6 144.3)
		(end 218.3 144.3)
		(width 0.125)
		(layer "In2.Cu")
		(net 400)
	)
	(segment
		(start 226.1 162)
		(end 226.425 162.325)
		(width 0.125)
		(layer "In2.Cu")
		(net 400)
	)
	(segment
		(start 226.725 162.325)
		(end 228.4 160.65)
		(width 0.125)
		(layer "In2.Cu")
		(net 400)
	)
	(segment
		(start 229.725 143.1)
		(end 229.225 142.6)
		(width 0.125)
		(layer "In2.Cu")
		(net 400)
	)
	(segment
		(start 244.570708 77.185)
		(end 244.133208 77.6225)
		(width 0.125)
		(layer "In5.Cu")
		(net 400)
	)
	(segment
		(start 244.133208 77.6225)
		(end 241.858208 77.6225)
		(width 0.125)
		(layer "In5.Cu")
		(net 400)
	)
	(segment
		(start 234.070708 79.072)
		(end 235.957708 77.185)
		(width 0.125)
		(layer "In5.Cu")
		(net 400)
	)
	(segment
		(start 235.957708 77.185)
		(end 241.420708 77.185)
		(width 0.125)
		(layer "In5.Cu")
		(net 400)
	)
	(segment
		(start 241.858208 77.6225)
		(end 241.420708 77.185)
		(width 0.125)
		(layer "In5.Cu")
		(net 400)
	)
	(segment
		(start 255.150707 77.185)
		(end 244.570708 77.185)
		(width 0.125)
		(layer "In5.Cu")
		(net 400)
	)
	(segment
		(start 226.525 161.775)
		(end 226.525 163.135)
		(width 0.125)
		(layer "F.Cu")
		(net 401)
	)
	(segment
		(start 237.121707 79.072)
		(end 238.908001 79.072)
		(width 0.125)
		(layer "F.Cu")
		(net 401)
	)
	(segment
		(start 237.121707 79.072)
		(end 235.958708 79.072)
		(width 0.125)
		(layer "F.Cu")
		(net 401)
	)
	(segment
		(start 235.958708 79.072)
		(end 235.920708 79.11)
		(width 0.125)
		(layer "F.Cu")
		(net 401)
	)
	(segment
		(start 226.6 161.7)
		(end 226.525 161.775)
		(width 0.125)
		(layer "F.Cu")
		(net 401)
	)
	(segment
		(start 238.908001 79.072)
		(end 239.000001 78.98)
		(width 0.125)
		(layer "F.Cu")
		(net 401)
	)
	(via
		(at 226.6 161.7)
		(size 0.45)
		(drill 0.1)
		(layers "F.Cu" "B.Cu")
		(teardrops
			(best_length_ratio 0.4)
			(max_length 1)
			(best_width_ratio 0.9)
			(max_width 2)
			(curved_edges yes)
			(filter_ratio 0.9)
			(enabled yes)
			(allow_two_segments yes)
			(prefer_zone_connections yes)
		)
		(net 401)
	)
	(via
		(at 235.920708 79.11)
		(size 0.45)
		(drill 0.1)
		(layers "F.Cu" "B.Cu")
		(remove_unused_layers yes)
		(keep_end_layers yes)
		(zone_layer_connections "In2.Cu")
		(teardrops
			(best_length_ratio 0.4)
			(max_length 1)
			(best_width_ratio 0.9)
			(max_width 2)
			(curved_edges yes)
			(filter_ratio 0.9)
			(enabled yes)
			(allow_two_segments yes)
			(prefer_zone_connections yes)
		)
		(net 401)
	)
	(segment
		(start 212.05 131.21)
		(end 212.05 126.16)
		(width 0.125)
		(layer "In2.Cu")
		(net 401)
	)
	(segment
		(start 216.9 141.2)
		(end 217.5 140.6)
		(width 0.125)
		(layer "In2.Cu")
		(net 401)
	)
	(segment
		(start 224.7 143)
		(end 222.6 145.1)
		(width 0.125)
		(layer "In2.Cu")
		(net 401)
	)
	(segment
		(start 227.8625 144.2875)
		(end 227.65 144.075)
		(width 0.125)
		(layer "In2.Cu")
		(net 401)
	)
	(segment
		(start 215.275 80.46)
		(end 231.070708 80.46)
		(width 0.125)
		(layer "In2.Cu")
		(net 401)
	)
	(segment
		(start 217.5 140.6)
		(end 217.5 136.66)
		(width 0.125)
		(layer "In2.Cu")
		(net 401)
	)
	(segment
		(start 203.75 91.985)
		(end 215.275 80.46)
		(width 0.125)
		(layer "In2.Cu")
		(net 401)
	)
	(segment
		(start 235.445208 78.6345)
		(end 235.920708 79.11)
		(width 0.125)
		(layer "In2.Cu")
		(net 401)
	)
	(segment
		(start 217.5 136.66)
		(end 212.05 131.21)
		(width 0.125)
		(layer "In2.Cu")
		(net 401)
	)
	(segment
		(start 232.896208 78.6345)
		(end 235.445208 78.6345)
		(width 0.125)
		(layer "In2.Cu")
		(net 401)
	)
	(segment
		(start 216.9 144)
		(end 216.9 141.2)
		(width 0.125)
		(layer "In2.Cu")
		(net 401)
	)
	(segment
		(start 212.05 126.16)
		(end 203.75 117.86)
		(width 0.125)
		(layer "In2.Cu")
		(net 401)
	)
	(segment
		(start 231.070708 80.46)
		(end 232.896208 78.6345)
		(width 0.125)
		(layer "In2.Cu")
		(net 401)
	)
	(segment
		(start 218 145.1)
		(end 216.9 144)
		(width 0.125)
		(layer "In2.Cu")
		(net 401)
	)
	(segment
		(start 227.3 144.075)
		(end 226.225 143)
		(width 0.125)
		(layer "In2.Cu")
		(net 401)
	)
	(segment
		(start 222.6 145.1)
		(end 218 145.1)
		(width 0.125)
		(layer "In2.Cu")
		(net 401)
	)
	(segment
		(start 226.6 161.7)
		(end 227.8625 160.4375)
		(width 0.125)
		(layer "In2.Cu")
		(net 401)
	)
	(segment
		(start 227.8625 160.4375)
		(end 227.8625 144.2875)
		(width 0.125)
		(layer "In2.Cu")
		(net 401)
	)
	(segment
		(start 226.225 143)
		(end 224.7 143)
		(width 0.125)
		(layer "In2.Cu")
		(net 401)
	)
	(segment
		(start 227.65 144.075)
		(end 227.3 144.075)
		(width 0.125)
		(layer "In2.Cu")
		(net 401)
	)
	(segment
		(start 203.75 117.86)
		(end 203.75 91.985)
		(width 0.125)
		(layer "In2.Cu")
		(net 401)
	)
	(segment
		(start 182.8 159.15)
		(end 184.025 157.925)
		(width 0.125)
		(layer "F.Cu")
		(net 409)
	)
	(segment
		(start 184.025 156.685)
		(end 184.025 157.925)
		(width 0.125)
		(layer "F.Cu")
		(net 409)
	)
	(segment
		(start 182.8 159.15)
		(end 180.8 159.15)
		(width 0.125)
		(layer "F.Cu")
		(net 409)
	)
	(via
		(at 180.8 159.15)
		(size 0.45)
		(drill 0.1)
		(layers "F.Cu" "B.Cu")
		(teardrops
			(best_length_ratio 0.4)
			(max_length 1)
			(best_width_ratio 0.9)
			(max_width 2)
			(curved_edges yes)
			(filter_ratio 0.9)
			(enabled yes)
			(allow_two_segments yes)
			(prefer_zone_connections yes)
		)
		(net 409)
	)
	(segment
		(start 180.8 160.15)
		(end 180.8 159.15)
		(width 0.125)
		(layer "B.Cu")
		(net 409)
	)
	(segment
		(start 193.025 155.125)
		(end 193.525 155.625)
		(width 0.125)
		(layer "F.Cu")
		(net 422)
	)
	(segment
		(start 189.1 153.95)
		(end 190.275 155.125)
		(width 0.125)
		(layer "F.Cu")
		(net 422)
	)
	(segment
		(start 190.275 155.125)
		(end 193.025 155.125)
		(width 0.125)
		(layer "F.Cu")
		(net 422)
	)
	(segment
		(start 189.1 153.95)
		(end 176.575 153.95)
		(width 0.125)
		(layer "F.Cu")
		(net 422)
	)
	(segment
		(start 193.525 156.685)
		(end 193.525 155.625)
		(width 0.125)
		(layer "F.Cu")
		(net 422)
	)
	(via
		(at 160.55 156.33)
		(size 0.45)
		(drill 0.1)
		(layers "F.Cu" "B.Cu")
		(remove_unused_layers yes)
		(keep_end_layers yes)
		(zone_layer_connections "In2.Cu")
		(teardrops
			(best_length_ratio 0.4)
			(max_length 1)
			(best_width_ratio 0.9)
			(max_width 2)
			(curved_edges yes)
			(filter_ratio 0.9)
			(enabled yes)
			(allow_two_segments yes)
			(prefer_zone_connections yes)
		)
		(net 422)
	)
	(via
		(at 176.575 153.95)
		(size 0.45)
		(drill 0.1)
		(layers "F.Cu" "B.Cu")
		(teardrops
			(best_length_ratio 0.4)
			(max_length 1)
			(best_width_ratio 0.9)
			(max_width 2)
			(curved_edges yes)
			(filter_ratio 0.9)
			(enabled yes)
			(allow_two_segments yes)
			(prefer_zone_connections yes)
		)
		(net 422)
	)
	(segment
		(start 162.2 152.7)
		(end 167.4 152.7)
		(width 0.125)
		(layer "In2.Cu")
		(net 422)
	)
	(segment
		(start 177.3 154.675)
		(end 176.575 153.95)
		(width 0.125)
		(layer "In2.Cu")
		(net 422)
	)
	(segment
		(start 177.3 155.8)
		(end 177.3 154.675)
		(width 0.125)
		(layer "In2.Cu")
		(net 422)
	)
	(segment
		(start 170.7 156)
		(end 177.1 156)
		(width 0.125)
		(layer "In2.Cu")
		(net 422)
	)
	(segment
		(start 160.55 156.33)
		(end 161.9 154.98)
		(width 0.125)
		(layer "In2.Cu")
		(net 422)
	)
	(segment
		(start 161.9 154.98)
		(end 161.9 153)
		(width 0.125)
		(layer "In2.Cu")
		(net 422)
	)
	(segment
		(start 161.9 153)
		(end 162.2 152.7)
		(width 0.125)
		(layer "In2.Cu")
		(net 422)
	)
	(segment
		(start 167.4 152.7)
		(end 170.7 156)
		(width 0.125)
		(layer "In2.Cu")
		(net 422)
	)
	(segment
		(start 177.1 156)
		(end 177.3 155.8)
		(width 0.125)
		(layer "In2.Cu")
		(net 422)
	)
	(segment
		(start 161.55 155.85)
		(end 160.95 155.25)
		(width 0.125)
		(layer "F.Cu")
		(net 423)
	)
	(segment
		(start 176.2 153.375)
		(end 189.125 153.375)
		(width 0.125)
		(layer "F.Cu")
		(net 423)
	)
	(segment
		(start 189.125 153.375)
		(end 190.625 154.875)
		(width 0.125)
		(layer "F.Cu")
		(net 423)
	)
	(segment
		(start 194.025 155.675)
		(end 194.025 156.685)
		(width 0.125)
		(layer "F.Cu")
		(net 423)
	)
	(segment
		(start 160.95 155.25)
		(end 160.95 154.2)
		(width 0.125)
		(layer "F.Cu")
		(net 423)
	)
	(segment
		(start 161.55 156.33)
		(end 161.55 155.85)
		(width 0.125)
		(layer "F.Cu")
		(net 423)
	)
	(segment
		(start 190.625 154.875)
		(end 193.225 154.875)
		(width 0.125)
		(layer "F.Cu")
		(net 423)
	)
	(segment
		(start 193.225 154.875)
		(end 194.025 155.675)
		(width 0.125)
		(layer "F.Cu")
		(net 423)
	)
	(via
		(at 176.2 153.375)
		(size 0.45)
		(drill 0.1)
		(layers "F.Cu" "B.Cu")
		(teardrops
			(best_length_ratio 0.4)
			(max_length 1)
			(best_width_ratio 0.9)
			(max_width 2)
			(curved_edges yes)
			(filter_ratio 0.9)
			(enabled yes)
			(allow_two_segments yes)
			(prefer_zone_connections yes)
		)
		(net 423)
	)
	(via
		(at 160.95 154.2)
		(size 0.45)
		(drill 0.1)
		(layers "F.Cu" "B.Cu")
		(teardrops
			(best_length_ratio 0.4)
			(max_length 1)
			(best_width_ratio 0.9)
			(max_width 2)
			(curved_edges yes)
			(filter_ratio 0.9)
			(enabled yes)
			(allow_two_segments yes)
			(prefer_zone_connections yes)
		)
		(net 423)
	)
	(segment
		(start 176.2 153.375)
		(end 174.555 151.73)
		(width 0.125)
		(layer "In2.Cu")
		(net 423)
	)
	(segment
		(start 160.53 152.6)
		(end 160.53 153.3)
		(width 0.125)
		(layer "In2.Cu")
		(net 423)
	)
	(segment
		(start 160.53 153.3)
		(end 160.95 153.72)
		(width 0.125)
		(layer "In2.Cu")
		(net 423)
	)
	(segment
		(start 161.4 151.73)
		(end 160.53 152.6)
		(width 0.125)
		(layer "In2.Cu")
		(net 423)
	)
	(segment
		(start 174.555 151.73)
		(end 161.4 151.73)
		(width 0.125)
		(layer "In2.Cu")
		(net 423)
	)
	(segment
		(start 160.95 153.72)
		(end 160.95 154.2)
		(width 0.125)
		(layer "In2.Cu")
		(net 423)
	)
	(segment
		(start 192.9 154.175)
		(end 192.9 153.8)
		(width 0.125)
		(layer "F.Cu")
		(net 424)
	)
	(segment
		(start 194.4 155.5)
		(end 194.225 155.5)
		(width 0.125)
		(layer "F.Cu")
		(net 424)
	)
	(segment
		(start 194.525 155.625)
		(end 194.4 155.5)
		(width 0.125)
		(layer "F.Cu")
		(net 424)
	)
	(segment
		(start 179.5 144)
		(end 179.75 144.25)
		(width 0.125)
		(layer "F.Cu")
		(net 424)
	)
	(segment
		(start 194.225 155.5)
		(end 192.9 154.175)
		(width 0.125)
		(layer "F.Cu")
		(net 424)
	)
	(segment
		(start 178.88 144)
		(end 179.5 144)
		(width 0.125)
		(layer "F.Cu")
		(net 424)
	)
	(segment
		(start 194.525 156.685)
		(end 194.525 155.625)
		(width 0.125)
		(layer "F.Cu")
		(net 424)
	)
	(via
		(at 179.75 144.25)
		(size 0.45)
		(drill 0.1)
		(layers "F.Cu" "B.Cu")
		(teardrops
			(best_length_ratio 0.4)
			(max_length 1)
			(best_width_ratio 0.9)
			(max_width 2)
			(curved_edges yes)
			(filter_ratio 0.9)
			(enabled yes)
			(allow_two_segments yes)
			(prefer_zone_connections yes)
		)
		(net 424)
	)
	(via
		(at 192.9 153.8)
		(size 0.45)
		(drill 0.1)
		(layers "F.Cu" "B.Cu")
		(teardrops
			(best_length_ratio 0.4)
			(max_length 1)
			(best_width_ratio 0.9)
			(max_width 2)
			(curved_edges yes)
			(filter_ratio 0.9)
			(enabled yes)
			(allow_two_segments yes)
			(prefer_zone_connections yes)
		)
		(net 424)
	)
	(segment
		(start 179.75 144.25)
		(end 180.5 144.25)
		(width 0.125)
		(layer "In2.Cu")
		(net 424)
	)
	(segment
		(start 181 142.15)
		(end 179.6 142.15)
		(width 0.125)
		(layer "In2.Cu")
		(net 424)
	)
	(segment
		(start 192.1 153)
		(end 192.9 153.8)
		(width 0.125)
		(layer "In2.Cu")
		(net 424)
	)
	(segment
		(start 179.35 146.45)
		(end 181.55 146.45)
		(width 0.125)
		(layer "In2.Cu")
		(net 424)
	)
	(segment
		(start 181.25 142.4)
		(end 181 142.15)
		(width 0.125)
		(layer "In2.Cu")
		(net 424)
	)
	(segment
		(start 185.15 144.15)
		(end 192.1 151.1)
		(width 0.125)
		(layer "In2.Cu")
		(net 424)
	)
	(segment
		(start 178.35 145.45)
		(end 179.35 146.45)
		(width 0.125)
		(layer "In2.Cu")
		(net 424)
	)
	(segment
		(start 180.5 144.25)
		(end 181.25 143.5)
		(width 0.125)
		(layer "In2.Cu")
		(net 424)
	)
	(segment
		(start 192.1 151.1)
		(end 192.1 153)
		(width 0.125)
		(layer "In2.Cu")
		(net 424)
	)
	(segment
		(start 179.6 142.15)
		(end 178.35 143.4)
		(width 0.125)
		(layer "In2.Cu")
		(net 424)
	)
	(segment
		(start 181.55 146.45)
		(end 183.85 144.15)
		(width 0.125)
		(layer "In2.Cu")
		(net 424)
	)
	(segment
		(start 178.35 143.4)
		(end 178.35 145.45)
		(width 0.125)
		(layer "In2.Cu")
		(net 424)
	)
	(segment
		(start 181.25 143.5)
		(end 181.25 142.4)
		(width 0.125)
		(layer "In2.Cu")
		(net 424)
	)
	(segment
		(start 183.85 144.15)
		(end 185.15 144.15)
		(width 0.125)
		(layer "In2.Cu")
		(net 424)
	)
	(segment
		(start 193.475 154.325)
		(end 193.475 153.675)
		(width 0.125)
		(layer "F.Cu")
		(net 425)
	)
	(segment
		(start 180.6 142.7)
		(end 180.300002 142.999998)
		(width 0.125)
		(layer "F.Cu")
		(net 425)
	)
	(segment
		(start 180.300002 142.999998)
		(end 178.88 142.999998)
		(width 0.125)
		(layer "F.Cu")
		(net 425)
	)
	(segment
		(start 194.3 155.15)
		(end 193.475 154.325)
		(width 0.125)
		(layer "F.Cu")
		(net 425)
	)
	(segment
		(start 193.475 153.675)
		(end 192.85 153.05)
		(width 0.125)
		(layer "F.Cu")
		(net 425)
	)
	(segment
		(start 195.025 156.685)
		(end 195.025 155.475)
		(width 0.125)
		(layer "F.Cu")
		(net 425)
	)
	(segment
		(start 194.7 155.15)
		(end 194.3 155.15)
		(width 0.125)
		(layer "F.Cu")
		(net 425)
	)
	(segment
		(start 195.025 155.475)
		(end 194.7 155.15)
		(width 0.125)
		(layer "F.Cu")
		(net 425)
	)
	(via
		(at 180.6 142.7)
		(size 0.45)
		(drill 0.1)
		(layers "F.Cu" "B.Cu")
		(teardrops
			(best_length_ratio 0.4)
			(max_length 1)
			(best_width_ratio 0.9)
			(max_width 2)
			(curved_edges yes)
			(filter_ratio 0.9)
			(enabled yes)
			(allow_two_segments yes)
			(prefer_zone_connections yes)
		)
		(net 425)
	)
	(via
		(at 192.85 153.05)
		(size 0.45)
		(drill 0.1)
		(layers "F.Cu" "B.Cu")
		(teardrops
			(best_length_ratio 0.4)
			(max_length 1)
			(best_width_ratio 0.9)
			(max_width 2)
			(curved_edges yes)
			(filter_ratio 0.9)
			(enabled yes)
			(allow_two_segments yes)
			(prefer_zone_connections yes)
		)
		(net 425)
	)
	(segment
		(start 183.775 143.675)
		(end 185.575 143.675)
		(width 0.125)
		(layer "In2.Cu")
		(net 425)
	)
	(segment
		(start 178.95 143.8)
		(end 178.95 145.15)
		(width 0.125)
		(layer "In2.Cu")
		(net 425)
	)
	(segment
		(start 185.575 143.675)
		(end 192.85 150.95)
		(width 0.125)
		(layer "In2.Cu")
		(net 425)
	)
	(segment
		(start 192.85 150.95)
		(end 192.85 153.05)
		(width 0.125)
		(layer "In2.Cu")
		(net 425)
	)
	(segment
		(start 179.7 145.9)
		(end 181.55 145.9)
		(width 0.125)
		(layer "In2.Cu")
		(net 425)
	)
	(segment
		(start 180.05 142.7)
		(end 178.95 143.8)
		(width 0.125)
		(layer "In2.Cu")
		(net 425)
	)
	(segment
		(start 181.55 145.9)
		(end 183.775 143.675)
		(width 0.125)
		(layer "In2.Cu")
		(net 425)
	)
	(segment
		(start 180.6 142.7)
		(end 180.05 142.7)
		(width 0.125)
		(layer "In2.Cu")
		(net 425)
	)
	(segment
		(start 178.95 145.15)
		(end 179.7 145.9)
		(width 0.125)
		(layer "In2.Cu")
		(net 425)
	)
	(segment
		(start 196.275 158.45)
		(end 197.075 158.45)
		(width 0.125)
		(layer "F.Cu")
		(net 426)
	)
	(segment
		(start 195.525 156.685)
		(end 195.525 157.7)
		(width 0.125)
		(layer "F.Cu")
		(net 426)
	)
	(segment
		(start 195.525 157.7)
		(end 196.275 158.45)
		(width 0.125)
		(layer "F.Cu")
		(net 426)
	)
	(via
		(at 197.075 158.45)
		(size 0.45)
		(drill 0.1)
		(layers "F.Cu" "B.Cu")
		(teardrops
			(best_length_ratio 0.4)
			(max_length 1)
			(best_width_ratio 0.9)
			(max_width 2)
			(curved_edges yes)
			(filter_ratio 0.9)
			(enabled yes)
			(allow_two_segments yes)
			(prefer_zone_connections yes)
		)
		(net 426)
	)
	(segment
		(start 197.075 157.625)
		(end 197.075 158.45)
		(width 0.125)
		(layer "B.Cu")
		(net 426)
	)
	(segment
		(start 196.585 155.9)
		(end 196.585 155.252966)
		(width 0.16)
		(layer "F.Cu")
		(net 427)
	)
	(segment
		(start 196.525 156.685)
		(end 196.525 155.96)
		(width 0.16)
		(layer "F.Cu")
		(net 427)
	)
	(segment
		(start 195.108431 154.802132)
		(end 195.106048 154.799749)
		(width 0.16)
		(layer "F.Cu")
		(net 427)
	)
	(segment
		(start 196.497132 155.040834)
		(end 196.434166 154.977868)
		(width 0.16)
		(layer "F.Cu")
		(net 427)
	)
	(segment
		(start 196.525 155.96)
		(end 196.585 155.9)
		(width 0.16)
		(layer "F.Cu")
		(net 427)
	)
	(segment
		(start 194.893916 154.711881)
		(end 194.813119 154.711881)
		(width 0.16)
		(layer "F.Cu")
		(net 427)
	)
	(segment
		(start 196.222034 154.89)
		(end 195.320563 154.89)
		(width 0.16)
		(layer "F.Cu")
		(net 427)
	)
	(via
		(at 135.13 147.62)
		(size 0.45)
		(drill 0.1)
		(layers "F.Cu" "B.Cu")
		(remove_unused_layers yes)
		(keep_end_layers yes)
		(zone_layer_connections)
		(teardrops
			(best_length_ratio 0.4)
			(max_length 1)
			(best_width_ratio 0.9)
			(max_width 2)
			(curved_edges yes)
			(filter_ratio 0.9)
			(enabled yes)
			(allow_two_segments yes)
			(prefer_zone_connections yes)
		)
		(net 427)
	)
	(via
		(at 194.813119 154.711881)
		(size 0.45)
		(drill 0.1)
		(layers "F.Cu" "B.Cu")
		(teardrops
			(best_length_ratio 0.4)
			(max_length 1)
			(best_width_ratio 0.9)
			(max_width 2)
			(curved_edges yes)
			(filter_ratio 0.9)
			(enabled yes)
			(allow_two_segments yes)
			(prefer_zone_connections yes)
		)
		(net 427)
	)
	(arc
		(start 196.434166 154.977868)
		(mid 196.336839 154.912836)
		(end 196.222034 154.89)
		(width 0.16)
		(layer "F.Cu")
		(net 427)
	)
	(arc
		(start 195.106048 154.799749)
		(mid 195.008721 154.734717)
		(end 194.893916 154.711881)
		(width 0.16)
		(layer "F.Cu")
		(net 427)
	)
	(arc
		(start 195.108431 154.802132)
		(mid 195.205758 154.867164)
		(end 195.320563 154.89)
		(width 0.16)
		(layer "F.Cu")
		(net 427)
	)
	(arc
		(start 196.585 155.252966)
		(mid 196.562164 155.138161)
		(end 196.497132 155.040834)
		(width 0.16)
		(layer "F.Cu")
		(net 427)
	)
	(segment
		(start 139.449166 148.782132)
		(end 142.010765 146.220533)
		(width 0.16)
		(layer "B.Cu")
		(net 427)
	)
	(segment
		(start 161.934084 145.11)
		(end 174.101376 145.11)
		(width 0.16)
		(layer "B.Cu")
		(net 427)
	)
	(segment
		(start 178.99 149.994754)
		(end 178.99 151.197034)
		(width 0.16)
		(layer "B.Cu")
		(net 427)
	)
	(segment
		(start 136.604134 148.37)
		(end 136.694134 148.37)
		(width 0.16)
		(layer "B.Cu")
		(net 427)
	)
	(segment
		(start 195.16 155.147034)
		(end 195.16 155.059264)
		(width 0.16)
		(layer "B.Cu")
		(net 427)
	)
	(segment
		(start 135.062868 148.294166)
		(end 135.550834 148.782132)
		(width 0.16)
		(layer "B.Cu")
		(net 427)
	)
	(segment
		(start 142.44661 146.04)
		(end 160.617034 146.04)
		(width 0.16)
		(layer "B.Cu")
		(net 427)
	)
	(segment
		(start 192.870753 154.47815)
		(end 193.15218 154.19672)
		(width 0.16)
		(layer "B.Cu")
		(net 427)
	)
	(segment
		(start 181.102966 153.31)
		(end 191.182964 153.31)
		(width 0.16)
		(layer "B.Cu")
		(net 427)
	)
	(segment
		(start 136.874134 148.55)
		(end 136.874134 148.69)
		(width 0.16)
		(layer "B.Cu")
		(net 427)
	)
	(segment
		(start 194.854038 154.711881)
		(end 194.813119 154.711881)
		(width 0.16)
		(layer "B.Cu")
		(net 427)
	)
	(segment
		(start 174.574801 145.306099)
		(end 178.796637 149.527935)
		(width 0.16)
		(layer "B.Cu")
		(net 427)
	)
	(segment
		(start 193.181878 155.038176)
		(end 193.615834 155.472132)
		(width 0.16)
		(layer "B.Cu")
		(net 427)
	)
	(segment
		(start 193.401082 154.19672)
		(end 193.463307 154.258945)
		(width 0.16)
		(layer "B.Cu")
		(net 427)
	)
	(segment
		(start 137.054134 148.87)
		(end 139.237034 148.87)
		(width 0.16)
		(layer "B.Cu")
		(net 427)
	)
	(segment
		(start 195.072132 154.847132)
		(end 194.995459 154.770459)
		(width 0.16)
		(layer "B.Cu")
		(net 427)
	)
	(segment
		(start 193.463308 154.507847)
		(end 193.181878 154.789274)
		(width 0.16)
		(layer "B.Cu")
		(net 427)
	)
	(segment
		(start 135.12 147.62)
		(end 135.062868 147.677132)
		(width 0.16)
		(layer "B.Cu")
		(net 427)
	)
	(segment
		(start 160.829166 145.952132)
		(end 161.48548 145.295818)
		(width 0.16)
		(layer "B.Cu")
		(net 427)
	)
	(segment
		(start 194.959166 155.472132)
		(end 195.072132 155.359166)
		(width 0.16)
		(layer "B.Cu")
		(net 427)
	)
	(segment
		(start 134.975 147.889264)
		(end 134.975 148.082034)
		(width 0.16)
		(layer "B.Cu")
		(net 427)
	)
	(segment
		(start 179.077868 151.409166)
		(end 180.890834 153.222132)
		(width 0.16)
		(layer "B.Cu")
		(net 427)
	)
	(segment
		(start 193.827966 155.56)
		(end 194.747034 155.56)
		(width 0.16)
		(layer "B.Cu")
		(net 427)
	)
	(segment
		(start 136.424134 148.69)
		(end 136.424134 148.55)
		(width 0.16)
		(layer "B.Cu")
		(net 427)
	)
	(segment
		(start 135.762966 148.87)
		(end 136.244134 148.87)
		(width 0.16)
		(layer "B.Cu")
		(net 427)
	)
	(segment
		(start 191.645142 153.50144)
		(end 192.621851 154.478149)
		(width 0.16)
		(layer "B.Cu")
		(net 427)
	)
	(arc
		(start 194.995459 154.770459)
		(mid 194.930574 154.727105)
		(end 194.854038 154.711881)
		(width 0.16)
		(layer "B.Cu")
		(net 427)
	)
	(arc
		(start 136.424134 148.55)
		(mid 136.476855 148.422721)
		(end 136.604134 148.37)
		(width 0.16)
		(layer "B.Cu")
		(net 427)
	)
	(arc
		(start 194.747034 155.56)
		(mid 194.861839 155.537164)
		(end 194.959166 155.472132)
		(width 0.16)
		(layer "B.Cu")
		(net 427)
	)
	(arc
		(start 191.182964 153.31)
		(mid 191.433093 153.359754)
		(end 191.645142 153.50144)
		(width 0.16)
		(layer "B.Cu")
		(net 427)
	)
	(arc
		(start 193.463307 154.258945)
		(mid 193.514856 154.383396)
		(end 193.463308 154.507847)
		(width 0.16)
		(layer "B.Cu")
		(net 427)
	)
	(arc
		(start 178.796637 149.527935)
		(mid 178.939746 149.742113)
		(end 178.99 149.994754)
		(width 0.16)
		(layer "B.Cu")
		(net 427)
	)
	(arc
		(start 135.550834 148.782132)
		(mid 135.648161 148.847164)
		(end 135.762966 148.87)
		(width 0.16)
		(layer "B.Cu")
		(net 427)
	)
	(arc
		(start 174.101376 145.11)
		(mid 174.357592 145.160964)
		(end 174.574801 145.306099)
		(width 0.16)
		(layer "B.Cu")
		(net 427)
	)
	(arc
		(start 178.99 151.197034)
		(mid 179.012836 151.311839)
		(end 179.077868 151.409166)
		(width 0.16)
		(layer "B.Cu")
		(net 427)
	)
	(arc
		(start 160.617034 146.04)
		(mid 160.731839 146.017164)
		(end 160.829166 145.952132)
		(width 0.16)
		(layer "B.Cu")
		(net 427)
	)
	(arc
		(start 136.244134 148.87)
		(mid 136.371413 148.817279)
		(end 136.424134 148.69)
		(width 0.16)
		(layer "B.Cu")
		(net 427)
	)
	(arc
		(start 180.890834 153.222132)
		(mid 180.988161 153.287164)
		(end 181.102966 153.31)
		(width 0.16)
		(layer "B.Cu")
		(net 427)
	)
	(arc
		(start 161.48548 145.295818)
		(mid 161.691301 145.158293)
		(end 161.934084 145.11)
		(width 0.16)
		(layer "B.Cu")
		(net 427)
	)
	(arc
		(start 193.15218 154.19672)
		(mid 193.276631 154.145171)
		(end 193.401082 154.19672)
		(width 0.16)
		(layer "B.Cu")
		(net 427)
	)
	(arc
		(start 135.062868 148.294166)
		(mid 134.997836 148.196839)
		(end 134.975 148.082034)
		(width 0.16)
		(layer "B.Cu")
		(net 427)
	)
	(arc
		(start 193.181878 154.789274)
		(mid 193.130329 154.913725)
		(end 193.181878 155.038176)
		(width 0.16)
		(layer "B.Cu")
		(net 427)
	)
	(arc
		(start 192.621851 154.478149)
		(mid 192.746302 154.529698)
		(end 192.870753 154.47815)
		(width 0.16)
		(layer "B.Cu")
		(net 427)
	)
	(arc
		(start 195.16 155.059264)
		(mid 195.137164 154.944459)
		(end 195.072132 154.847132)
		(width 0.16)
		(layer "B.Cu")
		(net 427)
	)
	(arc
		(start 193.615834 155.472132)
		(mid 193.713161 155.537164)
		(end 193.827966 155.56)
		(width 0.16)
		(layer "B.Cu")
		(net 427)
	)
	(arc
		(start 142.010765 146.220533)
		(mid 142.210732 146.086919)
		(end 142.44661 146.04)
		(width 0.16)
		(layer "B.Cu")
		(net 427)
	)
	(arc
		(start 135.062868 147.677132)
		(mid 134.997836 147.774459)
		(end 134.975 147.889264)
		(width 0.16)
		(layer "B.Cu")
		(net 427)
	)
	(arc
		(start 136.694134 148.37)
		(mid 136.821413 148.422721)
		(end 136.874134 148.55)
		(width 0.16)
		(layer "B.Cu")
		(net 427)
	)
	(arc
		(start 136.874134 148.69)
		(mid 136.926855 148.817279)
		(end 137.054134 148.87)
		(width 0.16)
		(layer "B.Cu")
		(net 427)
	)
	(arc
		(start 195.072132 155.359166)
		(mid 195.137164 155.261839)
		(end 195.16 155.147034)
		(width 0.16)
		(layer "B.Cu")
		(net 427)
	)
	(arc
		(start 139.237034 148.87)
		(mid 139.351839 148.847164)
		(end 139.449166 148.782132)
		(width 0.16)
		(layer "B.Cu")
		(net 427)
	)
	(segment
		(start 197.025 155.96)
		(end 196.965 155.9)
		(width 0.16)
		(layer "F.Cu")
		(net 428)
	)
	(segment
		(start 197.025 156.685)
		(end 197.025 155.96)
		(width 0.16)
		(layer "F.Cu")
		(net 428)
	)
	(segment
		(start 195.376421 154.451421)
		(end 195.345459 154.420459)
		(width 0.16)
		(layer "F.Cu")
		(net 428)
	)
	(segment
		(start 196.296595 154.51)
		(end 195.517843 154.51)
		(width 0.16)
		(layer "F.Cu")
		(net 428)
	)
	(segment
		(start 196.818553 154.824851)
		(end 196.650148 154.656446)
		(width 0.16)
		(layer "F.Cu")
		(net 428)
	)
	(segment
		(start 196.965 155.9)
		(end 196.965 155.178405)
		(width 0.16)
		(layer "F.Cu")
		(net 428)
	)
	(segment
		(start 195.286881 154.279038)
		(end 195.286881 154.238119)
		(width 0.16)
		(layer "F.Cu")
		(net 428)
	)
	(via
		(at 195.286881 154.238119)
		(size 0.45)
		(drill 0.1)
		(layers "F.Cu" "B.Cu")
		(teardrops
			(best_length_ratio 0.4)
			(max_length 1)
			(best_width_ratio 0.9)
			(max_width 2)
			(curved_edges yes)
			(filter_ratio 0.9)
			(enabled yes)
			(allow_two_segments yes)
			(prefer_zone_connections yes)
		)
		(net 428)
	)
	(via
		(at 134.45 147.62)
		(size 0.45)
		(drill 0.1)
		(layers "F.Cu" "B.Cu")
		(remove_unused_layers yes)
		(keep_end_layers yes)
		(zone_layer_connections)
		(teardrops
			(best_length_ratio 0.4)
			(max_length 1)
			(best_width_ratio 0.9)
			(max_width 2)
			(curved_edges yes)
			(filter_ratio 0.9)
			(enabled yes)
			(allow_two_segments yes)
			(prefer_zone_connections yes)
		)
		(net 428)
	)
	(arc
		(start 196.965 155.178405)
		(mid 196.92694 154.987063)
		(end 196.818553 154.824851)
		(width 0.16)
		(layer "F.Cu")
		(net 428)
	)
	(arc
		(start 195.517843 154.51)
		(mid 195.441306 154.494776)
		(end 195.376421 154.451421)
		(width 0.16)
		(layer "F.Cu")
		(net 428)
	)
	(arc
		(start 195.286881 154.279038)
		(mid 195.302105 154.355574)
		(end 195.345459 154.420459)
		(width 0.16)
		(layer "F.Cu")
		(net 428)
	)
	(arc
		(start 196.650148 154.656446)
		(mid 196.487936 154.54806)
		(end 196.296595 154.51)
		(width 0.16)
		(layer "F.Cu")
		(net 428)
	)
	(segment
		(start 195.54 154.903406)
		(end 195.54 155.221595)
		(width 0.16)
		(layer "B.Cu")
		(net 428)
	)
	(segment
		(start 195.286881 154.238119)
		(end 195.286881 154.318916)
		(width 0.16)
		(layer "B.Cu")
		(net 428)
	)
	(segment
		(start 139.311595 149.25)
		(end 135.688405 149.25)
		(width 0.16)
		(layer "B.Cu")
		(net 428)
	)
	(segment
		(start 174.097034 145.49)
		(end 161.952966 145.49)
		(width 0.16)
		(layer "B.Cu")
		(net 428)
	)
	(segment
		(start 134.595 148.156595)
		(end 134.595 147.889264)
		(width 0.16)
		(layer "B.Cu")
		(net 428)
	)
	(segment
		(start 135.334851 149.103553)
		(end 134.741446 148.510148)
		(width 0.16)
		(layer "B.Cu")
		(net 428)
	)
	(segment
		(start 134.507132 147.677132)
		(end 134.45 147.62)
		(width 0.16)
		(layer "B.Cu")
		(net 428)
	)
	(segment
		(start 178.61 151.271595)
		(end 178.61 150.002966)
		(width 0.16)
		(layer "B.Cu")
		(net 428)
	)
	(segment
		(start 195.393553 155.575149)
		(end 195.175148 155.793554)
		(width 0.16)
		(layer "B.Cu")
		(net 428)
	)
	(segment
		(start 180.674851 153.543553)
		(end 178.756446 151.625148)
		(width 0.16)
		(layer "B.Cu")
		(net 428)
	)
	(segment
		(start 178.522132 149.790834)
		(end 174.309166 145.577868)
		(width 0.16)
		(layer "B.Cu")
		(net 428)
	)
	(segment
		(start 193.399851 155.793553)
		(end 191.384166 153.777868)
		(width 0.16)
		(layer "B.Cu")
		(net 428)
	)
	(segment
		(start 161.740834 145.577868)
		(end 161.045148 146.273554)
		(width 0.16)
		(layer "B.Cu")
		(net 428)
	)
	(segment
		(start 195.374749 154.531048)
		(end 195.393554 154.549853)
		(width 0.16)
		(layer "B.Cu")
		(net 428)
	)
	(segment
		(start 191.172034 153.69)
		(end 181.028405 153.69)
		(width 0.16)
		(layer "B.Cu")
		(net 428)
	)
	(segment
		(start 194.821595 155.94)
		(end 193.753405 155.94)
		(width 0.16)
		(layer "B.Cu")
		(net 428)
	)
	(segment
		(start 160.691595 146.42)
		(end 142.472966 146.42)
		(width 0.16)
		(layer "B.Cu")
		(net 428)
	)
	(segment
		(start 142.260834 146.507868)
		(end 139.665148 149.103554)
		(width 0.16)
		(layer "B.Cu")
		(net 428)
	)
	(arc
		(start 161.045148 146.273554)
		(mid 160.882936 146.38194)
		(end 160.691595 146.42)
		(width 0.16)
		(layer "B.Cu")
		(net 428)
	)
	(arc
		(start 195.175148 155.793554)
		(mid 195.012936 155.90194)
		(end 194.821595 155.94)
		(width 0.16)
		(layer "B.Cu")
		(net 428)
	)
	(arc
		(start 161.952966 145.49)
		(mid 161.838161 145.512836)
		(end 161.740834 145.577868)
		(width 0.16)
		(layer "B.Cu")
		(net 428)
	)
	(arc
		(start 178.61 150.002966)
		(mid 178.587164 149.888161)
		(end 178.522132 149.790834)
		(width 0.16)
		(layer "B.Cu")
		(net 428)
	)
	(arc
		(start 134.595 147.889264)
		(mid 134.572164 147.774459)
		(end 134.507132 147.677132)
		(width 0.16)
		(layer "B.Cu")
		(net 428)
	)
	(arc
		(start 195.54 155.221595)
		(mid 195.50194 155.412937)
		(end 195.393553 155.575149)
		(width 0.16)
		(layer "B.Cu")
		(net 428)
	)
	(arc
		(start 193.399851 155.793553)
		(mid 193.562063 155.90194)
		(end 193.753405 155.94)
		(width 0.16)
		(layer "B.Cu")
		(net 428)
	)
	(arc
		(start 180.674851 153.543553)
		(mid 180.837063 153.65194)
		(end 181.028405 153.69)
		(width 0.16)
		(layer "B.Cu")
		(net 428)
	)
	(arc
		(start 135.688405 149.25)
		(mid 135.497063 149.21194)
		(end 135.334851 149.103553)
		(width 0.16)
		(layer "B.Cu")
		(net 428)
	)
	(arc
		(start 195.286881 154.318916)
		(mid 195.309717 154.433721)
		(end 195.374749 154.531048)
		(width 0.16)
		(layer "B.Cu")
		(net 428)
	)
	(arc
		(start 174.097034 145.49)
		(mid 174.211839 145.512836)
		(end 174.309166 145.577868)
		(width 0.16)
		(layer "B.Cu")
		(net 428)
	)
	(arc
		(start 134.595 148.156595)
		(mid 134.63306 148.347936)
		(end 134.741446 148.510148)
		(width 0.16)
		(layer "B.Cu")
		(net 428)
	)
	(arc
		(start 142.472966 146.42)
		(mid 142.358161 146.442836)
		(end 142.260834 146.507868)
		(width 0.16)
		(layer "B.Cu")
		(net 428)
	)
	(arc
		(start 139.311595 149.25)
		(mid 139.502936 149.21194)
		(end 139.665148 149.103554)
		(width 0.16)
		(layer "B.Cu")
		(net 428)
	)
	(arc
		(start 178.61 151.271595)
		(mid 178.64806 151.462936)
		(end 178.756446 151.625148)
		(width 0.16)
		(layer "B.Cu")
		(net 428)
	)
	(arc
		(start 191.384166 153.777868)
		(mid 191.286839 153.712836)
		(end 191.172034 153.69)
		(width 0.16)
		(layer "B.Cu")
		(net 428)
	)
	(arc
		(start 195.54 154.903406)
		(mid 195.50194 154.712065)
		(end 195.393554 154.549853)
		(width 0.16)
		(layer "B.Cu")
		(net 428)
	)
	(segment
		(start 198.2 155.35)
		(end 198 155.55)
		(width 0.125)
		(layer "F.Cu")
		(net 429)
	)
	(segment
		(start 198 156.66)
		(end 198.025 156.685)
		(width 0.125)
		(layer "F.Cu")
		(net 429)
	)
	(segment
		(start 198 155.55)
		(end 198 156.66)
		(width 0.125)
		(layer "F.Cu")
		(net 429)
	)
	(segment
		(start 125.7 145.45)
		(end 125.7 147.094)
		(width 0.125)
		(layer "F.Cu")
		(net 429)
	)
	(segment
		(start 198.2 154.95)
		(end 198.2 155.35)
		(width 0.125)
		(layer "F.Cu")
		(net 429)
	)
	(segment
		(start 125.7 147.094)
		(end 125.682 147.112)
		(width 0.125)
		(layer "F.Cu")
		(net 429)
	)
	(segment
		(start 126.825 144.325)
		(end 125.7 145.45)
		(width 0.125)
		(layer "F.Cu")
		(net 429)
	)
	(segment
		(start 126.825 143.4)
		(end 126.825 144.325)
		(width 0.125)
		(layer "F.Cu")
		(net 429)
	)
	(via
		(at 126.825 143.4)
		(size 0.45)
		(drill 0.1)
		(layers "F.Cu" "B.Cu")
		(teardrops
			(best_length_ratio 0.4)
			(max_length 1)
			(best_width_ratio 0.9)
			(max_width 2)
			(curved_edges yes)
			(filter_ratio 0.9)
			(enabled yes)
			(allow_two_segments yes)
			(prefer_zone_connections yes)
		)
		(net 429)
	)
	(via
		(at 198.2 154.95)
		(size 0.45)
		(drill 0.1)
		(layers "F.Cu" "B.Cu")
		(teardrops
			(best_length_ratio 0.4)
			(max_length 1)
			(best_width_ratio 0.9)
			(max_width 2)
			(curved_edges yes)
			(filter_ratio 0.9)
			(enabled yes)
			(allow_two_segments yes)
			(prefer_zone_connections yes)
		)
		(net 429)
	)
	(via
		(at 167.1 142.825)
		(size 0.45)
		(drill 0.1)
		(layers "F.Cu" "B.Cu")
		(teardrops
			(best_length_ratio 0.4)
			(max_length 1)
			(best_width_ratio 0.9)
			(max_width 2)
			(curved_edges yes)
			(filter_ratio 0.9)
			(enabled yes)
			(allow_two_segments yes)
			(prefer_zone_connections yes)
		)
		(net 429)
	)
	(segment
		(start 198.2 154.95)
		(end 201.65 154.95)
		(width 0.125)
		(layer "In2.Cu")
		(net 429)
	)
	(segment
		(start 198.35 147.85)
		(end 196.65 147.85)
		(width 0.125)
		(layer "In2.Cu")
		(net 429)
	)
	(segment
		(start 201.975 151.475)
		(end 198.35 147.85)
		(width 0.125)
		(layer "In2.Cu")
		(net 429)
	)
	(segment
		(start 191.15 142.35)
		(end 182.8 142.35)
		(width 0.125)
		(layer "In2.Cu")
		(net 429)
	)
	(segment
		(start 182.8 142.35)
		(end 181.8 141.35)
		(width 0.125)
		(layer "In2.Cu")
		(net 429)
	)
	(segment
		(start 181.8 141.35)
		(end 170.15 141.35)
		(width 0.125)
		(layer "In2.Cu")
		(net 429)
	)
	(segment
		(start 196.65 147.85)
		(end 191.15 142.35)
		(width 0.125)
		(layer "In2.Cu")
		(net 429)
	)
	(segment
		(start 170.15 141.35)
		(end 168.675 142.825)
		(width 0.125)
		(layer "In2.Cu")
		(net 429)
	)
	(segment
		(start 201.65 154.95)
		(end 201.975 154.625)
		(width 0.125)
		(layer "In2.Cu")
		(net 429)
	)
	(segment
		(start 201.975 154.625)
		(end 201.975 151.475)
		(width 0.125)
		(layer "In2.Cu")
		(net 429)
	)
	(segment
		(start 168.675 142.825)
		(end 167.1 142.825)
		(width 0.125)
		(layer "In2.Cu")
		(net 429)
	)
	(segment
		(start 141.35 137.825)
		(end 143.525 137.825)
		(width 0.125)
		(layer "In5.Cu")
		(net 429)
	)
	(segment
		(start 143.525 137.825)
		(end 143.95 138.25)
		(width 0.125)
		(layer "In5.Cu")
		(net 429)
	)
	(segment
		(start 142.575 143.5)
		(end 142.575 141.3)
		(width 0.125)
		(layer "In5.Cu")
		(net 429)
	)
	(segment
		(start 143.95 139.925)
		(end 143.95 138.25)
		(width 0.125)
		(layer "In5.Cu")
		(net 429)
	)
	(segment
		(start 143.05 143.975)
		(end 142.575 143.5)
		(width 0.125)
		(layer "In5.Cu")
		(net 429)
	)
	(segment
		(start 138.075 143.325)
		(end 139.325 142.075)
		(width 0.125)
		(layer "In5.Cu")
		(net 429)
	)
	(segment
		(start 139.325 139.85)
		(end 141.35 137.825)
		(width 0.125)
		(layer "In5.Cu")
		(net 429)
	)
	(segment
		(start 160.9 141.075)
		(end 167.775 141.075)
		(width 0.125)
		(layer "In5.Cu")
		(net 429)
	)
	(segment
		(start 143.05 143.975)
		(end 158 143.975)
		(width 0.125)
		(layer "In5.Cu")
		(net 429)
	)
	(segment
		(start 167.775 141.075)
		(end 168.3 141.6)
		(width 0.125)
		(layer "In5.Cu")
		(net 429)
	)
	(segment
		(start 158 143.975)
		(end 160.9 141.075)
		(width 0.125)
		(layer "In5.Cu")
		(net 429)
	)
	(segment
		(start 126.9 143.325)
		(end 126.825 143.4)
		(width 0.125)
		(layer "In5.Cu")
		(net 429)
	)
	(segment
		(start 142.575 141.3)
		(end 143.95 139.925)
		(width 0.125)
		(layer "In5.Cu")
		(net 429)
	)
	(segment
		(start 167.9 142.825)
		(end 168.3 142.425)
		(width 0.125)
		(layer "In5.Cu")
		(net 429)
	)
	(segment
		(start 126.9 143.325)
		(end 138.075 143.325)
		(width 0.125)
		(layer "In5.Cu")
		(net 429)
	)
	(segment
		(start 167.1 142.825)
		(end 167.9 142.825)
		(width 0.125)
		(layer "In5.Cu")
		(net 429)
	)
	(segment
		(start 168.3 142.425)
		(end 168.3 141.6)
		(width 0.125)
		(layer "In5.Cu")
		(net 429)
	)
	(segment
		(start 139.325 139.85)
		(end 139.325 142.075)
		(width 0.125)
		(layer "In5.Cu")
		(net 429)
	)
	(segment
		(start 199 154.95)
		(end 199.85 154.95)
		(width 0.125)
		(layer "F.Cu")
		(net 430)
	)
	(segment
		(start 198.525 156.685)
		(end 198.525 155.425)
		(width 0.125)
		(layer "F.Cu")
		(net 430)
	)
	(segment
		(start 144.029 147.3)
		(end 143.839 147.11)
		(width 0.125)
		(layer "F.Cu")
		(net 430)
	)
	(segment
		(start 198.525 155.425)
		(end 199 154.95)
		(width 0.125)
		(layer "F.Cu")
		(net 430)
	)
	(segment
		(start 199.85 154.95)
		(end 201.1 153.7)
		(width 0.125)
		(layer "F.Cu")
		(net 430)
	)
	(segment
		(start 145.03 147.3)
		(end 144.029 147.3)
		(width 0.125)
		(layer "F.Cu")
		(net 430)
	)
	(via
		(at 145.03 147.3)
		(size 0.45)
		(drill 0.1)
		(layers "F.Cu" "B.Cu")
		(remove_unused_layers yes)
		(keep_end_layers yes)
		(zone_layer_connections "In5.Cu")
		(teardrops
			(best_length_ratio 0.4)
			(max_length 1)
			(best_width_ratio 0.9)
			(max_width 2)
			(curved_edges yes)
			(filter_ratio 0.9)
			(enabled yes)
			(allow_two_segments yes)
			(prefer_zone_connections yes)
		)
		(net 430)
	)
	(via
		(at 201.1 153.7)
		(size 0.45)
		(drill 0.1)
		(layers "F.Cu" "B.Cu")
		(teardrops
			(best_length_ratio 0.4)
			(max_length 1)
			(best_width_ratio 0.9)
			(max_width 2)
			(curved_edges yes)
			(filter_ratio 0.9)
			(enabled yes)
			(allow_two_segments yes)
			(prefer_zone_connections yes)
		)
		(net 430)
	)
	(via
		(at 167.075 144.4)
		(size 0.45)
		(drill 0.1)
		(layers "F.Cu" "B.Cu")
		(teardrops
			(best_length_ratio 0.4)
			(max_length 1)
			(best_width_ratio 0.9)
			(max_width 2)
			(curved_edges yes)
			(filter_ratio 0.9)
			(enabled yes)
			(allow_two_segments yes)
			(prefer_zone_connections yes)
		)
		(net 430)
	)
	(segment
		(start 169.225 143.55)
		(end 170.9 141.875)
		(width 0.125)
		(layer "In2.Cu")
		(net 430)
	)
	(segment
		(start 197.725 148.4)
		(end 198.975 149.65)
		(width 0.125)
		(layer "In2.Cu")
		(net 430)
	)
	(segment
		(start 198.975 152.625)
		(end 200.05 153.7)
		(width 0.125)
		(layer "In2.Cu")
		(net 430)
	)
	(segment
		(start 181.5 141.875)
		(end 182.35 142.725)
		(width 0.125)
		(layer "In2.Cu")
		(net 430)
	)
	(segment
		(start 198.975 152.625)
		(end 198.975 149.65)
		(width 0.125)
		(layer "In2.Cu")
		(net 430)
	)
	(segment
		(start 167.075 144.025)
		(end 167.075 144.4)
		(width 0.125)
		(layer "In2.Cu")
		(net 430)
	)
	(segment
		(start 191.05 142.725)
		(end 196.725 148.4)
		(width 0.125)
		(layer "In2.Cu")
		(net 430)
	)
	(segment
		(start 170.9 141.875)
		(end 181.5 141.875)
		(width 0.125)
		(layer "In2.Cu")
		(net 430)
	)
	(segment
		(start 196.725 148.4)
		(end 197.725 148.4)
		(width 0.125)
		(layer "In2.Cu")
		(net 430)
	)
	(segment
		(start 182.35 142.725)
		(end 191.05 142.725)
		(width 0.125)
		(layer "In2.Cu")
		(net 430)
	)
	(segment
		(start 201.1 153.7)
		(end 200.05 153.7)
		(width 0.125)
		(layer "In2.Cu")
		(net 430)
	)
	(segment
		(start 167.55 143.55)
		(end 167.075 144.025)
		(width 0.125)
		(layer "In2.Cu")
		(net 430)
	)
	(segment
		(start 169.225 143.55)
		(end 167.55 143.55)
		(width 0.125)
		(layer "In2.Cu")
		(net 430)
	)
	(segment
		(start 167.8 141.725)
		(end 167.8 142.175)
		(width 0.125)
		(layer "In5.Cu")
		(net 430)
	)
	(segment
		(start 145.03 147.3)
		(end 145.805 146.525)
		(width 0.125)
		(layer "In5.Cu")
		(net 430)
	)
	(segment
		(start 145.805 146.525)
		(end 157.3 146.525)
		(width 0.125)
		(layer "In5.Cu")
		(net 430)
	)
	(segment
		(start 157.3 146.525)
		(end 162.425 141.4)
		(width 0.125)
		(layer "In5.Cu")
		(net 430)
	)
	(segment
		(start 162.425 141.4)
		(end 167.475 141.4)
		(width 0.125)
		(layer "In5.Cu")
		(net 430)
	)
	(segment
		(start 166.8 142.375)
		(end 166.475 142.7)
		(width 0.125)
		(layer "In5.Cu")
		(net 430)
	)
	(segment
		(start 166.475 142.7)
		(end 166.475 143.8)
		(width 0.125)
		(layer "In5.Cu")
		(net 430)
	)
	(segment
		(start 167.475 141.4)
		(end 167.8 141.725)
		(width 0.125)
		(layer "In5.Cu")
		(net 430)
	)
	(segment
		(start 167.6 142.375)
		(end 166.8 142.375)
		(width 0.125)
		(layer "In5.Cu")
		(net 430)
	)
	(segment
		(start 167.8 142.175)
		(end 167.6 142.375)
		(width 0.125)
		(layer "In5.Cu")
		(net 430)
	)
	(segment
		(start 166.475 143.8)
		(end 167.075 144.4)
		(width 0.125)
		(layer "In5.Cu")
		(net 430)
	)
	(segment
		(start 199.2 155.4)
		(end 200.1 155.4)
		(width 0.125)
		(layer "F.Cu")
		(net 431)
	)
	(segment
		(start 200.1 155.4)
		(end 201.05 154.45)
		(width 0.125)
		(layer "F.Cu")
		(net 431)
	)
	(segment
		(start 199.025 155.575)
		(end 199.2 155.4)
		(width 0.125)
		(layer "F.Cu")
		(net 431)
	)
	(segment
		(start 201.05 154.45)
		(end 201.05 154.4)
		(width 0.125)
		(layer "F.Cu")
		(net 431)
	)
	(segment
		(start 180.05 145)
		(end 180.1 145.05)
		(width 0.125)
		(layer "F.Cu")
		(net 431)
	)
	(segment
		(start 178.88 145)
		(end 180.05 145)
		(width 0.125)
		(layer "F.Cu")
		(net 431)
	)
	(segment
		(start 199.025 156.685)
		(end 199.025 155.575)
		(width 0.125)
		(layer "F.Cu")
		(net 431)
	)
	(via
		(at 201.05 154.4)
		(size 0.45)
		(drill 0.1)
		(layers "F.Cu" "B.Cu")
		(teardrops
			(best_length_ratio 0.4)
			(max_length 1)
			(best_width_ratio 0.9)
			(max_width 2)
			(curved_edges yes)
			(filter_ratio 0.9)
			(enabled yes)
			(allow_two_segments yes)
			(prefer_zone_connections yes)
		)
		(net 431)
	)
	(via
		(at 180.1 145.05)
		(size 0.45)
		(drill 0.1)
		(layers "F.Cu" "B.Cu")
		(teardrops
			(best_length_ratio 0.4)
			(max_length 1)
			(best_width_ratio 0.9)
			(max_width 2)
			(curved_edges yes)
			(filter_ratio 0.9)
			(enabled yes)
			(allow_two_segments yes)
			(prefer_zone_connections yes)
		)
		(net 431)
	)
	(segment
		(start 181.65 145.05)
		(end 180.1 145.05)
		(width 0.125)
		(layer "In2.Cu")
		(net 431)
	)
	(segment
		(start 201.05 154.4)
		(end 200.1 154.4)
		(width 0.125)
		(layer "In2.Cu")
		(net 431)
	)
	(segment
		(start 198.55 149.85)
		(end 197.6 148.9)
		(width 0.125)
		(layer "In2.Cu")
		(net 431)
	)
	(segment
		(start 200.1 154.4)
		(end 198.55 152.85)
		(width 0.125)
		(layer "In2.Cu")
		(net 431)
	)
	(segment
		(start 198.55 152.85)
		(end 198.55 149.85)
		(width 0.125)
		(layer "In2.Cu")
		(net 431)
	)
	(segment
		(start 191.025 143.175)
		(end 183.525 143.175)
		(width 0.125)
		(layer "In2.Cu")
		(net 431)
	)
	(segment
		(start 183.525 143.175)
		(end 181.65 145.05)
		(width 0.125)
		(layer "In2.Cu")
		(net 431)
	)
	(segment
		(start 197.6 148.9)
		(end 196.75 148.9)
		(width 0.125)
		(layer "In2.Cu")
		(net 431)
	)
	(segment
		(start 196.75 148.9)
		(end 191.025 143.175)
		(width 0.125)
		(layer "In2.Cu")
		(net 431)
	)
	(segment
		(start 197.6 158.765)
		(end 197.657132 158.822132)
		(width 0.16)
		(layer "F.Cu")
		(net 432)
	)
	(segment
		(start 198.825 158.91)
		(end 198.875 158.91)
		(width 0.16)
		(layer "F.Cu")
		(net 432)
	)
	(segment
		(start 198.345 158.536563)
		(end 198.425 158.536563)
		(width 0.16)
		(layer "F.Cu")
		(net 432)
	)
	(segment
		(start 200.085 157.47)
		(end 200.025 157.41)
		(width 0.16)
		(layer "F.Cu")
		(net 432)
	)
	(segment
		(start 200.085 158.122035)
		(end 200.085 157.47)
		(width 0.16)
		(layer "F.Cu")
		(net 432)
	)
	(segment
		(start 198.185 158.75)
		(end 198.185 158.696563)
		(width 0.16)
		(layer "F.Cu")
		(net 432)
	)
	(segment
		(start 198.585 158.696563)
		(end 198.585 158.75)
		(width 0.16)
		(layer "F.Cu")
		(net 432)
	)
	(segment
		(start 197.869264 158.91)
		(end 198.025 158.91)
		(width 0.16)
		(layer "F.Cu")
		(net 432)
	)
	(segment
		(start 198.745 158.91)
		(end 198.825 158.91)
		(width 0.16)
		(layer "F.Cu")
		(net 432)
	)
	(segment
		(start 200.025 157.41)
		(end 200.025 156.685)
		(width 0.16)
		(layer "F.Cu")
		(net 432)
	)
	(segment
		(start 199.509167 158.822132)
		(end 199.997132 158.334167)
		(width 0.16)
		(layer "F.Cu")
		(net 432)
	)
	(segment
		(start 198.875 158.91)
		(end 199.297035 158.91)
		(width 0.16)
		(layer "F.Cu")
		(net 432)
	)
	(via
		(at 197.6 158.765)
		(size 0.45)
		(drill 0.1)
		(layers "F.Cu" "B.Cu")
		(teardrops
			(best_length_ratio 0.4)
			(max_length 1)
			(best_width_ratio 0.9)
			(max_width 2)
			(curved_edges yes)
			(filter_ratio 0.9)
			(enabled yes)
			(allow_two_segments yes)
			(prefer_zone_connections yes)
		)
		(net 432)
	)
	(via
		(at 153.285 147.63)
		(size 0.45)
		(drill 0.1)
		(layers "F.Cu" "B.Cu")
		(remove_unused_layers yes)
		(keep_end_layers yes)
		(zone_layer_connections)
		(teardrops
			(best_length_ratio 0.4)
			(max_length 1)
			(best_width_ratio 0.9)
			(max_width 2)
			(curved_edges yes)
			(filter_ratio 0.9)
			(enabled yes)
			(allow_two_segments yes)
			(prefer_zone_connections yes)
		)
		(net 432)
	)
	(arc
		(start 198.025 158.91)
		(mid 198.138137 158.863137)
		(end 198.185 158.75)
		(width 0.16)
		(layer "F.Cu")
		(net 432)
	)
	(arc
		(start 197.657132 158.822132)
		(mid 197.754459 158.887164)
		(end 197.869264 158.91)
		(width 0.16)
		(layer "F.Cu")
		(net 432)
	)
	(arc
		(start 199.997132 158.334167)
		(mid 200.062164 158.23684)
		(end 200.085 158.122035)
		(width 0.16)
		(layer "F.Cu")
		(net 432)
	)
	(arc
		(start 198.185 158.696563)
		(mid 198.231863 158.583426)
		(end 198.345 158.536563)
		(width 0.16)
		(layer "F.Cu")
		(net 432)
	)
	(arc
		(start 199.297035 158.91)
		(mid 199.41184 158.887164)
		(end 199.509167 158.822132)
		(width 0.16)
		(layer "F.Cu")
		(net 432)
	)
	(arc
		(start 198.585 158.75)
		(mid 198.631863 158.863137)
		(end 198.745 158.91)
		(width 0.16)
		(layer "F.Cu")
		(net 432)
	)
	(arc
		(start 198.425 158.536563)
		(mid 198.538137 158.583426)
		(end 198.585 158.696563)
		(width 0.16)
		(layer "F.Cu")
		(net 432)
	)
	(segment
		(start 154.438414 150.969712)
		(end 154.459351 150.990649)
		(width 0.16)
		(layer "B.Cu")
		(net 432)
	)
	(segment
		(start 192.902966 157.91)
		(end 195.139944 157.91)
		(width 0.16)
		(layer "B.Cu")
		(net 432)
	)
	(segment
		(start 155.502966 151.91)
		(end 156.108801 151.91)
		(width 0.16)
		(layer "B.Cu")
		(net 432)
	)
	(segment
		(start 157.908801 150.66)
		(end 158.108801 150.66)
		(width 0.16)
		(layer "B.Cu")
		(net 432)
	)
	(segment
		(start 178.021298 158.56)
		(end 178.065649 158.515649)
		(width 0.16)
		(layer "B.Cu")
		(net 432)
	)
	(segment
		(start 159.35 151.91)
		(end 160.097034 151.91)
		(width 0.16)
		(layer "B.Cu")
		(net 432)
	)
	(segment
		(start 179.892716 156.46)
		(end 191.077229 156.46)
		(width 0.16)
		(layer "B.Cu")
		(net 432)
	)
	(segment
		(start 153.285 147.63)
		(end 153.14 147.775)
		(width 0.16)
		(layer "B.Cu")
		(net 432)
	)
	(segment
		(start 196.502966 158.91)
		(end 197.330736 158.91)
		(width 0.16)
		(layer "B.Cu")
		(net 432)
	)
	(segment
		(start 156.908801 154.71)
		(end 157.108801 154.71)
		(width 0.16)
		(layer "B.Cu")
		(net 432)
	)
	(segment
		(start 170.79 150.775291)
		(end 170.79 154.697034)
		(width 0.16)
		(layer "B.Cu")
		(net 432)
	)
	(segment
		(start 169.255604 148.986902)
		(end 170.6104 150.341698)
		(width 0.16)
		(layer "B.Cu")
		(net 432)
	)
	(segment
		(start 177.159716 159.597122)
		(end 177.159716 159.15)
		(width 0.16)
		(layer "B.Cu")
		(net 432)
	)
	(segment
		(start 157.318801 152.5)
		(end 157.318801 151.25)
		(width 0.16)
		(layer "B.Cu")
		(net 432)
	)
	(segment
		(start 178.065649 158.515649)
		(end 178.372132 158.209166)
		(width 0.16)
		(layer "B.Cu")
		(net 432)
	)
	(segment
		(start 191.50652 156.637818)
		(end 192.690834 157.822132)
		(width 0.16)
		(layer "B.Cu")
		(net 432)
	)
	(segment
		(start 176.539716 157.902878)
		(end 176.539716 158.35)
		(width 0.16)
		(layer "B.Cu")
		(net 432)
	)
	(segment
		(start 176.539716 158.35)
		(end 176.539716 159.597122)
		(width 0.16)
		(layer "B.Cu")
		(net 432)
	)
	(segment
		(start 175.749716 157.312878)
		(end 175.949716 157.312878)
		(width 0.16)
		(layer "B.Cu")
		(net 432)
	)
	(segment
		(start 158.908801 151.91)
		(end 159.108801 151.91)
		(width 0.16)
		(layer "B.Cu")
		(net 432)
	)
	(segment
		(start 177.749716 158.56)
		(end 177.949716 158.56)
		(width 0.16)
		(layer "B.Cu")
		(net 432)
	)
	(segment
		(start 170.877868 154.909166)
		(end 174.440834 158.472132)
		(width 0.16)
		(layer "B.Cu")
		(net 432)
	)
	(segment
		(start 197.542868 158.822132)
		(end 197.6 158.765)
		(width 0.16)
		(layer "B.Cu")
		(net 432)
	)
	(segment
		(start 154.434969 150.192512)
		(end 154.500022 150.257565)
		(width 0.16)
		(layer "B.Cu")
		(net 432)
	)
	(segment
		(start 175.159716 158.35)
		(end 175.159716 157.902878)
		(width 0.16)
		(layer "B.Cu")
		(net 432)
	)
	(segment
		(start 153.227868 149.759166)
		(end 153.787876 150.319174)
		(width 0.16)
		(layer "B.Cu")
		(net 432)
	)
	(segment
		(start 158.698801 151.25)
		(end 158.698801 151.7)
		(width 0.16)
		(layer "B.Cu")
		(net 432)
	)
	(segment
		(start 159.108801 151.91)
		(end 159.35 151.91)
		(width 0.16)
		(layer "B.Cu")
		(net 432)
	)
	(segment
		(start 154.048092 150.319175)
		(end 154.174753 150.192511)
		(width 0.16)
		(layer "B.Cu")
		(net 432)
	)
	(segment
		(start 154.373359 150.904658)
		(end 154.438414 150.969712)
		(width 0.16)
		(layer "B.Cu")
		(net 432)
	)
	(segment
		(start 154.500022 150.517781)
		(end 154.373358 150.644442)
		(width 0.16)
		(layer "B.Cu")
		(net 432)
	)
	(segment
		(start 178.46 157.997034)
		(end 178.46 157.828405)
		(width 0.16)
		(layer "B.Cu")
		(net 432)
	)
	(segment
		(start 177.949716 158.56)
		(end 178.021298 158.56)
		(width 0.16)
		(layer "B.Cu")
		(net 432)
	)
	(segment
		(start 174.652966 158.56)
		(end 174.949716 158.56)
		(width 0.16)
		(layer "B.Cu")
		(net 432)
	)
	(segment
		(start 160.309166 151.822132)
		(end 163.12453 149.006768)
		(width 0.16)
		(layer "B.Cu")
		(net 432)
	)
	(segment
		(start 195.547529 158.078827)
		(end 196.290834 158.822132)
		(width 0.16)
		(layer "B.Cu")
		(net 432)
	)
	(segment
		(start 153.14 147.775)
		(end 153.14 149.547034)
		(width 0.16)
		(layer "B.Cu")
		(net 432)
	)
	(segment
		(start 156.698801 152.5)
		(end 156.698801 154.5)
		(width 0.16)
		(layer "B.Cu")
		(net 432)
	)
	(segment
		(start 154.459351 150.990649)
		(end 155.290834 151.822132)
		(width 0.16)
		(layer "B.Cu")
		(net 432)
	)
	(segment
		(start 157.318801 154.5)
		(end 157.318801 152.5)
		(width 0.16)
		(layer "B.Cu")
		(net 432)
	)
	(segment
		(start 163.59957 148.81)
		(end 168.828525 148.81)
		(width 0.16)
		(layer "B.Cu")
		(net 432)
	)
	(segment
		(start 176.749716 159.807122)
		(end 176.949716 159.807122)
		(width 0.16)
		(layer "B.Cu")
		(net 432)
	)
	(segment
		(start 178.606447 157.474851)
		(end 179.429376 156.651922)
		(width 0.16)
		(layer "B.Cu")
		(net 432)
	)
	(arc
		(start 160.097034 151.91)
		(mid 160.211839 151.887164)
		(end 160.309166 151.822132)
		(width 0.16)
		(layer "B.Cu")
		(net 432)
	)
	(arc
		(start 176.539716 159.597122)
		(mid 176.601224 159.745614)
		(end 176.749716 159.807122)
		(width 0.16)
		(layer "B.Cu")
		(net 432)
	)
	(arc
		(start 191.077229 156.46)
		(mid 191.30956 156.506213)
		(end 191.50652 156.637818)
		(width 0.16)
		(layer "B.Cu")
		(net 432)
	)
	(arc
		(start 192.690834 157.822132)
		(mid 192.788161 157.887164)
		(end 192.902966 157.91)
		(width 0.16)
		(layer "B.Cu")
		(net 432)
	)
	(arc
		(start 179.429376 156.651922)
		(mid 179.641958 156.509879)
		(end 179.892716 156.46)
		(width 0.16)
		(layer "B.Cu")
		(net 432)
	)
	(arc
		(start 175.949716 157.312878)
		(mid 176.366909 157.485685)
		(end 176.539716 157.902878)
		(width 0.16)
		(layer "B.Cu")
		(net 432)
	)
	(arc
		(start 155.290834 151.822132)
		(mid 155.388161 151.887164)
		(end 155.502966 151.91)
		(width 0.16)
		(layer "B.Cu")
		(net 432)
	)
	(arc
		(start 157.318801 151.25)
		(mid 157.491608 150.832807)
		(end 157.908801 150.66)
		(width 0.16)
		(layer "B.Cu")
		(net 432)
	)
	(arc
		(start 178.372132 158.209166)
		(mid 178.437164 158.111839)
		(end 178.46 157.997034)
		(width 0.16)
		(layer "B.Cu")
		(net 432)
	)
	(arc
		(start 197.330736 158.91)
		(mid 197.445541 158.887164)
		(end 197.542868 158.822132)
		(width 0.16)
		(layer "B.Cu")
		(net 432)
	)
	(arc
		(start 177.159716 159.15)
		(mid 177.332523 158.732807)
		(end 177.749716 158.56)
		(width 0.16)
		(layer "B.Cu")
		(net 432)
	)
	(arc
		(start 153.787876 150.319174)
		(mid 153.917984 150.373066)
		(end 154.048092 150.319175)
		(width 0.16)
		(layer "B.Cu")
		(net 432)
	)
	(arc
		(start 170.79 154.697034)
		(mid 170.812836 154.811839)
		(end 170.877868 154.909166)
		(width 0.16)
		(layer "B.Cu")
		(net 432)
	)
	(arc
		(start 157.108801 154.71)
		(mid 157.257293 154.648492)
		(end 157.318801 154.5)
		(width 0.16)
		(layer "B.Cu")
		(net 432)
	)
	(arc
		(start 154.500022 150.257565)
		(mid 154.553914 150.387673)
		(end 154.500022 150.517781)
		(width 0.16)
		(layer "B.Cu")
		(net 432)
	)
	(arc
		(start 154.373358 150.644442)
		(mid 154.319467 150.77455)
		(end 154.373359 150.904658)
		(width 0.16)
		(layer "B.Cu")
		(net 432)
	)
	(arc
		(start 175.159716 157.902878)
		(mid 175.332523 157.485685)
		(end 175.749716 157.312878)
		(width 0.16)
		(layer "B.Cu")
		(net 432)
	)
	(arc
		(start 174.949716 158.56)
		(mid 175.098208 158.498492)
		(end 175.159716 158.35)
		(width 0.16)
		(layer "B.Cu")
		(net 432)
	)
	(arc
		(start 153.14 149.547034)
		(mid 153.162836 149.661839)
		(end 153.227868 149.759166)
		(width 0.16)
		(layer "B.Cu")
		(net 432)
	)
	(arc
		(start 174.440834 158.472132)
		(mid 174.538161 158.537164)
		(end 174.652966 158.56)
		(width 0.16)
		(layer "B.Cu")
		(net 432)
	)
	(arc
		(start 196.290834 158.822132)
		(mid 196.388161 158.887164)
		(end 196.502966 158.91)
		(width 0.16)
		(layer "B.Cu")
		(net 432)
	)
	(arc
		(start 168.828525 148.81)
		(mid 169.059659 148.855975)
		(end 169.255604 148.986902)
		(width 0.16)
		(layer "B.Cu")
		(net 432)
	)
	(arc
		(start 170.6104 150.341698)
		(mid 170.743324 150.540632)
		(end 170.79 150.775291)
		(width 0.16)
		(layer "B.Cu")
		(net 432)
	)
	(arc
		(start 195.139944 157.91)
		(mid 195.360527 157.953877)
		(end 195.547529 158.078827)
		(width 0.16)
		(layer "B.Cu")
		(net 432)
	)
	(arc
		(start 156.698801 154.5)
		(mid 156.760309 154.648492)
		(end 156.908801 154.71)
		(width 0.16)
		(layer "B.Cu")
		(net 432)
	)
	(arc
		(start 156.108801 151.91)
		(mid 156.525994 152.082807)
		(end 156.698801 152.5)
		(width 0.16)
		(layer "B.Cu")
		(net 432)
	)
	(arc
		(start 178.46 157.828405)
		(mid 178.49806 157.637063)
		(end 178.606447 157.474851)
		(width 0.16)
		(layer "B.Cu")
		(net 432)
	)
	(arc
		(start 163.12453 149.006768)
		(mid 163.34248 148.861138)
		(end 163.59957 148.81)
		(width 0.16)
		(layer "B.Cu")
		(net 432)
	)
	(arc
		(start 176.949716 159.807122)
		(mid 177.098208 159.745614)
		(end 177.159716 159.597122)
		(width 0.16)
		(layer "B.Cu")
		(net 432)
	)
	(arc
		(start 154.174753 150.192511)
		(mid 154.304861 150.13862)
		(end 154.434969 150.192512)
		(width 0.16)
		(layer "B.Cu")
		(net 432)
	)
	(arc
		(start 158.698801 151.7)
		(mid 158.760309 151.848492)
		(end 158.908801 151.91)
		(width 0.16)
		(layer "B.Cu")
		(net 432)
	)
	(arc
		(start 158.108801 150.66)
		(mid 158.525994 150.832807)
		(end 158.698801 151.25)
		(width 0.16)
		(layer "B.Cu")
		(net 432)
	)
	(segment
		(start 200.465 157.47)
		(end 200.525 157.41)
		(width 0.16)
		(layer "F.Cu")
		(net 433)
	)
	(segment
		(start 200.525 157.41)
		(end 200.525 156.685)
		(width 0.16)
		(layer "F.Cu")
		(net 433)
	)
	(segment
		(start 200.465 158.196594)
		(end 200.465 157.47)
		(width 0.16)
		(layer "F.Cu")
		(net 433)
	)
	(segment
		(start 199.725148 159.143553)
		(end 200.318554 158.550147)
		(width 0.16)
		(layer "F.Cu")
		(net 433)
	)
	(segment
		(start 197.869264 159.29)
		(end 199.371594 159.29)
		(width 0.16)
		(layer "F.Cu")
		(net 433)
	)
	(segment
		(start 197.6 159.435)
		(end 197.657132 159.377868)
		(width 0.16)
		(layer "F.Cu")
		(net 433)
	)
	(via
		(at 197.6 159.435)
		(size 0.45)
		(drill 0.1)
		(layers "F.Cu" "B.Cu")
		(teardrops
			(best_length_ratio 0.4)
			(max_length 1)
			(best_width_ratio 0.9)
			(max_width 2)
			(curved_edges yes)
			(filter_ratio 0.9)
			(enabled yes)
			(allow_two_segments yes)
			(prefer_zone_connections yes)
		)
		(net 433)
	)
	(via
		(at 152.615 147.63)
		(size 0.45)
		(drill 0.1)
		(layers "F.Cu" "B.Cu")
		(remove_unused_layers yes)
		(keep_end_layers yes)
		(zone_layer_connections)
		(teardrops
			(best_length_ratio 0.4)
			(max_length 1)
			(best_width_ratio 0.9)
			(max_width 2)
			(curved_edges yes)
			(filter_ratio 0.9)
			(enabled yes)
			(allow_two_segments yes)
			(prefer_zone_connections yes)
		)
		(net 433)
	)
	(arc
		(start 197.869264 159.29)
		(mid 197.754459 159.312836)
		(end 197.657132 159.377868)
		(width 0.16)
		(layer "F.Cu")
		(net 433)
	)
	(arc
		(start 199.725148 159.143553)
		(mid 199.562936 159.25194)
		(end 199.371594 159.29)
		(width 0.16)
		(layer "F.Cu")
		(net 433)
	)
	(arc
		(start 200.465 158.196594)
		(mid 200.42694 158.387935)
		(end 200.318554 158.550147)
		(width 0.16)
		(layer "F.Cu")
		(net 433)
	)
	(segment
		(start 178.178702 158.94)
		(end 178.334351 158.784351)
		(width 0.16)
		(layer "B.Cu")
		(net 433)
	)
	(segment
		(start 155.503124 152.29)
		(end 156.108801 152.29)
		(width 0.16)
		(layer "B.Cu")
		(net 433)
	)
	(segment
		(start 170.41 150.802966)
		(end 170.41 154.771595)
		(width 0.16)
		(layer "B.Cu")
		(net 433)
	)
	(segment
		(start 191.259166 156.927868)
		(end 192.474852 158.143554)
		(width 0.16)
		(layer "B.Cu")
		(net 433)
	)
	(segment
		(start 192.828405 158.29)
		(end 195.097034 158.29)
		(width 0.16)
		(layer "B.Cu")
		(net 433)
	)
	(segment
		(start 174.578405 158.94)
		(end 174.949716 158.94)
		(width 0.16)
		(layer "B.Cu")
		(net 433)
	)
	(segment
		(start 176.749716 160.187122)
		(end 176.949716 160.187122)
		(width 0.16)
		(layer "B.Cu")
		(net 433)
	)
	(segment
		(start 195.309166 158.377868)
		(end 196.074852 159.143554)
		(width 0.16)
		(layer "B.Cu")
		(net 433)
	)
	(segment
		(start 152.958499 150.027201)
		(end 155.022017 152.090719)
		(width 0.16)
		(layer "B.Cu")
		(net 433)
	)
	(segment
		(start 163.602966 149.19)
		(end 168.797034 149.19)
		(width 0.16)
		(layer "B.Cu")
		(net 433)
	)
	(segment
		(start 196.428405 159.29)
		(end 197.330736 159.29)
		(width 0.16)
		(layer "B.Cu")
		(net 433)
	)
	(segment
		(start 176.159716 158.35)
		(end 176.159716 159.597122)
		(width 0.16)
		(layer "B.Cu")
		(net 433)
	)
	(segment
		(start 178.334351 158.784351)
		(end 178.693554 158.425148)
		(width 0.16)
		(layer "B.Cu")
		(net 433)
	)
	(segment
		(start 160.525149 152.143553)
		(end 163.390834 149.277868)
		(width 0.16)
		(layer "B.Cu")
		(net 433)
	)
	(segment
		(start 177.949716 158.94)
		(end 178.178702 158.94)
		(width 0.16)
		(layer "B.Cu")
		(net 433)
	)
	(segment
		(start 158.318801 151.25)
		(end 158.318801 151.7)
		(width 0.16)
		(layer "B.Cu")
		(net 433)
	)
	(segment
		(start 178.927868 157.690834)
		(end 179.690834 156.927868)
		(width 0.16)
		(layer "B.Cu")
		(net 433)
	)
	(segment
		(start 156.318801 152.5)
		(end 156.318801 154.5)
		(width 0.16)
		(layer "B.Cu")
		(net 433)
	)
	(segment
		(start 170.556447 155.125149)
		(end 174.224852 158.793554)
		(width 0.16)
		(layer "B.Cu")
		(net 433)
	)
	(segment
		(start 177.749716 158.94)
		(end 177.949716 158.94)
		(width 0.16)
		(layer "B.Cu")
		(net 433)
	)
	(segment
		(start 159.35 152.29)
		(end 160.171595 152.29)
		(width 0.16)
		(layer "B.Cu")
		(net 433)
	)
	(segment
		(start 177.539716 159.597122)
		(end 177.539716 159.15)
		(width 0.16)
		(layer "B.Cu")
		(net 433)
	)
	(segment
		(start 152.76 147.775)
		(end 152.76 149.547982)
		(width 0.16)
		(layer "B.Cu")
		(net 433)
	)
	(segment
		(start 156.908801 155.09)
		(end 157.108801 155.09)
		(width 0.16)
		(layer "B.Cu")
		(net 433)
	)
	(segment
		(start 175.749716 157.692878)
		(end 175.949716 157.692878)
		(width 0.16)
		(layer "B.Cu")
		(net 433)
	)
	(segment
		(start 157.698801 152.5)
		(end 157.698801 151.25)
		(width 0.16)
		(layer "B.Cu")
		(net 433)
	)
	(segment
		(start 169.009166 149.277868)
		(end 170.322132 150.590834)
		(width 0.16)
		(layer "B.Cu")
		(net 433)
	)
	(segment
		(start 152.615 147.63)
		(end 152.76 147.775)
		(width 0.16)
		(layer "B.Cu")
		(net 433)
	)
	(segment
		(start 178.84 158.071595)
		(end 178.84 157.902966)
		(width 0.16)
		(layer "B.Cu")
		(net 433)
	)
	(segment
		(start 157.908801 151.04)
		(end 158.108801 151.04)
		(width 0.16)
		(layer "B.Cu")
		(net 433)
	)
	(segment
		(start 159.108801 152.29)
		(end 159.35 152.29)
		(width 0.16)
		(layer "B.Cu")
		(net 433)
	)
	(segment
		(start 176.159716 157.902878)
		(end 176.159716 158.35)
		(width 0.16)
		(layer "B.Cu")
		(net 433)
	)
	(segment
		(start 197.542868 159.377868)
		(end 197.6 159.435)
		(width 0.16)
		(layer "B.Cu")
		(net 433)
	)
	(segment
		(start 179.902966 156.84)
		(end 191.047034 156.84)
		(width 0.16)
		(layer "B.Cu")
		(net 433)
	)
	(segment
		(start 158.908801 152.29)
		(end 159.108801 152.29)
		(width 0.16)
		(layer "B.Cu")
		(net 433)
	)
	(segment
		(start 157.698801 154.5)
		(end 157.698801 152.5)
		(width 0.16)
		(layer "B.Cu")
		(net 433)
	)
	(segment
		(start 175.539716 158.35)
		(end 175.539716 157.902878)
		(width 0.16)
		(layer "B.Cu")
		(net 433)
	)
	(arc
		(start 158.318801 151.7)
		(mid 158.491608 152.117193)
		(end 158.908801 152.29)
		(width 0.16)
		(layer "B.Cu")
		(net 433)
	)
	(arc
		(start 160.171595 152.29)
		(mid 160.362937 152.25194)
		(end 160.525149 152.143553)
		(width 0.16)
		(layer "B.Cu")
		(net 433)
	)
	(arc
		(start 196.074852 159.143554)
		(mid 196.237064 159.25194)
		(end 196.428405 159.29)
		(width 0.16)
		(layer "B.Cu")
		(net 433)
	)
	(arc
		(start 178.84 157.902966)
		(mid 178.862836 157.788161)
		(end 178.927868 157.690834)
		(width 0.16)
		(layer "B.Cu")
		(net 433)
	)
	(arc
		(start 156.108801 152.29)
		(mid 156.257293 152.351508)
		(end 156.318801 152.5)
		(width 0.16)
		(layer "B.Cu")
		(net 433)
	)
	(arc
		(start 175.539716 157.902878)
		(mid 175.601224 157.754386)
		(end 175.749716 157.692878)
		(width 0.16)
		(layer "B.Cu")
		(net 433)
	)
	(arc
		(start 152.76 149.547982)
		(mid 152.811588 149.807333)
		(end 152.958499 150.027201)
		(width 0.16)
		(layer "B.Cu")
		(net 433)
	)
	(arc
		(start 197.330736 159.29)
		(mid 197.445541 159.312836)
		(end 197.542868 159.377868)
		(width 0.16)
		(layer "B.Cu")
		(net 433)
	)
	(arc
		(start 174.949716 158.94)
		(mid 175.366909 158.767193)
		(end 175.539716 158.35)
		(width 0.16)
		(layer "B.Cu")
		(net 433)
	)
	(arc
		(start 174.224852 158.793554)
		(mid 174.387064 158.90194)
		(end 174.578405 158.94)
		(width 0.16)
		(layer "B.Cu")
		(net 433)
	)
	(arc
		(start 163.390834 149.277868)
		(mid 163.488161 149.212836)
		(end 163.602966 149.19)
		(width 0.16)
		(layer "B.Cu")
		(net 433)
	)
	(arc
		(start 170.41 154.771595)
		(mid 170.44806 154.962937)
		(end 170.556447 155.125149)
		(width 0.16)
		(layer "B.Cu")
		(net 433)
	)
	(arc
		(start 175.949716 157.692878)
		(mid 176.098208 157.754386)
		(end 176.159716 157.902878)
		(width 0.16)
		(layer "B.Cu")
		(net 433)
	)
	(arc
		(start 157.108801 155.09)
		(mid 157.525994 154.917193)
		(end 157.698801 154.5)
		(width 0.16)
		(layer "B.Cu")
		(net 433)
	)
	(arc
		(start 170.322132 150.590834)
		(mid 170.387164 150.688161)
		(end 170.41 150.802966)
		(width 0.16)
		(layer "B.Cu")
		(net 433)
	)
	(arc
		(start 176.949716 160.187122)
		(mid 177.366909 160.014315)
		(end 177.539716 159.597122)
		(width 0.16)
		(layer "B.Cu")
		(net 433)
	)
	(arc
		(start 178.84 158.071595)
		(mid 178.80194 158.262936)
		(end 178.693554 158.425148)
		(width 0.16)
		(layer "B.Cu")
		(net 433)
	)
	(arc
		(start 195.097034 158.29)
		(mid 195.211839 158.312836)
		(end 195.309166 158.377868)
		(width 0.16)
		(layer "B.Cu")
		(net 433)
	)
	(arc
		(start 158.108801 151.04)
		(mid 158.257293 151.101508)
		(end 158.318801 151.25)
		(width 0.16)
		(layer "B.Cu")
		(net 433)
	)
	(arc
		(start 156.318801 154.5)
		(mid 156.491608 154.917193)
		(end 156.908801 155.09)
		(width 0.16)
		(layer "B.Cu")
		(net 433)
	)
	(arc
		(start 179.690834 156.927868)
		(mid 179.788161 156.862836)
		(end 179.902966 156.84)
		(width 0.16)
		(layer "B.Cu")
		(net 433)
	)
	(arc
		(start 168.797034 149.19)
		(mid 168.911839 149.212836)
		(end 169.009166 149.277868)
		(width 0.16)
		(layer "B.Cu")
		(net 433)
	)
	(arc
		(start 191.047034 156.84)
		(mid 191.161839 156.862836)
		(end 191.259166 156.927868)
		(width 0.16)
		(layer "B.Cu")
		(net 433)
	)
	(arc
		(start 157.698801 151.25)
		(mid 157.760309 151.101508)
		(end 157.908801 151.04)
		(width 0.16)
		(layer "B.Cu")
		(net 433)
	)
	(arc
		(start 177.539716 159.15)
		(mid 177.601224 159.001508)
		(end 177.749716 158.94)
		(width 0.16)
		(layer "B.Cu")
		(net 433)
	)
	(arc
		(start 192.474852 158.143554)
		(mid 192.637064 158.25194)
		(end 192.828405 158.29)
		(width 0.16)
		(layer "B.Cu")
		(net 433)
	)
	(arc
		(start 155.022017 152.090719)
		(mid 155.242751 152.238209)
		(end 155.503124 152.29)
		(width 0.16)
		(layer "B.Cu")
		(net 433)
	)
	(arc
		(start 176.159716 159.597122)
		(mid 176.332523 160.014315)
		(end 176.749716 160.187122)
		(width 0.16)
		(layer "B.Cu")
		(net 433)
	)
	(segment
		(start 249.475 132.893)
		(end 249.469 132.887)
		(width 0.125)
		(layer "F.Cu")
		(net 434)
	)
	(segment
		(start 204.025 156.685)
		(end 204.025 155.5)
		(width 0.125)
		(layer "F.Cu")
		(net 434)
	)
	(segment
		(start 221.55 149.125)
		(end 223.35 149.125)
		(width 0.125)
		(layer "F.Cu")
		(net 434)
	)
	(segment
		(start 204.025 155.5)
		(end 204.05 155.475)
		(width 0.125)
		(layer "F.Cu")
		(net 434)
	)
	(segment
		(start 247.825 133.45)
		(end 248.15 133.775)
		(width 0.125)
		(layer "F.Cu")
		(net 434)
	)
	(segment
		(start 230.4 148.4)
		(end 231.95 149.95)
		(width 0.125)
		(layer "F.Cu")
		(net 434)
	)
	(segment
		(start 247.825 132.84)
		(end 247.825 133.45)
		(width 0.125)
		(layer "F.Cu")
		(net 434)
	)
	(segment
		(start 224.075 148.4)
		(end 230.4 148.4)
		(width 0.125)
		(layer "F.Cu")
		(net 434)
	)
	(segment
		(start 223.35 149.125)
		(end 224.075 148.4)
		(width 0.125)
		(layer "F.Cu")
		(net 434)
	)
	(segment
		(start 245.35 149.95)
		(end 245.7 149.6)
		(width 0.125)
		(layer "F.Cu")
		(net 434)
	)
	(segment
		(start 248.15 133.775)
		(end 249.475 133.775)
		(width 0.125)
		(layer "F.Cu")
		(net 434)
	)
	(segment
		(start 249.475 133.775)
		(end 249.475 132.893)
		(width 0.125)
		(layer "F.Cu")
		(net 434)
	)
	(segment
		(start 231.95 149.95)
		(end 245.35 149.95)
		(width 0.125)
		(layer "F.Cu")
		(net 434)
	)
	(via
		(at 204.05 155.475)
		(size 0.45)
		(drill 0.1)
		(layers "F.Cu" "B.Cu")
		(teardrops
			(best_length_ratio 0.4)
			(max_length 1)
			(best_width_ratio 0.9)
			(max_width 2)
			(curved_edges yes)
			(filter_ratio 0.9)
			(enabled yes)
			(allow_two_segments yes)
			(prefer_zone_connections yes)
		)
		(net 434)
	)
	(via
		(at 221.55 149.125)
		(size 0.45)
		(drill 0.1)
		(layers "F.Cu" "B.Cu")
		(teardrops
			(best_length_ratio 0.4)
			(max_length 1)
			(best_width_ratio 0.9)
			(max_width 2)
			(curved_edges yes)
			(filter_ratio 0.9)
			(enabled yes)
			(allow_two_segments yes)
			(prefer_zone_connections yes)
		)
		(net 434)
	)
	(via
		(at 249.475 133.775)
		(size 0.45)
		(drill 0.1)
		(layers "F.Cu" "B.Cu")
		(teardrops
			(best_length_ratio 0.4)
			(max_length 1)
			(best_width_ratio 0.9)
			(max_width 2)
			(curved_edges yes)
			(filter_ratio 0.9)
			(enabled yes)
			(allow_two_segments yes)
			(prefer_zone_connections yes)
		)
		(net 434)
	)
	(via
		(at 245.7 149.6)
		(size 0.45)
		(drill 0.1)
		(layers "F.Cu" "B.Cu")
		(teardrops
			(best_length_ratio 0.4)
			(max_length 1)
			(best_width_ratio 0.9)
			(max_width 2)
			(curved_edges yes)
			(filter_ratio 0.9)
			(enabled yes)
			(allow_two_segments yes)
			(prefer_zone_connections yes)
		)
		(net 434)
	)
	(segment
		(start 214.75 154.85)
		(end 220.475 149.125)
		(width 0.125)
		(layer "In2.Cu")
		(net 434)
	)
	(segment
		(start 220.475 149.125)
		(end 221.55 149.125)
		(width 0.125)
		(layer "In2.Cu")
		(net 434)
	)
	(segment
		(start 204.675 154.85)
		(end 214.75 154.85)
		(width 0.125)
		(layer "In2.Cu")
		(net 434)
	)
	(segment
		(start 204.05 155.475)
		(end 204.675 154.85)
		(width 0.125)
		(layer "In2.Cu")
		(net 434)
	)
	(segment
		(start 249.475 145.825)
		(end 249.475 133.775)
		(width 0.125)
		(layer "In5.Cu")
		(net 434)
	)
	(segment
		(start 245.7 149.6)
		(end 249.475 145.825)
		(width 0.125)
		(layer "In5.Cu")
		(net 434)
	)
	(segment
		(start 209.025 157.875)
		(end 208.85 158.05)
		(width 0.125)
		(layer "F.Cu")
		(net 439)
	)
	(segment
		(start 209.025 156.685)
		(end 209.025 157.875)
		(width 0.125)
		(layer "F.Cu")
		(net 439)
	)
	(via
		(at 208.85 158.05)
		(size 0.45)
		(drill 0.1)
		(layers "F.Cu" "B.Cu")
		(teardrops
			(best_length_ratio 0.4)
			(max_length 1)
			(best_width_ratio 0.9)
			(max_width 2)
			(curved_edges yes)
			(filter_ratio 0.9)
			(enabled yes)
			(allow_two_segments yes)
			(prefer_zone_connections yes)
		)
		(net 439)
	)
	(segment
		(start 208.85 158.05)
		(end 208.85 156)
		(width 0.125)
		(layer "B.Cu")
		(net 439)
	)
	(segment
		(start 208.85 156)
		(end 208.8 155.95)
		(width 0.125)
		(layer "B.Cu")
		(net 439)
	)
	(segment
		(start 184.025 151.135)
		(end 184.025 149.325)
		(width 0.125)
		(layer "F.Cu")
		(net 471)
	)
	(segment
		(start 184.025 149.325)
		(end 184.25 149.1)
		(width 0.125)
		(layer "F.Cu")
		(net 471)
	)
	(via
		(at 184.25 149.1)
		(size 0.45)
		(drill 0.1)
		(layers "F.Cu" "B.Cu")
		(teardrops
			(best_length_ratio 0.4)
			(max_length 1)
			(best_width_ratio 0.9)
			(max_width 2)
			(curved_edges yes)
			(filter_ratio 0.9)
			(enabled yes)
			(allow_two_segments yes)
			(prefer_zone_connections yes)
		)
		(net 471)
	)
	(segment
		(start 192.8 149.2)
		(end 192.8 149.7)
		(width 0.125)
		(layer "F.Cu")
		(net 484)
	)
	(segment
		(start 193.025 149.925)
		(end 193.025 151.135)
		(width 0.125)
		(layer "F.Cu")
		(net 484)
	)
	(segment
		(start 192.8 149.7)
		(end 193.025 149.925)
		(width 0.125)
		(layer "F.Cu")
		(net 484)
	)
	(via
		(at 192.8 149.2)
		(size 0.45)
		(drill 0.1)
		(layers "F.Cu" "B.Cu")
		(teardrops
			(best_length_ratio 0.4)
			(max_length 1)
			(best_width_ratio 0.9)
			(max_width 2)
			(curved_edges yes)
			(filter_ratio 0.9)
			(enabled yes)
			(allow_two_segments yes)
			(prefer_zone_connections yes)
		)
		(net 484)
	)
	(segment
		(start 192.8 149.2)
		(end 192.8 149.6)
		(width 0.125)
		(layer "B.Cu")
		(net 484)
	)
	(segment
		(start 193.607538 150.407538)
		(end 193.607538 150.457538)
		(width 0.125)
		(layer "B.Cu")
		(net 484)
	)
	(segment
		(start 192.8 149.6)
		(end 193.607538 150.407538)
		(width 0.125)
		(layer "B.Cu")
		(net 484)
	)
	(segment
		(start 194.25 149.875)
		(end 194.375 149.875)
		(width 0.125)
		(layer "F.Cu")
		(net 487)
	)
	(segment
		(start 194.1 148.7)
		(end 194.1 149.725)
		(width 0.125)
		(layer "F.Cu")
		(net 487)
	)
	(segment
		(start 194.1 149.725)
		(end 194.25 149.875)
		(width 0.125)
		(layer "F.Cu")
		(net 487)
	)
	(segment
		(start 193.4 148)
		(end 194.1 148.7)
		(width 0.125)
		(layer "F.Cu")
		(net 487)
	)
	(segment
		(start 194.525 150.025)
		(end 194.525 151.135)
		(width 0.125)
		(layer "F.Cu")
		(net 487)
	)
	(segment
		(start 178.88 148)
		(end 193.4 148)
		(width 0.125)
		(layer "F.Cu")
		(net 487)
	)
	(segment
		(start 194.375 149.875)
		(end 194.525 150.025)
		(width 0.125)
		(layer "F.Cu")
		(net 487)
	)
	(segment
		(start 193.55 147.55)
		(end 194.55 148.55)
		(width 0.125)
		(layer "F.Cu")
		(net 488)
	)
	(segment
		(start 194.55 149.65)
		(end 195.025 150.125)
		(width 0.125)
		(layer "F.Cu")
		(net 488)
	)
	(segment
		(start 181.8 147)
		(end 182.35 147.55)
		(width 0.125)
		(layer "F.Cu")
		(net 488)
	)
	(segment
		(start 178.88 147)
		(end 181.8 147)
		(width 0.125)
		(layer "F.Cu")
		(net 488)
	)
	(segment
		(start 195.025 150.125)
		(end 195.025 151.135)
		(width 0.125)
		(layer "F.Cu")
		(net 488)
	)
	(segment
		(start 182.35 147.55)
		(end 193.55 147.55)
		(width 0.125)
		(layer "F.Cu")
		(net 488)
	)
	(segment
		(start 194.55 148.55)
		(end 194.55 149.65)
		(width 0.125)
		(layer "F.Cu")
		(net 488)
	)
	(segment
		(start 195.525 150.025)
		(end 195.525 151.135)
		(width 0.125)
		(layer "F.Cu")
		(net 489)
	)
	(segment
		(start 195 149.5)
		(end 195.525 150.025)
		(width 0.125)
		(layer "F.Cu")
		(net 489)
	)
	(via
		(at 195 149.5)
		(size 0.45)
		(drill 0.1)
		(layers "F.Cu" "B.Cu")
		(teardrops
			(best_length_ratio 0.4)
			(max_length 1)
			(best_width_ratio 0.9)
			(max_width 2)
			(curved_edges yes)
			(filter_ratio 0.9)
			(enabled yes)
			(allow_two_segments yes)
			(prefer_zone_connections yes)
		)
		(net 489)
	)
	(segment
		(start 194.35 150.15)
		(end 194.35 151.2)
		(width 0.125)
		(layer "B.Cu")
		(net 489)
	)
	(segment
		(start 195 149.5)
		(end 194.35 150.15)
		(width 0.125)
		(layer "B.Cu")
		(net 489)
	)
	(segment
		(start 198.025 151.135)
		(end 198.025 149.575)
		(width 0.125)
		(layer "F.Cu")
		(net 490)
	)
	(segment
		(start 178.925 139.7)
		(end 173.5 139.7)
		(width 0.125)
		(layer "F.Cu")
		(net 490)
	)
	(segment
		(start 183.475 146.1)
		(end 183.45 146.075)
		(width 0.125)
		(layer "F.Cu")
		(net 490)
	)
	(segment
		(start 181.75 142.525)
		(end 178.925 139.7)
		(width 0.125)
		(layer "F.Cu")
		(net 490)
	)
	(segment
		(start 184.45 146.1)
		(end 183.475 146.1)
		(width 0.125)
		(layer "F.Cu")
		(net 490)
	)
	(segment
		(start 198.025 149.575)
		(end 197.8 149.35)
		(width 0.125)
		(layer "F.Cu")
		(net 490)
	)
	(segment
		(start 125.682 152.512)
		(end 125.682 151.411)
		(width 0.125)
		(layer "F.Cu")
		(net 490)
	)
	(segment
		(start 197.8 149.35)
		(end 196.825 149.35)
		(width 0.125)
		(layer "F.Cu")
		(net 490)
	)
	(segment
		(start 181.75 144.375)
		(end 181.75 142.525)
		(width 0.125)
		(layer "F.Cu")
		(net 490)
	)
	(segment
		(start 183.45 146.075)
		(end 181.75 144.375)
		(width 0.125)
		(layer "F.Cu")
		(net 490)
	)
	(via
		(at 125.682 152.512)
		(size 0.45)
		(drill 0.1)
		(layers "F.Cu" "B.Cu")
		(remove_unused_layers yes)
		(keep_end_layers yes)
		(zone_layer_connections "In5.Cu")
		(teardrops
			(best_length_ratio 0.4)
			(max_length 1)
			(best_width_ratio 0.9)
			(max_width 2)
			(curved_edges yes)
			(filter_ratio 0.9)
			(enabled yes)
			(allow_two_segments yes)
			(prefer_zone_connections yes)
		)
		(net 490)
	)
	(via
		(at 139.075 153.5)
		(size 0.45)
		(drill 0.1)
		(layers "F.Cu" "B.Cu")
		(teardrops
			(best_length_ratio 0.4)
			(max_length 1)
			(best_width_ratio 0.9)
			(max_width 2)
			(curved_edges yes)
			(filter_ratio 0.9)
			(enabled yes)
			(allow_two_segments yes)
			(prefer_zone_connections yes)
		)
		(net 490)
	)
	(via
		(at 173.5 139.7)
		(size 0.45)
		(drill 0.1)
		(layers "F.Cu" "B.Cu")
		(teardrops
			(best_length_ratio 0.4)
			(max_length 1)
			(best_width_ratio 0.9)
			(max_width 2)
			(curved_edges yes)
			(filter_ratio 0.9)
			(enabled yes)
			(allow_two_segments yes)
			(prefer_zone_connections yes)
		)
		(net 490)
	)
	(via
		(at 196.825 149.35)
		(size 0.45)
		(drill 0.1)
		(layers "F.Cu" "B.Cu")
		(teardrops
			(best_length_ratio 0.4)
			(max_length 1)
			(best_width_ratio 0.9)
			(max_width 2)
			(curved_edges yes)
			(filter_ratio 0.9)
			(enabled yes)
			(allow_two_segments yes)
			(prefer_zone_connections yes)
		)
		(net 490)
	)
	(via
		(at 184.45 146.1)
		(size 0.45)
		(drill 0.1)
		(layers "F.Cu" "B.Cu")
		(teardrops
			(best_length_ratio 0.4)
			(max_length 1)
			(best_width_ratio 0.9)
			(max_width 2)
			(curved_edges yes)
			(filter_ratio 0.9)
			(enabled yes)
			(allow_two_segments yes)
			(prefer_zone_connections yes)
		)
		(net 490)
	)
	(segment
		(start 194.6 153.45)
		(end 193.3 154.75)
		(width 0.125)
		(layer "In2.Cu")
		(net 490)
	)
	(segment
		(start 162 144.575)
		(end 166.875 139.7)
		(width 0.125)
		(layer "In2.Cu")
		(net 490)
	)
	(segment
		(start 154.425 151.05)
		(end 160.475 151.05)
		(width 0.125)
		(layer "In2.Cu")
		(net 490)
	)
	(segment
		(start 166.875 139.7)
		(end 173.5 139.7)
		(width 0.125)
		(layer "In2.Cu")
		(net 490)
	)
	(segment
		(start 154.035 151.44)
		(end 154.425 151.05)
		(width 0.125)
		(layer "In2.Cu")
		(net 490)
	)
	(segment
		(start 194.6 151.575)
		(end 194.6 153.45)
		(width 0.125)
		(layer "In2.Cu")
		(net 490)
	)
	(segment
		(start 184.45 146.475)
		(end 184.45 146.1)
		(width 0.125)
		(layer "In2.Cu")
		(net 490)
	)
	(segment
		(start 189.2 153.425)
		(end 191.1 153.425)
		(width 0.125)
		(layer "In2.Cu")
		(net 490)
	)
	(segment
		(start 192.425 154.75)
		(end 193.3 154.75)
		(width 0.125)
		(layer "In2.Cu")
		(net 490)
	)
	(segment
		(start 160.475 151.05)
		(end 162 149.525)
		(width 0.125)
		(layer "In2.Cu")
		(net 490)
	)
	(segment
		(start 189.2 153.425)
		(end 188.6 152.825)
		(width 0.125)
		(layer "In2.Cu")
		(net 490)
	)
	(segment
		(start 188.6 152.825)
		(end 188.6 150.625)
		(width 0.125)
		(layer "In2.Cu")
		(net 490)
	)
	(segment
		(start 191.1 153.425)
		(end 192.425 154.75)
		(width 0.125)
		(layer "In2.Cu")
		(net 490)
	)
	(segment
		(start 196.825 149.35)
		(end 194.6 151.575)
		(width 0.125)
		(layer "In2.Cu")
		(net 490)
	)
	(segment
		(start 141.075 153.5)
		(end 143.135 151.44)
		(width 0.125)
		(layer "In2.Cu")
		(net 490)
	)
	(segment
		(start 162 149.525)
		(end 162 144.575)
		(width 0.125)
		(layer "In2.Cu")
		(net 490)
	)
	(segment
		(start 184.45 146.475)
		(end 188.6 150.625)
		(width 0.125)
		(layer "In2.Cu")
		(net 490)
	)
	(segment
		(start 139.075 153.5)
		(end 141.075 153.5)
		(width 0.125)
		(layer "In2.Cu")
		(net 490)
	)
	(segment
		(start 143.135 151.44)
		(end 154.035 151.44)
		(width 0.125)
		(layer "In2.Cu")
		(net 490)
	)
	(segment
		(start 139.065 153.51)
		(end 139.075 153.5)
		(width 0.125)
		(layer "In5.Cu")
		(net 490)
	)
	(segment
		(start 126.68 153.51)
		(end 139.065 153.51)
		(width 0.125)
		(layer "In5.Cu")
		(net 490)
	)
	(segment
		(start 126.68 153.51)
		(end 125.682 152.512)
		(width 0.125)
		(layer "In5.Cu")
		(net 490)
	)
	(segment
		(start 143.839 152.51)
		(end 143.839 151.409)
		(width 0.125)
		(layer "F.Cu")
		(net 491)
	)
	(segment
		(start 197.55 147.725)
		(end 194.95 147.725)
		(width 0.125)
		(layer "F.Cu")
		(net 491)
	)
	(segment
		(start 198.525 151.135)
		(end 198.525 148.7)
		(width 0.125)
		(layer "F.Cu")
		(net 491)
	)
	(segment
		(start 197.55 147.725)
		(end 198.525 148.7)
		(width 0.125)
		(layer "F.Cu")
		(net 491)
	)
	(via
		(at 143.839 152.51)
		(size 0.45)
		(drill 0.1)
		(layers "F.Cu" "B.Cu")
		(remove_unused_layers yes)
		(keep_end_layers yes)
		(zone_layer_connections "In2.Cu")
		(teardrops
			(best_length_ratio 0.4)
			(max_length 1)
			(best_width_ratio 0.9)
			(max_width 2)
			(curved_edges yes)
			(filter_ratio 0.9)
			(enabled yes)
			(allow_two_segments yes)
			(prefer_zone_connections yes)
		)
		(net 491)
	)
	(via
		(at 194.95 147.725)
		(size 0.45)
		(drill 0.1)
		(layers "F.Cu" "B.Cu")
		(teardrops
			(best_length_ratio 0.4)
			(max_length 1)
			(best_width_ratio 0.9)
			(max_width 2)
			(curved_edges yes)
			(filter_ratio 0.9)
			(enabled yes)
			(allow_two_segments yes)
			(prefer_zone_connections yes)
		)
		(net 491)
	)
	(segment
		(start 194.075 153.475)
		(end 194.075 148.6)
		(width 0.125)
		(layer "In2.Cu")
		(net 491)
	)
	(segment
		(start 143.839 152.261)
		(end 144.325 151.775)
		(width 0.125)
		(layer "In2.Cu")
		(net 491)
	)
	(segment
		(start 193.125 154.425)
		(end 194.075 153.475)
		(width 0.125)
		(layer "In2.Cu")
		(net 491)
	)
	(segment
		(start 179.55 149)
		(end 183.5 145.05)
		(width 0.125)
		(layer "In2.Cu")
		(net 491)
	)
	(segment
		(start 194.075 148.6)
		(end 194.95 147.725)
		(width 0.125)
		(layer "In2.Cu")
		(net 491)
	)
	(segment
		(start 144.325 151.775)
		(end 154.6 151.775)
		(width 0.125)
		(layer "In2.Cu")
		(net 491)
	)
	(segment
		(start 183.5 145.05)
		(end 185.45 145.05)
		(width 0.125)
		(layer "In2.Cu")
		(net 491)
	)
	(segment
		(start 143.839 152.51)
		(end 143.839 152.261)
		(width 0.125)
		(layer "In2.Cu")
		(net 491)
	)
	(segment
		(start 173.975 149)
		(end 179.55 149)
		(width 0.125)
		(layer "In2.Cu")
		(net 491)
	)
	(segment
		(start 155.075 151.3)
		(end 171.675 151.3)
		(width 0.125)
		(layer "In2.Cu")
		(net 491)
	)
	(segment
		(start 191.525 151.125)
		(end 191.525 153.4)
		(width 0.125)
		(layer "In2.Cu")
		(net 491)
	)
	(segment
		(start 154.6 151.775)
		(end 155.075 151.3)
		(width 0.125)
		(layer "In2.Cu")
		(net 491)
	)
	(segment
		(start 191.525 153.4)
		(end 192.55 154.425)
		(width 0.125)
		(layer "In2.Cu")
		(net 491)
	)
	(segment
		(start 171.675 151.3)
		(end 173.975 149)
		(width 0.125)
		(layer "In2.Cu")
		(net 491)
	)
	(segment
		(start 192.55 154.425)
		(end 193.125 154.425)
		(width 0.125)
		(layer "In2.Cu")
		(net 491)
	)
	(segment
		(start 185.45 145.05)
		(end 191.525 151.125)
		(width 0.125)
		(layer "In2.Cu")
		(net 491)
	)
	(segment
		(start 182.8 147.05)
		(end 197.525 147.05)
		(width 0.125)
		(layer "F.Cu")
		(net 492)
	)
	(segment
		(start 199.025 148.55)
		(end 199.025 151.135)
		(width 0.125)
		(layer "F.Cu")
		(net 492)
	)
	(segment
		(start 178.88 145.999999)
		(end 181.749999 145.999999)
		(width 0.125)
		(layer "F.Cu")
		(net 492)
	)
	(segment
		(start 197.525 147.05)
		(end 199.025 148.55)
		(width 0.125)
		(layer "F.Cu")
		(net 492)
	)
	(segment
		(start 181.749999 145.999999)
		(end 182.8 147.05)
		(width 0.125)
		(layer "F.Cu")
		(net 492)
	)
	(segment
		(start 216.42 70.61)
		(end 216.42 78.1)
		(width 0.2)
		(layer "F.Cu")
		(net 523)
	)
	(segment
		(start 208.459 76.351)
		(end 208.459 78.11)
		(width 0.2)
		(layer "F.Cu")
		(net 525)
	)
	(segment
		(start 208.959 75.851)
		(end 208.459 76.351)
		(width 0.2)
		(layer "F.Cu")
		(net 525)
	)
	(segment
		(start 208.959 70.61)
		(end 208.959 75.851)
		(width 0.2)
		(layer "F.Cu")
		(net 525)
	)
	(segment
		(start 316.748 164.458)
		(end 315.135 164.458)
		(width 0.125)
		(layer "F.Cu")
		(net 526)
	)
	(segment
		(start 200.3 122.6)
		(end 204.2 126.5)
		(width 0.125)
		(layer "F.Cu")
		(net 526)
	)
	(segment
		(start 317.2 164.91)
		(end 316.748 164.458)
		(width 0.125)
		(layer "F.Cu")
		(net 526)
	)
	(segment
		(start 315.135 164.458)
		(end 314.363 164.458)
		(width 0.125)
		(layer "F.Cu")
		(net 526)
	)
	(segment
		(start 160.5 108.6)
		(end 163.95 112.05)
		(width 0.125)
		(layer "F.Cu")
		(net 526)
	)
	(segment
		(start 310.95 165.26)
		(end 312.15 165.26)
		(width 0.125)
		(layer "F.Cu")
		(net 526)
	)
	(segment
		(start 310.5 165.71)
		(end 310.95 165.26)
		(width 0.125)
		(layer "F.Cu")
		(net 526)
	)
	(segment
		(start 222.08 133.58)
		(end 219.432501 133.58)
		(width 0.125)
		(layer "F.Cu")
		(net 526)
	)
	(segment
		(start 159.675 108.6)
		(end 160.5 108.6)
		(width 0.125)
		(layer "F.Cu")
		(net 526)
	)
	(segment
		(start 312.15 165.26)
		(end 312.952 164.458)
		(width 0.125)
		(layer "F.Cu")
		(net 526)
	)
	(segment
		(start 319.45 164.91)
		(end 317.2 164.91)
		(width 0.125)
		(layer "F.Cu")
		(net 526)
	)
	(segment
		(start 204.2 126.5)
		(end 208.7 126.5)
		(width 0.125)
		(layer "F.Cu")
		(net 526)
	)
	(segment
		(start 312.952 164.458)
		(end 314.363 164.458)
		(width 0.125)
		(layer "F.Cu")
		(net 526)
	)
	(segment
		(start 200.3 121.75)
		(end 200.3 122.6)
		(width 0.125)
		(layer "F.Cu")
		(net 526)
	)
	(segment
		(start 222.1 133.56)
		(end 222.08 133.58)
		(width 0.125)
		(layer "F.Cu")
		(net 526)
	)
	(via
		(at 310.5 165.71)
		(size 0.45)
		(drill 0.1)
		(layers "F.Cu" "B.Cu")
		(remove_unused_layers yes)
		(keep_end_layers yes)
		(zone_layer_connections "In2.Cu")
		(teardrops
			(best_length_ratio 0.4)
			(max_length 1)
			(best_width_ratio 0.9)
			(max_width 2)
			(curved_edges yes)
			(filter_ratio 0.9)
			(enabled yes)
			(allow_two_segments yes)
			(prefer_zone_connections yes)
		)
		(net 526)
	)
	(via
		(at 200.3 121.75)
		(size 0.45)
		(drill 0.1)
		(layers "F.Cu" "B.Cu")
		(teardrops
			(best_length_ratio 0.4)
			(max_length 1)
			(best_width_ratio 0.9)
			(max_width 2)
			(curved_edges yes)
			(filter_ratio 0.9)
			(enabled yes)
			(allow_two_segments yes)
			(prefer_zone_connections yes)
		)
		(net 526)
	)
	(via
		(at 208.7 126.5)
		(size 0.45)
		(drill 0.1)
		(layers "F.Cu" "B.Cu")
		(teardrops
			(best_length_ratio 0.4)
			(max_length 1)
			(best_width_ratio 0.9)
			(max_width 2)
			(curved_edges yes)
			(filter_ratio 0.9)
			(enabled yes)
			(allow_two_segments yes)
			(prefer_zone_connections yes)
		)
		(net 526)
	)
	(via
		(at 159.675 108.6)
		(size 0.45)
		(drill 0.1)
		(layers "F.Cu" "B.Cu")
		(teardrops
			(best_length_ratio 0.4)
			(max_length 1)
			(best_width_ratio 0.9)
			(max_width 2)
			(curved_edges yes)
			(filter_ratio 0.9)
			(enabled yes)
			(allow_two_segments yes)
			(prefer_zone_connections yes)
		)
		(net 526)
	)
	(via
		(at 130.15 89.99)
		(size 0.45)
		(drill 0.1)
		(layers "F.Cu" "B.Cu")
		(remove_unused_layers yes)
		(keep_end_layers yes)
		(zone_layer_connections "In2.Cu")
		(teardrops
			(best_length_ratio 0.4)
			(max_length 1)
			(best_width_ratio 0.9)
			(max_width 2)
			(curved_edges yes)
			(filter_ratio 0.9)
			(enabled yes)
			(allow_two_segments yes)
			(prefer_zone_connections yes)
		)
		(net 526)
	)
	(via
		(at 222.1 133.56)
		(size 0.45)
		(drill 0.1)
		(layers "F.Cu" "B.Cu")
		(remove_unused_layers yes)
		(keep_end_layers yes)
		(zone_layer_connections "In2.Cu" "In5.Cu")
		(teardrops
			(best_length_ratio 0.4)
			(max_length 1)
			(best_width_ratio 0.9)
			(max_width 2)
			(curved_edges yes)
			(filter_ratio 0.9)
			(enabled yes)
			(allow_two_segments yes)
			(prefer_zone_connections yes)
		)
		(net 526)
	)
	(via
		(at 163.95 112.05)
		(size 0.45)
		(drill 0.1)
		(layers "F.Cu" "B.Cu")
		(teardrops
			(best_length_ratio 0.4)
			(max_length 1)
			(best_width_ratio 0.9)
			(max_width 2)
			(curved_edges yes)
			(filter_ratio 0.9)
			(enabled yes)
			(allow_two_segments yes)
			(prefer_zone_connections yes)
		)
		(net 526)
	)
	(segment
		(start 295.9 164.31)
		(end 291.82 160.23)
		(width 0.125)
		(layer "In2.Cu")
		(net 526)
	)
	(segment
		(start 291.82 154.47)
		(end 287.155 149.805)
		(width 0.125)
		(layer "In2.Cu")
		(net 526)
	)
	(segment
		(start 309.9 165.71)
		(end 310.5 165.71)
		(width 0.125)
		(layer "In2.Cu")
		(net 526)
	)
	(segment
		(start 308.5 164.31)
		(end 295.9 164.31)
		(width 0.125)
		(layer "In2.Cu")
		(net 526)
	)
	(segment
		(start 274.2 142.61)
		(end 231.15 142.61)
		(width 0.125)
		(layer "In2.Cu")
		(net 526)
	)
	(segment
		(start 187.95 130.25)
		(end 196.45 121.75)
		(width 0.125)
		(layer "In2.Cu")
		(net 526)
	)
	(segment
		(start 196.45 121.75)
		(end 200.3 121.75)
		(width 0.125)
		(layer "In2.Cu")
		(net 526)
	)
	(segment
		(start 291.82 160.23)
		(end 291.82 154.47)
		(width 0.125)
		(layer "In2.Cu")
		(net 526)
	)
	(segment
		(start 148.76 108.6)
		(end 130.15 89.99)
		(width 0.125)
		(layer "In2.Cu")
		(net 526)
	)
	(segment
		(start 163.95 112.05)
		(end 182.15 130.25)
		(width 0.125)
		(layer "In2.Cu")
		(net 526)
	)
	(segment
		(start 308.5 164.31)
		(end 309.9 165.71)
		(width 0.125)
		(layer "In2.Cu")
		(net 526)
	)
	(segment
		(start 159.675 108.6)
		(end 148.76 108.6)
		(width 0.125)
		(layer "In2.Cu")
		(net 526)
	)
	(segment
		(start 281.395 149.805)
		(end 274.2 142.61)
		(width 0.125)
		(layer "In2.Cu")
		(net 526)
	)
	(segment
		(start 287.155 149.805)
		(end 281.395 149.805)
		(width 0.125)
		(layer "In2.Cu")
		(net 526)
	)
	(segment
		(start 182.15 130.25)
		(end 187.95 130.25)
		(width 0.125)
		(layer "In2.Cu")
		(net 526)
	)
	(segment
		(start 231.15 142.61)
		(end 222.1 133.56)
		(width 0.125)
		(layer "In2.Cu")
		(net 526)
	)
	(segment
		(start 219.3 129.2)
		(end 222.1 132)
		(width 0.125)
		(layer "In5.Cu")
		(net 526)
	)
	(segment
		(start 208.7 123.45)
		(end 211.15 121)
		(width 0.125)
		(layer "In5.Cu")
		(net 526)
	)
	(segment
		(start 208.7 126.5)
		(end 208.7 123.45)
		(width 0.125)
		(layer "In5.Cu")
		(net 526)
	)
	(segment
		(start 219.3 122.85)
		(end 219.3 129.2)
		(width 0.125)
		(layer "In5.Cu")
		(net 526)
	)
	(segment
		(start 217.45 121)
		(end 219.3 122.85)
		(width 0.125)
		(layer "In5.Cu")
		(net 526)
	)
	(segment
		(start 211.15 121)
		(end 217.45 121)
		(width 0.125)
		(layer "In5.Cu")
		(net 526)
	)
	(segment
		(start 222.1 132)
		(end 222.1 133.56)
		(width 0.125)
		(layer "In5.Cu")
		(net 526)
	)
	(segment
		(start 313.252 164.958)
		(end 314.363 164.958)
		(width 0.125)
		(layer "F.Cu")
		(net 527)
	)
	(segment
		(start 311.35 165.71)
		(end 312.5 165.71)
		(width 0.125)
		(layer "F.Cu")
		(net 527)
	)
	(segment
		(start 312.5 165.71)
		(end 313.252 164.958)
		(width 0.125)
		(layer "F.Cu")
		(net 527)
	)
	(segment
		(start 317.35 165.71)
		(end 316.598 164.958)
		(width 0.125)
		(layer "F.Cu")
		(net 527)
	)
	(segment
		(start 319.45 165.71)
		(end 317.35 165.71)
		(width 0.125)
		(layer "F.Cu")
		(net 527)
	)
	(segment
		(start 130.4 75.76)
		(end 130.4 78.06)
		(width 0.125)
		(layer "F.Cu")
		(net 527)
	)
	(segment
		(start 315.135 164.958)
		(end 314.363 164.958)
		(width 0.125)
		(layer "F.Cu")
		(net 527)
	)
	(segment
		(start 316.598 164.958)
		(end 315.135 164.958)
		(width 0.125)
		(layer "F.Cu")
		(net 527)
	)
	(via
		(at 311.35 165.71)
		(size 0.45)
		(drill 0.1)
		(layers "F.Cu" "B.Cu")
		(remove_unused_layers yes)
		(keep_end_layers yes)
		(zone_layer_connections "In5.Cu")
		(teardrops
			(best_length_ratio 0.4)
			(max_length 1)
			(best_width_ratio 0.9)
			(max_width 2)
			(curved_edges yes)
			(filter_ratio 0.9)
			(enabled yes)
			(allow_two_segments yes)
			(prefer_zone_connections yes)
		)
		(net 527)
	)
	(via
		(at 130.4 75.76)
		(size 0.45)
		(drill 0.1)
		(layers "F.Cu" "B.Cu")
		(remove_unused_layers yes)
		(keep_end_layers yes)
		(zone_layer_connections "In5.Cu")
		(teardrops
			(best_length_ratio 0.4)
			(max_length 1)
			(best_width_ratio 0.9)
			(max_width 2)
			(curved_edges yes)
			(filter_ratio 0.9)
			(enabled yes)
			(allow_two_segments yes)
			(prefer_zone_connections yes)
		)
		(net 527)
	)
	(via
		(at 129.15 89.990001)
		(size 0.45)
		(drill 0.1)
		(layers "F.Cu" "B.Cu")
		(remove_unused_layers yes)
		(keep_end_layers yes)
		(zone_layer_connections "In5.Cu")
		(teardrops
			(best_length_ratio 0.4)
			(max_length 1)
			(best_width_ratio 0.9)
			(max_width 2)
			(curved_edges yes)
			(filter_ratio 0.9)
			(enabled yes)
			(allow_two_segments yes)
			(prefer_zone_connections yes)
		)
		(net 527)
	)
	(via
		(at 130.4 78.06)
		(size 0.45)
		(drill 0.1)
		(layers "F.Cu" "B.Cu")
		(remove_unused_layers yes)
		(keep_end_layers yes)
		(zone_layer_connections "In5.Cu")
		(teardrops
			(best_length_ratio 0.4)
			(max_length 1)
			(best_width_ratio 0.9)
			(max_width 2)
			(curved_edges yes)
			(filter_ratio 0.9)
			(enabled yes)
			(allow_two_segments yes)
			(prefer_zone_connections yes)
		)
		(net 527)
	)
	(segment
		(start 271.83 122.03)
		(end 279.02 129.22)
		(width 0.125)
		(layer "In5.Cu")
		(net 527)
	)
	(segment
		(start 148.685055 75.672658)
		(end 149.072397 76.06)
		(width 0.125)
		(layer "In5.Cu")
		(net 527)
	)
	(segment
		(start 130.65844 76.01844)
		(end 146.39156 76.01844)
		(width 0.125)
		(layer "In5.Cu")
		(net 527)
	)
	(segment
		(start 129.15 81.76)
		(end 129.15 89.990001)
		(width 0.125)
		(layer "In5.Cu")
		(net 527)
	)
	(segment
		(start 207.7 100.15)
		(end 207.7 112.121092)
		(width 0.125)
		(layer "In5.Cu")
		(net 527)
	)
	(segment
		(start 146.737342 75.672658)
		(end 148.685055 75.672658)
		(width 0.125)
		(layer "In5.Cu")
		(net 527)
	)
	(segment
		(start 149.072397 76.06)
		(end 183.61 76.06)
		(width 0.125)
		(layer "In5.Cu")
		(net 527)
	)
	(segment
		(start 264.67 122.03)
		(end 271.83 122.03)
		(width 0.125)
		(layer "In5.Cu")
		(net 527)
	)
	(segment
		(start 312.68 161.94)
		(end 312.68 164.38)
		(width 0.125)
		(layer "In5.Cu")
		(net 527)
	)
	(segment
		(start 130.4 78.06)
		(end 129.35 79.11)
		(width 0.125)
		(layer "In5.Cu")
		(net 527)
	)
	(segment
		(start 293.3 150.66)
		(end 301.4 150.66)
		(width 0.125)
		(layer "In5.Cu")
		(net 527)
	)
	(segment
		(start 129.35 79.11)
		(end 129.35 81.56)
		(width 0.125)
		(layer "In5.Cu")
		(net 527)
	)
	(segment
		(start 183.61 76.06)
		(end 207.7 100.15)
		(width 0.125)
		(layer "In5.Cu")
		(net 527)
	)
	(segment
		(start 146.39156 76.01844)
		(end 146.737342 75.672658)
		(width 0.125)
		(layer "In5.Cu")
		(net 527)
	)
	(segment
		(start 129.35 81.56)
		(end 129.15 81.76)
		(width 0.125)
		(layer "In5.Cu")
		(net 527)
	)
	(segment
		(start 130.4 75.76)
		(end 130.65844 76.01844)
		(width 0.125)
		(layer "In5.Cu")
		(net 527)
	)
	(segment
		(start 279.02 129.22)
		(end 279.02 136.38)
		(width 0.125)
		(layer "In5.Cu")
		(net 527)
	)
	(segment
		(start 255.55 112.91)
		(end 264.67 122.03)
		(width 0.125)
		(layer "In5.Cu")
		(net 527)
	)
	(segment
		(start 279.02 136.38)
		(end 293.3 150.66)
		(width 0.125)
		(layer "In5.Cu")
		(net 527)
	)
	(segment
		(start 301.4 150.66)
		(end 312.68 161.94)
		(width 0.125)
		(layer "In5.Cu")
		(net 527)
	)
	(segment
		(start 207.7 112.121092)
		(end 208.488908 112.91)
		(width 0.125)
		(layer "In5.Cu")
		(net 527)
	)
	(segment
		(start 208.488908 112.91)
		(end 255.55 112.91)
		(width 0.125)
		(layer "In5.Cu")
		(net 527)
	)
	(segment
		(start 312.68 164.38)
		(end 311.35 165.71)
		(width 0.125)
		(layer "In5.Cu")
		(net 527)
	)
	(segment
		(start 315.135 163.46)
		(end 314.363 163.46)
		(width 0.125)
		(layer "F.Cu")
		(net 528)
	)
	(segment
		(start 308.75 156.71)
		(end 308.756 156.704)
		(width 0.125)
		(layer "F.Cu")
		(net 528)
	)
	(segment
		(start 319.45 164.11)
		(end 317.45 164.11)
		(width 0.125)
		(layer "F.Cu")
		(net 528)
	)
	(segment
		(start 317.45 164.11)
		(end 316.8 163.46)
		(width 0.125)
		(layer "F.Cu")
		(net 528)
	)
	(segment
		(start 291.125 102.86)
		(end 290.33 102.86)
		(width 0.125)
		(layer "F.Cu")
		(net 528)
	)
	(segment
		(start 316.8 163.46)
		(end 315.135 163.46)
		(width 0.125)
		(layer "F.Cu")
		(net 528)
	)
	(segment
		(start 313.75 163.46)
		(end 313.4 163.11)
		(width 0.125)
		(layer "F.Cu")
		(net 528)
	)
	(segment
		(start 314.363 163.46)
		(end 313.75 163.46)
		(width 0.125)
		(layer "F.Cu")
		(net 528)
	)
	(segment
		(start 290.33 103.305)
		(end 290.33 102.86)
		(width 0.125)
		(layer "F.Cu")
		(net 528)
	)
	(segment
		(start 308.756 156.704)
		(end 308.756 155.182)
		(width 0.125)
		(layer "F.Cu")
		(net 528)
	)
	(segment
		(start 282.4 103.185)
		(end 282.75 103.535)
		(width 0.125)
		(layer "F.Cu")
		(net 528)
	)
	(segment
		(start 290.1 103.535)
		(end 290.33 103.305)
		(width 0.125)
		(layer "F.Cu")
		(net 528)
	)
	(segment
		(start 282.75 103.535)
		(end 290.1 103.535)
		(width 0.125)
		(layer "F.Cu")
		(net 528)
	)
	(via
		(at 264.55 93.485)
		(size 0.45)
		(drill 0.1)
		(layers "F.Cu" "B.Cu")
		(remove_unused_layers yes)
		(keep_end_layers yes)
		(zone_layer_connections "In2.Cu")
		(teardrops
			(best_length_ratio 0.4)
			(max_length 1)
			(best_width_ratio 0.9)
			(max_width 2)
			(curved_edges yes)
			(filter_ratio 0.9)
			(enabled yes)
			(allow_two_segments yes)
			(prefer_zone_connections yes)
		)
		(net 528)
	)
	(via
		(at 282.4 103.185)
		(size 0.45)
		(drill 0.1)
		(layers "F.Cu" "B.Cu")
		(remove_unused_layers yes)
		(keep_end_layers yes)
		(zone_layer_connections "In2.Cu")
		(teardrops
			(best_length_ratio 0.4)
			(max_length 1)
			(best_width_ratio 0.9)
			(max_width 2)
			(curved_edges yes)
			(filter_ratio 0.9)
			(enabled yes)
			(allow_two_segments yes)
			(prefer_zone_connections yes)
		)
		(net 528)
	)
	(via
		(at 308.75 156.71)
		(size 0.45)
		(drill 0.1)
		(layers "F.Cu" "B.Cu")
		(remove_unused_layers yes)
		(keep_end_layers yes)
		(zone_layer_connections "In2.Cu" "In5.Cu")
		(teardrops
			(best_length_ratio 0.4)
			(max_length 1)
			(best_width_ratio 0.9)
			(max_width 2)
			(curved_edges yes)
			(filter_ratio 0.9)
			(enabled yes)
			(allow_two_segments yes)
			(prefer_zone_connections yes)
		)
		(net 528)
	)
	(via
		(at 291.125 102.86)
		(size 0.45)
		(drill 0.1)
		(layers "F.Cu" "B.Cu")
		(remove_unused_layers yes)
		(keep_end_layers yes)
		(zone_layer_connections "In2.Cu")
		(teardrops
			(best_length_ratio 0.4)
			(max_length 1)
			(best_width_ratio 0.9)
			(max_width 2)
			(curved_edges yes)
			(filter_ratio 0.9)
			(enabled yes)
			(allow_two_segments yes)
			(prefer_zone_connections yes)
		)
		(net 528)
	)
	(via
		(at 142.97 84.06)
		(size 0.45)
		(drill 0.1)
		(layers "F.Cu" "B.Cu")
		(remove_unused_layers yes)
		(keep_end_layers yes)
		(zone_layer_connections "In2.Cu")
		(teardrops
			(best_length_ratio 0.4)
			(max_length 1)
			(best_width_ratio 0.9)
			(max_width 2)
			(curved_edges yes)
			(filter_ratio 0.9)
			(enabled yes)
			(allow_two_segments yes)
			(prefer_zone_connections yes)
		)
		(net 528)
	)
	(via
		(at 157.55 156.33)
		(size 0.45)
		(drill 0.1)
		(layers "F.Cu" "B.Cu")
		(remove_unused_layers yes)
		(keep_end_layers yes)
		(zone_layer_connections "In2.Cu")
		(teardrops
			(best_length_ratio 0.4)
			(max_length 1)
			(best_width_ratio 0.9)
			(max_width 2)
			(curved_edges yes)
			(filter_ratio 0.9)
			(enabled yes)
			(allow_two_segments yes)
			(prefer_zone_connections yes)
		)
		(net 528)
	)
	(via
		(at 178 107.66)
		(size 0.45)
		(drill 0.1)
		(layers "F.Cu" "B.Cu")
		(remove_unused_layers yes)
		(keep_end_layers yes)
		(zone_layer_connections "In2.Cu")
		(teardrops
			(best_length_ratio 0.4)
			(max_length 1)
			(best_width_ratio 0.9)
			(max_width 2)
			(curved_edges yes)
			(filter_ratio 0.9)
			(enabled yes)
			(allow_two_segments yes)
			(prefer_zone_connections yes)
		)
		(net 528)
	)
	(via
		(at 122.18 163.56)
		(size 0.45)
		(drill 0.1)
		(layers "F.Cu" "B.Cu")
		(remove_unused_layers yes)
		(keep_end_layers yes)
		(zone_layer_connections "In2.Cu")
		(teardrops
			(best_length_ratio 0.4)
			(max_length 1)
			(best_width_ratio 0.9)
			(max_width 2)
			(curved_edges yes)
			(filter_ratio 0.9)
			(enabled yes)
			(allow_two_segments yes)
			(prefer_zone_connections yes)
		)
		(net 528)
	)
	(via
		(at 313.4 163.11)
		(size 0.45)
		(drill 0.1)
		(layers "F.Cu" "B.Cu")
		(remove_unused_layers yes)
		(keep_end_layers yes)
		(zone_layer_connections "In5.Cu")
		(teardrops
			(best_length_ratio 0.4)
			(max_length 1)
			(best_width_ratio 0.9)
			(max_width 2)
			(curved_edges yes)
			(filter_ratio 0.9)
			(enabled yes)
			(allow_two_segments yes)
			(prefer_zone_connections yes)
		)
		(net 528)
	)
	(via
		(at 158.55 152.76)
		(size 0.45)
		(drill 0.1)
		(layers "F.Cu" "B.Cu")
		(remove_unused_layers yes)
		(keep_end_layers yes)
		(zone_layer_connections "In2.Cu" "In5.Cu")
		(teardrops
			(best_length_ratio 0.4)
			(max_length 1)
			(best_width_ratio 0.9)
			(max_width 2)
			(curved_edges yes)
			(filter_ratio 0.9)
			(enabled yes)
			(allow_two_segments yes)
			(prefer_zone_connections yes)
		)
		(net 528)
	)
	(via
		(at 297.2 84.51)
		(size 0.45)
		(drill 0.1)
		(layers "F.Cu" "B.Cu")
		(remove_unused_layers yes)
		(keep_end_layers yes)
		(zone_layer_connections "In2.Cu")
		(teardrops
			(best_length_ratio 0.4)
			(max_length 1)
			(best_width_ratio 0.9)
			(max_width 2)
			(curved_edges yes)
			(filter_ratio 0.9)
			(enabled yes)
			(allow_two_segments yes)
			(prefer_zone_connections yes)
		)
		(net 528)
	)
	(via
		(at 158.55 150.31)
		(size 0.45)
		(drill 0.1)
		(layers "F.Cu" "B.Cu")
		(remove_unused_layers yes)
		(keep_end_layers yes)
		(zone_layer_connections "In2.Cu" "In5.Cu")
		(teardrops
			(best_length_ratio 0.4)
			(max_length 1)
			(best_width_ratio 0.9)
			(max_width 2)
			(curved_edges yes)
			(filter_ratio 0.9)
			(enabled yes)
			(allow_two_segments yes)
			(prefer_zone_connections yes)
		)
		(net 528)
	)
	(via
		(at 127.9 81.280001)
		(size 0.45)
		(drill 0.1)
		(layers "F.Cu" "B.Cu")
		(remove_unused_layers yes)
		(keep_end_layers yes)
		(zone_layer_connections "In2.Cu")
		(teardrops
			(best_length_ratio 0.4)
			(max_length 1)
			(best_width_ratio 0.9)
			(max_width 2)
			(curved_edges yes)
			(filter_ratio 0.9)
			(enabled yes)
			(allow_two_segments yes)
			(prefer_zone_connections yes)
		)
		(net 528)
	)
	(segment
		(start 171.6 106.65)
		(end 172.71 107.76)
		(width 0.125)
		(layer "In2.Cu")
		(net 528)
	)
	(segment
		(start 154 83.51)
		(end 155.44 83.51)
		(width 0.125)
		(layer "In2.Cu")
		(net 528)
	)
	(segment
		(start 142.5 85.45)
		(end 143.7 86.65)
		(width 0.125)
		(layer "In2.Cu")
		(net 528)
	)
	(segment
		(start 139.35 154.31)
		(end 157 154.31)
		(width 0.125)
		(layer "In2.Cu")
		(net 528)
	)
	(segment
		(start 229.420708 79.66)
		(end 230.970708 78.11)
		(width 0.125)
		(layer "In2.Cu")
		(net 528)
	)
	(segment
		(start 128.720001 80.46)
		(end 127.9 81.280001)
		(width 0.125)
		(layer "In2.Cu")
		(net 528)
	)
	(segment
		(start 157 154.31)
		(end 157.55 154.86)
		(width 0.125)
		(layer "In2.Cu")
		(net 528)
	)
	(segment
		(start 174.8 107.76)
		(end 176.55 109.51)
		(width 0.125)
		(layer "In2.Cu")
		(net 528)
	)
	(segment
		(start 142.5 84.53)
		(end 142.5 85.45)
		(width 0.125)
		(layer "In2.Cu")
		(net 528)
	)
	(segment
		(start 143.7 91.06)
		(end 160.7 108.06)
		(width 0.125)
		(layer "In2.Cu")
		(net 528)
	)
	(segment
		(start 274.25 103.185)
		(end 282.4 103.185)
		(width 0.125)
		(layer "In2.Cu")
		(net 528)
	)
	(segment
		(start 240.395708 81.96)
		(end 245.925 81.96)
		(width 0.125)
		(layer "In2.Cu")
		(net 528)
	)
	(segment
		(start 172.71 107.76)
		(end 174.8 107.76)
		(width 0.125)
		(layer "In2.Cu")
		(net 528)
	)
	(segment
		(start 299.2 130.21)
		(end 299.2 149.985)
		(width 0.125)
		(layer "In2.Cu")
		(net 528)
	)
	(segment
		(start 291.125 102.86)
		(end 291.125 122.135)
		(width 0.125)
		(layer "In2.Cu")
		(net 528)
	)
	(segment
		(start 142.97 84.06)
		(end 139.37 80.46)
		(width 0.125)
		(layer "In2.Cu")
		(net 528)
	)
	(segment
		(start 130.1 163.56)
		(end 139.35 154.31)
		(width 0.125)
		(layer "In2.Cu")
		(net 528)
	)
	(segment
		(start 305.925 156.71)
		(end 308.75 156.71)
		(width 0.125)
		(layer "In2.Cu")
		(net 528)
	)
	(segment
		(start 258.965 87.9)
		(end 274.25 103.185)
		(width 0.125)
		(layer "In2.Cu")
		(net 528)
	)
	(segment
		(start 159.45 150.31)
		(end 158.55 150.31)
		(width 0.125)
		(layer "In2.Cu")
		(net 528)
	)
	(segment
		(start 178.65 108.31)
		(end 178 107.66)
		(width 0.125)
		(layer "In2.Cu")
		(net 528)
	)
	(segment
		(start 160.7 149.06)
		(end 159.45 150.31)
		(width 0.125)
		(layer "In2.Cu")
		(net 528)
	)
	(segment
		(start 178.05 109.51)
		(end 178.65 108.91)
		(width 0.125)
		(layer "In2.Cu")
		(net 528)
	)
	(segment
		(start 299.2 149.985)
		(end 305.925 156.71)
		(width 0.125)
		(layer "In2.Cu")
		(net 528)
	)
	(segment
		(start 157 154.31)
		(end 158.55 152.76)
		(width 0.125)
		(layer "In2.Cu")
		(net 528)
	)
	(segment
		(start 178 107.66)
		(end 178 106.9)
		(width 0.125)
		(layer "In2.Cu")
		(net 528)
	)
	(segment
		(start 157.55 154.86)
		(end 157.55 156.33)
		(width 0.125)
		(layer "In2.Cu")
		(net 528)
	)
	(segment
		(start 176.55 109.51)
		(end 178.05 109.51)
		(width 0.125)
		(layer "In2.Cu")
		(net 528)
	)
	(segment
		(start 142.97 84.06)
		(end 142.5 84.53)
		(width 0.125)
		(layer "In2.Cu")
		(net 528)
	)
	(segment
		(start 245.925 81.96)
		(end 251.865 87.9)
		(width 0.125)
		(layer "In2.Cu")
		(net 528)
	)
	(segment
		(start 142.97 84.06)
		(end 153.45 84.06)
		(width 0.125)
		(layer "In2.Cu")
		(net 528)
	)
	(segment
		(start 291.125 122.135)
		(end 299.2 130.21)
		(width 0.125)
		(layer "In2.Cu")
		(net 528)
	)
	(segment
		(start 171.6 99.67)
		(end 171.6 106.65)
		(width 0.125)
		(layer "In2.Cu")
		(net 528)
	)
	(segment
		(start 251.865 87.9)
		(end 258.965 87.9)
		(width 0.125)
		(layer "In2.Cu")
		(net 528)
	)
	(segment
		(start 236.545708 78.11)
		(end 240.395708 81.96)
		(width 0.125)
		(layer "In2.Cu")
		(net 528)
	)
	(segment
		(start 292.55 101.435)
		(end 291.125 102.86)
		(width 0.125)
		(layer "In2.Cu")
		(net 528)
	)
	(segment
		(start 292.55 89.21)
		(end 292.55 101.435)
		(width 0.125)
		(layer "In2.Cu")
		(net 528)
	)
	(segment
		(start 122.18 163.56)
		(end 130.1 163.56)
		(width 0.125)
		(layer "In2.Cu")
		(net 528)
	)
	(segment
		(start 139.37 80.46)
		(end 128.720001 80.46)
		(width 0.125)
		(layer "In2.Cu")
		(net 528)
	)
	(segment
		(start 230.970708 78.11)
		(end 236.545708 78.11)
		(width 0.125)
		(layer "In2.Cu")
		(net 528)
	)
	(segment
		(start 178.65 108.91)
		(end 178.65 108.31)
		(width 0.125)
		(layer "In2.Cu")
		(net 528)
	)
	(segment
		(start 184.75 79.66)
		(end 229.420708 79.66)
		(width 0.125)
		(layer "In2.Cu")
		(net 528)
	)
	(segment
		(start 153.45 84.06)
		(end 154 83.51)
		(width 0.125)
		(layer "In2.Cu")
		(net 528)
	)
	(segment
		(start 176.1 105)
		(end 176.1 88.31)
		(width 0.125)
		(layer "In2.Cu")
		(net 528)
	)
	(segment
		(start 176.1 88.31)
		(end 184.75 79.66)
		(width 0.125)
		(layer "In2.Cu")
		(net 528)
	)
	(segment
		(start 297.2 84.56)
		(end 292.55 89.21)
		(width 0.125)
		(layer "In2.Cu")
		(net 528)
	)
	(segment
		(start 143.7 86.65)
		(end 143.7 91.06)
		(width 0.125)
		(layer "In2.Cu")
		(net 528)
	)
	(segment
		(start 160.7 108.06)
		(end 160.7 149.06)
		(width 0.125)
		(layer "In2.Cu")
		(net 528)
	)
	(segment
		(start 178 106.9)
		(end 176.1 105)
		(width 0.125)
		(layer "In2.Cu")
		(net 528)
	)
	(segment
		(start 297.2 84.51)
		(end 297.2 84.56)
		(width 0.125)
		(layer "In2.Cu")
		(net 528)
	)
	(segment
		(start 155.44 83.51)
		(end 171.6 99.67)
		(width 0.125)
		(layer "In2.Cu")
		(net 528)
	)
	(segment
		(start 158.55 150.31)
		(end 158.55 152.76)
		(width 0.125)
		(layer "In5.Cu")
		(net 528)
	)
	(segment
		(start 313.4 163.11)
		(end 313.4 161.36)
		(width 0.125)
		(layer "In5.Cu")
		(net 528)
	)
	(segment
		(start 313.4 161.36)
		(end 308.75 156.71)
		(width 0.125)
		(layer "In5.Cu")
		(net 528)
	)
	(segment
		(start 179.35 104.81)
		(end 179.35 104.35)
		(width 0.125)
		(layer "F.Cu")
		(net 529)
	)
	(segment
		(start 177.729815 105.85563)
		(end 178.30437 105.85563)
		(width 0.125)
		(layer "F.Cu")
		(net 529)
	)
	(segment
		(start 178.30437 105.85563)
		(end 179.35 104.81)
		(width 0.125)
		(layer "F.Cu")
		(net 529)
	)
	(via
		(at 177.729815 105.85563)
		(size 0.45)
		(drill 0.1)
		(layers "F.Cu" "B.Cu")
		(remove_unused_layers yes)
		(keep_end_layers yes)
		(zone_layer_connections "In2.Cu")
		(teardrops
			(best_length_ratio 0.4)
			(max_length 1)
			(best_width_ratio 0.9)
			(max_width 2)
			(curved_edges yes)
			(filter_ratio 0.9)
			(enabled yes)
			(allow_two_segments yes)
			(prefer_zone_connections yes)
		)
		(net 529)
	)
	(via
		(at 210.8 126.09)
		(size 0.45)
		(drill 0.1)
		(layers "F.Cu" "B.Cu")
		(remove_unused_layers yes)
		(keep_end_layers yes)
		(zone_layer_connections "In2.Cu")
		(teardrops
			(best_length_ratio 0.4)
			(max_length 1)
			(best_width_ratio 0.9)
			(max_width 2)
			(curved_edges yes)
			(filter_ratio 0.9)
			(enabled yes)
			(allow_two_segments yes)
			(prefer_zone_connections yes)
		)
		(net 529)
	)
	(segment
		(start 177.975445 105.61)
		(end 178.84 105.61)
		(width 0.125)
		(layer "B.Cu")
		(net 529)
	)
	(segment
		(start 177.729815 105.85563)
		(end 177.975445 105.61)
		(width 0.125)
		(layer "B.Cu")
		(net 529)
	)
	(segment
		(start 179.33 107.455815)
		(end 179.33 113.69)
		(width 0.125)
		(layer "In2.Cu")
		(net 529)
	)
	(segment
		(start 184.49 118.85)
		(end 201.67 118.85)
		(width 0.125)
		(layer "In2.Cu")
		(net 529)
	)
	(segment
		(start 179.33 113.69)
		(end 184.49 118.85)
		(width 0.125)
		(layer "In2.Cu")
		(net 529)
	)
	(segment
		(start 177.729815 105.85563)
		(end 179.33 107.455815)
		(width 0.125)
		(layer "In2.Cu")
		(net 529)
	)
	(segment
		(start 208.91 126.09)
		(end 210.8 126.09)
		(width 0.125)
		(layer "In2.Cu")
		(net 529)
	)
	(segment
		(start 201.67 118.85)
		(end 208.91 126.09)
		(width 0.125)
		(layer "In2.Cu")
		(net 529)
	)
	(segment
		(start 299.2 83.53)
		(end 298.949 83.279)
		(width 0.125)
		(layer "F.Cu")
		(net 530)
	)
	(segment
		(start 298.949 83.279)
		(end 298.949 81.583)
		(width 0.125)
		(layer "F.Cu")
		(net 530)
	)
	(via
		(at 223.16 128.2)
		(size 0.45)
		(drill 0.1)
		(layers "F.Cu" "B.Cu")
		(remove_unused_layers yes)
		(keep_end_layers yes)
		(zone_layer_connections "In2.Cu")
		(teardrops
			(best_length_ratio 0.4)
			(max_length 1)
			(best_width_ratio 0.9)
			(max_width 2)
			(curved_edges yes)
			(filter_ratio 0.9)
			(enabled yes)
			(allow_two_segments yes)
			(prefer_zone_connections yes)
		)
		(net 530)
	)
	(via
		(at 299.2 83.53)
		(size 0.45)
		(drill 0.1)
		(layers "F.Cu" "B.Cu")
		(remove_unused_layers yes)
		(keep_end_layers yes)
		(zone_layer_connections "In2.Cu")
		(teardrops
			(best_length_ratio 0.4)
			(max_length 1)
			(best_width_ratio 0.9)
			(max_width 2)
			(curved_edges yes)
			(filter_ratio 0.9)
			(enabled yes)
			(allow_two_segments yes)
			(prefer_zone_connections yes)
		)
		(net 530)
	)
	(via
		(at 290.56 88.8)
		(size 0.45)
		(drill 0.1)
		(layers "F.Cu" "B.Cu")
		(remove_unused_layers yes)
		(keep_end_layers yes)
		(zone_layer_connections "In2.Cu" "In5.Cu")
		(teardrops
			(best_length_ratio 0.4)
			(max_length 1)
			(best_width_ratio 0.9)
			(max_width 2)
			(curved_edges yes)
			(filter_ratio 0.9)
			(enabled yes)
			(allow_two_segments yes)
			(prefer_zone_connections yes)
		)
		(net 530)
	)
	(via
		(at 283.25 94.3)
		(size 0.45)
		(drill 0.1)
		(layers "F.Cu" "B.Cu")
		(remove_unused_layers yes)
		(keep_end_layers yes)
		(zone_layer_connections "In2.Cu" "In5.Cu")
		(teardrops
			(best_length_ratio 0.4)
			(max_length 1)
			(best_width_ratio 0.9)
			(max_width 2)
			(curved_edges yes)
			(filter_ratio 0.9)
			(enabled yes)
			(allow_two_segments yes)
			(prefer_zone_connections yes)
		)
		(net 530)
	)
	(segment
		(start 295.83 83.53)
		(end 299.2 83.53)
		(width 0.125)
		(layer "In2.Cu")
		(net 530)
	)
	(segment
		(start 290.56 88.8)
		(end 295.83 83.53)
		(width 0.125)
		(layer "In2.Cu")
		(net 530)
	)
	(segment
		(start 283.25 114.46)
		(end 272.4 125.31)
		(width 0.125)
		(layer "In2.Cu")
		(net 530)
	)
	(segment
		(start 226.05 125.31)
		(end 223.16 128.2)
		(width 0.125)
		(layer "In2.Cu")
		(net 530)
	)
	(segment
		(start 272.4 125.31)
		(end 226.05 125.31)
		(width 0.125)
		(layer "In2.Cu")
		(net 530)
	)
	(segment
		(start 283.25 94.3)
		(end 283.25 114.46)
		(width 0.125)
		(layer "In2.Cu")
		(net 530)
	)
	(segment
		(start 283.25 94.3)
		(end 288.75 88.8)
		(width 0.125)
		(layer "In5.Cu")
		(net 530)
	)
	(segment
		(start 288.75 88.8)
		(end 290.56 88.8)
		(width 0.125)
		(layer "In5.Cu")
		(net 530)
	)
	(segment
		(start 111.763 131.41)
		(end 112.535 131.41)
		(width 0.2)
		(layer "F.Cu")
		(net 531)
	)
	(segment
		(start 114.46 131.41)
		(end 112.535 131.41)
		(width 0.2)
		(layer "F.Cu")
		(net 531)
	)
	(segment
		(start 113.5 139.36)
		(end 113.5 139.66)
		(width 0.125)
		(layer "F.Cu")
		(net 531)
	)
	(segment
		(start 111.46 131.41)
		(end 111.763 131.41)
		(width 0.2)
		(layer "F.Cu")
		(net 531)
	)
	(segment
		(start 114.01 139.36)
		(end 115.1 138.27)
		(width 0.2)
		(layer "F.Cu")
		(net 531)
	)
	(segment
		(start 115.1 132.05)
		(end 114.46 131.41)
		(width 0.2)
		(layer "F.Cu")
		(net 531)
	)
	(segment
		(start 115.1 138.27)
		(end 115.1 132.05)
		(width 0.2)
		(layer "F.Cu")
		(net 531)
	)
	(segment
		(start 113.5 139.36)
		(end 114.01 139.36)
		(width 0.2)
		(layer "F.Cu")
		(net 531)
	)
	(segment
		(start 110.96 130.91)
		(end 111.46 131.41)
		(width 0.2)
		(layer "F.Cu")
		(net 531)
	)
	(segment
		(start 109.505 130.21)
		(end 110.55 130.21)
		(width 0.2)
		(layer "F.Cu")
		(net 531)
	)
	(segment
		(start 113.2 139.96)
		(end 112.58 139.96)
		(width 0.125)
		(layer "F.Cu")
		(net 531)
	)
	(segment
		(start 113.5 139.66)
		(end 113.2 139.96)
		(width 0.125)
		(layer "F.Cu")
		(net 531)
	)
	(segment
		(start 207.025 164.175)
		(end 207.025 163.135)
		(width 0.125)
		(layer "F.Cu")
		(net 531)
	)
	(segment
		(start 110.55 130.21)
		(end 110.96 130.62)
		(width 0.2)
		(layer "F.Cu")
		(net 531)
	)
	(segment
		(start 110.96 130.62)
		(end 110.96 130.91)
		(width 0.2)
		(layer "F.Cu")
		(net 531)
	)
	(via
		(at 145.25 148.85)
		(size 0.45)
		(drill 0.1)
		(layers "F.Cu" "B.Cu")
		(teardrops
			(best_length_ratio 0.4)
			(max_length 1)
			(best_width_ratio 0.9)
			(max_width 2)
			(curved_edges yes)
			(filter_ratio 0.9)
			(enabled yes)
			(allow_two_segments yes)
			(prefer_zone_connections yes)
		)
		(net 531)
	)
	(via
		(at 166.55 157.7)
		(size 0.45)
		(drill 0.1)
		(layers "F.Cu" "B.Cu")
		(teardrops
			(best_length_ratio 0.4)
			(max_length 1)
			(best_width_ratio 0.9)
			(max_width 2)
			(curved_edges yes)
			(filter_ratio 0.9)
			(enabled yes)
			(allow_two_segments yes)
			(prefer_zone_connections yes)
		)
		(net 531)
	)
	(via
		(at 113.5 139.36)
		(size 0.45)
		(drill 0.1)
		(layers "F.Cu" "B.Cu")
		(remove_unused_layers yes)
		(keep_end_layers yes)
		(zone_layer_connections "In5.Cu")
		(teardrops
			(best_length_ratio 0.4)
			(max_length 1)
			(best_width_ratio 0.9)
			(max_width 2)
			(curved_edges yes)
			(filter_ratio 0.9)
			(enabled yes)
			(allow_two_segments yes)
			(prefer_zone_connections yes)
		)
		(net 531)
	)
	(via
		(at 138.35 152)
		(size 0.45)
		(drill 0.1)
		(layers "F.Cu" "B.Cu")
		(teardrops
			(best_length_ratio 0.4)
			(max_length 1)
			(best_width_ratio 0.9)
			(max_width 2)
			(curved_edges yes)
			(filter_ratio 0.9)
			(enabled yes)
			(allow_two_segments yes)
			(prefer_zone_connections yes)
		)
		(net 531)
	)
	(via
		(at 207.025 164.175)
		(size 0.45)
		(drill 0.1)
		(layers "F.Cu" "B.Cu")
		(teardrops
			(best_length_ratio 0.4)
			(max_length 1)
			(best_width_ratio 0.9)
			(max_width 2)
			(curved_edges yes)
			(filter_ratio 0.9)
			(enabled yes)
			(allow_two_segments yes)
			(prefer_zone_connections yes)
		)
		(net 531)
	)
	(segment
		(start 142.3 152)
		(end 144.55 149.75)
		(width 0.125)
		(layer "B.Cu")
		(net 531)
	)
	(segment
		(start 144.55 149.2)
		(end 144.55 149.75)
		(width 0.125)
		(layer "B.Cu")
		(net 531)
	)
	(segment
		(start 144.9 148.85)
		(end 144.55 149.2)
		(width 0.125)
		(layer "B.Cu")
		(net 531)
	)
	(segment
		(start 145.25 148.85)
		(end 144.9 148.85)
		(width 0.125)
		(layer "B.Cu")
		(net 531)
	)
	(segment
		(start 142.3 152)
		(end 138.35 152)
		(width 0.125)
		(layer "B.Cu")
		(net 531)
	)
	(segment
		(start 199.55 158.95)
		(end 197.8 157.2)
		(width 0.125)
		(layer "In2.Cu")
		(net 531)
	)
	(segment
		(start 187.1 159)
		(end 189.25 159)
		(width 0.125)
		(layer "In2.Cu")
		(net 531)
	)
	(segment
		(start 186.85 159.25)
		(end 184.2 159.25)
		(width 0.125)
		(layer "In2.Cu")
		(net 531)
	)
	(segment
		(start 189.25 159)
		(end 191.05 157.2)
		(width 0.125)
		(layer "In2.Cu")
		(net 531)
	)
	(segment
		(start 183.65 158.7)
		(end 183.65 158.15)
		(width 0.125)
		(layer "In2.Cu")
		(net 531)
	)
	(segment
		(start 166.8 157.45)
		(end 166.55 157.7)
		(width 0.125)
		(layer "In2.Cu")
		(net 531)
	)
	(segment
		(start 184.2 159.25)
		(end 183.65 158.7)
		(width 0.125)
		(layer "In2.Cu")
		(net 531)
	)
	(segment
		(start 197.8 157.2)
		(end 191.05 157.2)
		(width 0.125)
		(layer "In2.Cu")
		(net 531)
	)
	(segment
		(start 182.95 157.45)
		(end 166.8 157.45)
		(width 0.125)
		(layer "In2.Cu")
		(net 531)
	)
	(segment
		(start 203.4 161.2)
		(end 201.15 158.95)
		(width 0.125)
		(layer "In2.Cu")
		(net 531)
	)
	(segment
		(start 183.65 158.15)
		(end 182.95 157.45)
		(width 0.125)
		(layer "In2.Cu")
		(net 531)
	)
	(segment
		(start 201.15 158.95)
		(end 199.55 158.95)
		(width 0.125)
		(layer "In2.Cu")
		(net 531)
	)
	(segment
		(start 205.3 162.45)
		(end 203.85 162.45)
		(width 0.125)
		(layer "In2.Cu")
		(net 531)
	)
	(segment
		(start 207.025 164.175)
		(end 205.3 162.45)
		(width 0.125)
		(layer "In2.Cu")
		(net 531)
	)
	(segment
		(start 203.85 162.45)
		(end 203.4 162)
		(width 0.125)
		(layer "In2.Cu")
		(net 531)
	)
	(segment
		(start 203.4 162)
		(end 203.4 161.2)
		(width 0.125)
		(layer "In2.Cu")
		(net 531)
	)
	(segment
		(start 187.1 159)
		(end 186.85 159.25)
		(width 0.125)
		(layer "In2.Cu")
		(net 531)
	)
	(segment
		(start 121.35 150.25)
		(end 118.95 147.85)
		(width 0.125)
		(layer "In5.Cu")
		(net 531)
	)
	(segment
		(start 164.625 158.325)
		(end 165.925 158.325)
		(width 0.125)
		(layer "In5.Cu")
		(net 531)
	)
	(segment
		(start 157.75 150.8)
		(end 157.75 154.183364)
		(width 0.125)
		(layer "In5.Cu")
		(net 531)
	)
	(segment
		(start 118.7 147.85)
		(end 118.15 147.3)
		(width 0.125)
		(layer "In5.Cu")
		(net 531)
	)
	(segment
		(start 118.055 147.3)
		(end 116.95 146.195)
		(width 0.125)
		(layer "In5.Cu")
		(net 531)
	)
	(segment
		(start 161.95 156.1)
		(end 161.95 156.85)
		(width 0.125)
		(layer "In5.Cu")
		(net 531)
	)
	(segment
		(start 155.8 148.85)
		(end 157.75 150.8)
		(width 0.125)
		(layer "In5.Cu")
		(net 531)
	)
	(segment
		(start 118.95 147.85)
		(end 118.7 147.85)
		(width 0.125)
		(layer "In5.Cu")
		(net 531)
	)
	(segment
		(start 118.15 147.3)
		(end 118.055 147.3)
		(width 0.125)
		(layer "In5.Cu")
		(net 531)
	)
	(segment
		(start 164.55 158.4)
		(end 164.625 158.325)
		(width 0.125)
		(layer "In5.Cu")
		(net 531)
	)
	(segment
		(start 157.75 154.183364)
		(end 159.066636 155.5)
		(width 0.125)
		(layer "In5.Cu")
		(net 531)
	)
	(segment
		(start 116.95 142.81)
		(end 113.5 139.36)
		(width 0.125)
		(layer "In5.Cu")
		(net 531)
	)
	(segment
		(start 116.95 146.195)
		(end 116.95 142.81)
		(width 0.125)
		(layer "In5.Cu")
		(net 531)
	)
	(segment
		(start 161.95 156.85)
		(end 163.5 158.4)
		(width 0.125)
		(layer "In5.Cu")
		(net 531)
	)
	(segment
		(start 161.35 155.5)
		(end 161.95 156.1)
		(width 0.125)
		(layer "In5.Cu")
		(net 531)
	)
	(segment
		(start 136.6 150.25)
		(end 121.35 150.25)
		(width 0.125)
		(layer "In5.Cu")
		(net 531)
	)
	(segment
		(start 145.25 148.85)
		(end 155.8 148.85)
		(width 0.125)
		(layer "In5.Cu")
		(net 531)
	)
	(segment
		(start 165.925 158.325)
		(end 166.55 157.7)
		(width 0.125)
		(layer "In5.Cu")
		(net 531)
	)
	(segment
		(start 159.066636 155.5)
		(end 161.35 155.5)
		(width 0.125)
		(layer "In5.Cu")
		(net 531)
	)
	(segment
		(start 163.5 158.4)
		(end 164.55 158.4)
		(width 0.125)
		(layer "In5.Cu")
		(net 531)
	)
	(segment
		(start 138.35 152)
		(end 136.6 150.25)
		(width 0.125)
		(layer "In5.Cu")
		(net 531)
	)
	(segment
		(start 201.525 156.685)
		(end 201.525 155.96)
		(width 0.202)
		(layer "F.Cu")
		(net 532)
	)
	(segment
		(start 220.276 153.1555)
		(end 220.4 153.0315)
		(width 0.202)
		(layer "F.Cu")
		(net 532)
	)
	(segment
		(start 201.5805 154.544434)
		(end 202.969434 153.1555)
		(width 0.202)
		(layer "F.Cu")
		(net 532)
	)
	(segment
		(start 315.3425 159.9675)
		(end 315.351749 159.9675)
		(width 0.202)
		(layer "F.Cu")
		(net 532)
	)
	(segment
		(start 318.0195 159.5155)
		(end 318.225 159.31)
		(width 0.202)
		(layer "F.Cu")
		(net 532)
	)
	(segment
		(start 202.969434 153.1555)
		(end 220.276 153.1555)
		(width 0.202)
		(layer "F.Cu")
		(net 532)
	)
	(segment
		(start 315.287 159.912)
		(end 315.3425 159.9675)
		(width 0.202)
		(layer "F.Cu")
		(net 532)
	)
	(segment
		(start 270.924 158.0055)
		(end 270.8 157.8815)
		(width 0.202)
		(layer "F.Cu")
		(net 532)
	)
	(segment
		(start 277.830566 158.0055)
		(end 270.924 158.0055)
		(width 0.202)
		(layer "F.Cu")
		(net 532)
	)
	(segment
		(start 315.135 159.91)
		(end 314.363 159.91)
		(width 0.202)
		(layer "F.Cu")
		(net 532)
	)
	(segment
		(start 315.634592 159.850342)
		(end 315.742903 159.742031)
		(width 0.202)
		(layer "F.Cu")
		(net 532)
	)
	(segment
		(start 299.669434 161.3555)
		(end 281.180566 161.3555)
		(width 0.202)
		(layer "F.Cu")
		(net 532)
	)
	(segment
		(start 281.180566 161.3555)
		(end 277.830566 158.0055)
		(width 0.202)
		(layer "F.Cu")
		(net 532)
	)
	(segment
		(start 301.059434 159.9655)
		(end 299.669434 161.3555)
		(width 0.202)
		(layer "F.Cu")
		(net 532)
	)
	(segment
		(start 201.5805 155.9045)
		(end 201.5805 154.544434)
		(width 0.202)
		(layer "F.Cu")
		(net 532)
	)
	(segment
		(start 314.3075 159.9655)
		(end 301.059434 159.9655)
		(width 0.202)
		(layer "F.Cu")
		(net 532)
	)
	(segment
		(start 316.289799 159.5155)
		(end 318.0195 159.5155)
		(width 0.202)
		(layer "F.Cu")
		(net 532)
	)
	(segment
		(start 314.363 159.91)
		(end 314.3075 159.9655)
		(width 0.202)
		(layer "F.Cu")
		(net 532)
	)
	(segment
		(start 201.525 155.96)
		(end 201.5805 155.9045)
		(width 0.202)
		(layer "F.Cu")
		(net 532)
	)
	(via
		(at 270.8 157.8815)
		(size 0.45)
		(drill 0.1)
		(layers "F.Cu" "B.Cu")
		(teardrops
			(best_length_ratio 0.4)
			(max_length 1)
			(best_width_ratio 0.9)
			(max_width 2)
			(curved_edges yes)
			(filter_ratio 0.9)
			(enabled yes)
			(allow_two_segments yes)
			(prefer_zone_connections yes)
		)
		(net 532)
	)
	(via
		(at 220.4 153.0315)
		(size 0.45)
		(drill 0.1)
		(layers "F.Cu" "B.Cu")
		(teardrops
			(best_length_ratio 0.4)
			(max_length 1)
			(best_width_ratio 0.9)
			(max_width 2)
			(curved_edges yes)
			(filter_ratio 0.9)
			(enabled yes)
			(allow_two_segments yes)
			(prefer_zone_connections yes)
		)
		(net 532)
	)
	(arc
		(start 315.351749 159.9675)
		(mid 315.504823 159.937052)
		(end 315.634592 159.850342)
		(width 0.202)
		(layer "F.Cu")
		(net 532)
	)
	(arc
		(start 315.742903 159.742031)
		(mid 315.993821 159.574373)
		(end 316.289799 159.5155)
		(width 0.202)
		(layer "F.Cu")
		(net 532)
	)
	(segment
		(start 220.4 153.0315)
		(end 220.524 153.1555)
		(width 0.202)
		(layer "B.Cu")
		(net 532)
	)
	(segment
		(start 257.369434 159.9055)
		(end 259.269434 158.0055)
		(width 0.202)
		(layer "B.Cu")
		(net 532)
	)
	(segment
		(start 226.930566 153.1555)
		(end 235.580566 161.8055)
		(width 0.202)
		(layer "B.Cu")
		(net 532)
	)
	(segment
		(start 259.269434 158.0055)
		(end 270.676 158.0055)
		(width 0.202)
		(layer "B.Cu")
		(net 532)
	)
	(segment
		(start 251.519434 161.8055)
		(end 253.419434 159.9055)
		(width 0.202)
		(layer "B.Cu")
		(net 532)
	)
	(segment
		(start 235.580566 161.8055)
		(end 251.519434 161.8055)
		(width 0.202)
		(layer "B.Cu")
		(net 532)
	)
	(segment
		(start 270.676 158.0055)
		(end 270.8 157.8815)
		(width 0.202)
		(layer "B.Cu")
		(net 532)
	)
	(segment
		(start 253.419434 159.9055)
		(end 257.369434 159.9055)
		(width 0.202)
		(layer "B.Cu")
		(net 532)
	)
	(segment
		(start 220.524 153.1555)
		(end 226.930566 153.1555)
		(width 0.202)
		(layer "B.Cu")
		(net 532)
	)
	(segment
		(start 291.9 139.01)
		(end 300.85 139.01)
		(width 0.125)
		(layer "F.Cu")
		(net 533)
	)
	(segment
		(start 257.1 134.31)
		(end 258.1245 133.2855)
		(width 0.125)
		(layer "F.Cu")
		(net 533)
	)
	(segment
		(start 243.8 134.31)
		(end 244.65 134.31)
		(width 0.125)
		(layer "F.Cu")
		(net 533)
	)
	(segment
		(start 302.575 137.805)
		(end 303.871 137.805)
		(width 0.2)
		(layer "F.Cu")
		(net 533)
	)
	(segment
		(start 244.65 134.31)
		(end 257.1 134.31)
		(width 0.125)
		(layer "F.Cu")
		(net 533)
	)
	(segment
		(start 300.85 139.01)
		(end 302.055 137.805)
		(width 0.125)
		(layer "F.Cu")
		(net 533)
	)
	(segment
		(start 243.8 132.834)
		(end 243.8 134.31)
		(width 0.125)
		(layer "F.Cu")
		(net 533)
	)
	(segment
		(start 240.8 133.64)
		(end 240.8 132.84)
		(width 0.125)
		(layer "F.Cu")
		(net 533)
	)
	(segment
		(start 241.47 134.31)
		(end 240.8 133.64)
		(width 0.125)
		(layer "F.Cu")
		(net 533)
	)
	(segment
		(start 258.1245 133.2855)
		(end 258.1245 130.41)
		(width 0.125)
		(layer "F.Cu")
		(net 533)
	)
	(segment
		(start 302.055 137.805)
		(end 302.575 137.805)
		(width 0.125)
		(layer "F.Cu")
		(net 533)
	)
	(segment
		(start 244.65 134.31)
		(end 241.47 134.31)
		(width 0.125)
		(layer "F.Cu")
		(net 533)
	)
	(via
		(at 303.875 137.809)
		(size 0.45)
		(drill 0.1)
		(layers "F.Cu" "B.Cu")
		(remove_unused_layers yes)
		(keep_end_layers yes)
		(zone_layer_connections)
		(teardrops
			(best_length_ratio 0.4)
			(max_length 1)
			(best_width_ratio 0.9)
			(max_width 2)
			(curved_edges yes)
			(filter_ratio 0.9)
			(enabled yes)
			(allow_two_segments yes)
			(prefer_zone_connections yes)
		)
		(net 533)
	)
	(via
		(at 258.1 130.41)
		(size 0.45)
		(drill 0.1)
		(layers "F.Cu" "B.Cu")
		(remove_unused_layers yes)
		(keep_end_layers yes)
		(zone_layer_connections "In2.Cu")
		(teardrops
			(best_length_ratio 0.4)
			(max_length 1)
			(best_width_ratio 0.9)
			(max_width 2)
			(curved_edges yes)
			(filter_ratio 0.9)
			(enabled yes)
			(allow_two_segments yes)
			(prefer_zone_connections yes)
		)
		(net 533)
	)
	(via
		(at 291.9 139.01)
		(size 0.45)
		(drill 0.1)
		(layers "F.Cu" "B.Cu")
		(remove_unused_layers yes)
		(keep_end_layers yes)
		(zone_layer_connections "In2.Cu")
		(teardrops
			(best_length_ratio 0.4)
			(max_length 1)
			(best_width_ratio 0.9)
			(max_width 2)
			(curved_edges yes)
			(filter_ratio 0.9)
			(enabled yes)
			(allow_two_segments yes)
			(prefer_zone_connections yes)
		)
		(net 533)
	)
	(segment
		(start 306.5245 108.4845)
		(end 306.5245 102.86)
		(width 0.125)
		(layer "B.Cu")
		(net 533)
	)
	(segment
		(start 303.875 137.809)
		(end 304.821 137.809)
		(width 0.125)
		(layer "B.Cu")
		(net 533)
	)
	(segment
		(start 313.26 115.22)
		(end 306.5245 108.4845)
		(width 0.125)
		(layer "B.Cu")
		(net 533)
	)
	(segment
		(start 304.821 137.809)
		(end 313.26 129.37)
		(width 0.125)
		(layer "B.Cu")
		(net 533)
	)
	(segment
		(start 313.26 129.37)
		(end 313.26 115.22)
		(width 0.125)
		(layer "B.Cu")
		(net 533)
	)
	(segment
		(start 291.9 139.01)
		(end 283.3 130.41)
		(width 0.125)
		(layer "In2.Cu")
		(net 533)
	)
	(segment
		(start 283.3 130.41)
		(end 258.1 130.41)
		(width 0.125)
		(layer "In2.Cu")
		(net 533)
	)
	(segment
		(start 306.075 138.7595)
		(end 307.0495 138.7595)
		(width 0.2)
		(layer "F.Cu")
		(net 534)
	)
	(segment
		(start 307.0495 138.7595)
		(end 307.57 139.28)
		(width 0.2)
		(layer "F.Cu")
		(net 534)
	)
	(segment
		(start 307.57 139.96)
		(end 307.57 141.288)
		(width 0.2)
		(layer "F.Cu")
		(net 534)
	)
	(segment
		(start 307.57 139.28)
		(end 307.57 139.96)
		(width 0.2)
		(layer "F.Cu")
		(net 534)
	)
	(segment
		(start 289.3995 97.5605)
		(end 290.23 96.73)
		(width 0.2)
		(layer "F.Cu")
		(net 536)
	)
	(segment
		(start 292.02 96.73)
		(end 292.112 96.822)
		(width 0.2)
		(layer "F.Cu")
		(net 536)
	)
	(segment
		(start 290.23 96.73)
		(end 292.02 96.73)
		(width 0.2)
		(layer "F.Cu")
		(net 536)
	)
	(segment
		(start 292.112 96.822)
		(end 292.112 97.574)
		(width 0.2)
		(layer "F.Cu")
		(net 536)
	)
	(segment
		(start 289.3995 98.31)
		(end 289.3995 97.5605)
		(width 0.2)
		(layer "F.Cu")
		(net 536)
	)
	(segment
		(start 292.02 96.16)
		(end 292.02 96.73)
		(width 0.2)
		(layer "F.Cu")
		(net 536)
	)
	(segment
		(start 315.898875 160.136191)
		(end 316.013409 160.021657)
		(width 0.202)
		(layer "F.Cu")
		(net 537)
	)
	(segment
		(start 202.025 156.685)
		(end 202.025 155.96)
		(width 0.202)
		(layer "F.Cu")
		(net 537)
	)
	(segment
		(start 220.276 153.5445)
		(end 220.4 153.6685)
		(width 0.202)
		(layer "F.Cu")
		(net 537)
	)
	(segment
		(start 203.130566 153.5445)
		(end 204.117398 153.5445)
		(width 0.202)
		(layer "F.Cu")
		(net 537)
	)
	(segment
		(start 318.0195 159.9045)
		(end 318.225 160.11)
		(width 0.202)
		(layer "F.Cu")
		(net 537)
	)
	(segment
		(start 205.864881 153.5445)
		(end 220.276 153.5445)
		(width 0.202)
		(layer "F.Cu")
		(net 537)
	)
	(segment
		(start 202.025 155.96)
		(end 201.9695 155.9045)
		(width 0.202)
		(layer "F.Cu")
		(net 537)
	)
	(segment
		(start 204.317398 153.7445)
		(end 204.317398 153.838446)
		(width 0.202)
		(layer "F.Cu")
		(net 537)
	)
	(segment
		(start 314.3075 160.3545)
		(end 301.220566 160.3545)
		(width 0.202)
		(layer "F.Cu")
		(net 537)
	)
	(segment
		(start 315.135 160.41)
		(end 314.363 160.41)
		(width 0.202)
		(layer "F.Cu")
		(net 537)
	)
	(segment
		(start 204.817398 153.838446)
		(end 204.817398 153.7445)
		(width 0.202)
		(layer "F.Cu")
		(net 537)
	)
	(segment
		(start 314.363 160.41)
		(end 314.3075 160.3545)
		(width 0.202)
		(layer "F.Cu")
		(net 537)
	)
	(segment
		(start 315.287 160.412)
		(end 315.3425 160.3565)
		(width 0.202)
		(layer "F.Cu")
		(net 537)
	)
	(segment
		(start 201.9695 154.705566)
		(end 203.130566 153.5445)
		(width 0.202)
		(layer "F.Cu")
		(net 537)
	)
	(segment
		(start 301.220566 160.3545)
		(end 299.830566 161.7445)
		(width 0.202)
		(layer "F.Cu")
		(net 537)
	)
	(segment
		(start 299.830566 161.7445)
		(end 281.019434 161.7445)
		(width 0.202)
		(layer "F.Cu")
		(net 537)
	)
	(segment
		(start 315.3425 160.3565)
		(end 315.367003 160.3565)
		(width 0.202)
		(layer "F.Cu")
		(net 537)
	)
	(segment
		(start 270.924 158.3945)
		(end 270.8 158.5185)
		(width 0.202)
		(layer "F.Cu")
		(net 537)
	)
	(segment
		(start 281.019434 161.7445)
		(end 277.669434 158.3945)
		(width 0.202)
		(layer "F.Cu")
		(net 537)
	)
	(segment
		(start 204.517398 154.038446)
		(end 204.617398 154.038446)
		(width 0.202)
		(layer "F.Cu")
		(net 537)
	)
	(segment
		(start 205.117398 153.5445)
		(end 205.864881 153.5445)
		(width 0.202)
		(layer "F.Cu")
		(net 537)
	)
	(segment
		(start 316.296251 159.9045)
		(end 318.0195 159.9045)
		(width 0.202)
		(layer "F.Cu")
		(net 537)
	)
	(segment
		(start 201.9695 155.9045)
		(end 201.9695 154.705566)
		(width 0.202)
		(layer "F.Cu")
		(net 537)
	)
	(segment
		(start 205.017398 153.5445)
		(end 205.117398 153.5445)
		(width 0.202)
		(layer "F.Cu")
		(net 537)
	)
	(segment
		(start 277.669434 158.3945)
		(end 270.924 158.3945)
		(width 0.202)
		(layer "F.Cu")
		(net 537)
	)
	(via
		(at 270.8 158.5185)
		(size 0.45)
		(drill 0.1)
		(layers "F.Cu" "B.Cu")
		(teardrops
			(best_length_ratio 0.4)
			(max_length 1)
			(best_width_ratio 0.9)
			(max_width 2)
			(curved_edges yes)
			(filter_ratio 0.9)
			(enabled yes)
			(allow_two_segments yes)
			(prefer_zone_connections yes)
		)
		(net 537)
	)
	(via
		(at 220.4 153.6685)
		(size 0.45)
		(drill 0.1)
		(layers "F.Cu" "B.Cu")
		(teardrops
			(best_length_ratio 0.4)
			(max_length 1)
			(best_width_ratio 0.9)
			(max_width 2)
			(curved_edges yes)
			(filter_ratio 0.9)
			(enabled yes)
			(allow_two_segments yes)
			(prefer_zone_connections yes)
		)
		(net 537)
	)
	(arc
		(start 204.617398 154.038446)
		(mid 204.758819 153.979867)
		(end 204.817398 153.838446)
		(width 0.202)
		(layer "F.Cu")
		(net 537)
	)
	(arc
		(start 315.898875 160.136191)
		(mid 315.65485 160.299243)
		(end 315.367003 160.3565)
		(width 0.202)
		(layer "F.Cu")
		(net 537)
	)
	(arc
		(start 204.817398 153.7445)
		(mid 204.875977 153.603079)
		(end 205.017398 153.5445)
		(width 0.202)
		(layer "F.Cu")
		(net 537)
	)
	(arc
		(start 204.117398 153.5445)
		(mid 204.258819 153.603079)
		(end 204.317398 153.7445)
		(width 0.202)
		(layer "F.Cu")
		(net 537)
	)
	(arc
		(start 204.317398 153.838446)
		(mid 204.375977 153.979867)
		(end 204.517398 154.038446)
		(width 0.202)
		(layer "F.Cu")
		(net 537)
	)
	(arc
		(start 316.013409 160.021657)
		(mid 316.143178 159.934948)
		(end 316.296251 159.9045)
		(width 0.202)
		(layer "F.Cu")
		(net 537)
	)
	(segment
		(start 270.676 158.3945)
		(end 270.8 158.5185)
		(width 0.202)
		(layer "B.Cu")
		(net 537)
	)
	(segment
		(start 220.524 153.5445)
		(end 226.769434 153.5445)
		(width 0.202)
		(layer "B.Cu")
		(net 537)
	)
	(segment
		(start 226.769434 153.5445)
		(end 235.419434 162.1945)
		(width 0.202)
		(layer "B.Cu")
		(net 537)
	)
	(segment
		(start 251.680566 162.1945)
		(end 253.580566 160.2945)
		(width 0.202)
		(layer "B.Cu")
		(net 537)
	)
	(segment
		(start 257.530566 160.2945)
		(end 259.430566 158.3945)
		(width 0.202)
		(layer "B.Cu")
		(net 537)
	)
	(segment
		(start 220.4 153.6685)
		(end 220.524 153.5445)
		(width 0.202)
		(layer "B.Cu")
		(net 537)
	)
	(segment
		(start 259.430566 158.3945)
		(end 270.676 158.3945)
		(width 0.202)
		(layer "B.Cu")
		(net 537)
	)
	(segment
		(start 235.419434 162.1945)
		(end 251.680566 162.1945)
		(width 0.202)
		(layer "B.Cu")
		(net 537)
	)
	(segment
		(start 253.580566 160.2945)
		(end 257.530566 160.2945)
		(width 0.202)
		(layer "B.Cu")
		(net 537)
	)
	(segment
		(start 260.698 93.735)
		(end 260.697999 93.337)
		(width 0.125)
		(layer "F.Cu")
		(net 538)
	)
	(segment
		(start 260.87 93.907)
		(end 260.698 93.735)
		(width 0.125)
		(layer "F.Cu")
		(net 538)
	)
	(segment
		(start 261.04 95.22)
		(end 264.18 95.22)
		(width 0.125)
		(layer "F.Cu")
		(net 538)
	)
	(segment
		(start 260.87 94.337)
		(end 260.87 93.907)
		(width 0.125)
		(layer "F.Cu")
		(net 538)
	)
	(segment
		(start 265.4995 93.9005)
		(end 265.4995 91.31)
		(width 0.125)
		(layer "F.Cu")
		(net 538)
	)
	(segment
		(start 264.18 95.22)
		(end 265.4995 93.9005)
		(width 0.125)
		(layer "F.Cu")
		(net 538)
	)
	(segment
		(start 260.87 94.337)
		(end 260.87 95.05)
		(width 0.125)
		(layer "F.Cu")
		(net 538)
	)
	(segment
		(start 260.87 95.05)
		(end 261.04 95.22)
		(width 0.125)
		(layer "F.Cu")
		(net 538)
	)
	(segment
		(start 99.1 71.86)
		(end 100.75 71.86)
		(width 0.125)
		(layer "B.Cu")
		(net 539)
	)
	(segment
		(start 100.75 71.86)
		(end 101.0505 71.5595)
		(width 0.125)
		(layer "B.Cu")
		(net 539)
	)
	(segment
		(start 98.701 72.259)
		(end 99.1 71.86)
		(width 0.125)
		(layer "B.Cu")
		(net 539)
	)
	(segment
		(start 98.701 74.691)
		(end 98.701 72.96)
		(width 0.125)
		(layer "B.Cu")
		(net 539)
	)
	(segment
		(start 101.0505 71.5595)
		(end 101.0505 70.81)
		(width 0.125)
		(layer "B.Cu")
		(net 539)
	)
	(segment
		(start 98.701 72.96)
		(end 98.701 72.259)
		(width 0.125)
		(layer "B.Cu")
		(net 539)
	)
	(segment
		(start 98.25 75.81)
		(end 98.82 75.81)
		(width 0.125)
		(layer "B.Cu")
		(net 540)
	)
	(segment
		(start 97.7505 75.3105)
		(end 98.25 75.81)
		(width 0.125)
		(layer "B.Cu")
		(net 540)
	)
	(segment
		(start 97.7505 70.76)
		(end 97.7505 75.3105)
		(width 0.125)
		(layer "B.Cu")
		(net 540)
	)
	(segment
		(start 121.799 142.811)
		(end 120.55 142.811)
		(width 0.2)
		(layer "F.Cu")
		(net 541)
	)
	(segment
		(start 119.3905 141.8605)
		(end 120.341 142.811)
		(width 0.2)
		(layer "F.Cu")
		(net 541)
	)
	(segment
		(start 256.25 84.46)
		(end 256.249999 84.459999)
		(width 0.125)
		(layer "F.Cu")
		(net 541)
	)
	(segment
		(start 120.341 142.811)
		(end 120.55 142.811)
		(width 0.2)
		(layer "F.Cu")
		(net 541)
	)
	(segment
		(start 256.249999 84.459999)
		(end 254.7 84.459999)
		(width 0.125)
		(layer "F.Cu")
		(net 541)
	)
	(segment
		(start 121.8 142.81)
		(end 121.799 142.811)
		(width 0.2)
		(layer "F.Cu")
		(net 541)
	)
	(segment
		(start 118.35 141.8605)
		(end 119.3905 141.8605)
		(width 0.2)
		(layer "F.Cu")
		(net 541)
	)
	(via
		(at 256.25 84.46)
		(size 0.45)
		(drill 0.1)
		(layers "F.Cu" "B.Cu")
		(remove_unused_layers yes)
		(keep_end_layers yes)
		(zone_layer_connections "In2.Cu")
		(teardrops
			(best_length_ratio 0.4)
			(max_length 1)
			(best_width_ratio 0.9)
			(max_width 2)
			(curved_edges yes)
			(filter_ratio 0.9)
			(enabled yes)
			(allow_two_segments yes)
			(prefer_zone_connections yes)
		)
		(net 541)
	)
	(via
		(at 121.8 142.81)
		(size 0.45)
		(drill 0.1)
		(layers "F.Cu" "B.Cu")
		(remove_unused_layers yes)
		(keep_end_layers yes)
		(zone_layer_connections "In2.Cu")
		(teardrops
			(best_length_ratio 0.4)
			(max_length 1)
			(best_width_ratio 0.9)
			(max_width 2)
			(curved_edges yes)
			(filter_ratio 0.9)
			(enabled yes)
			(allow_two_segments yes)
			(prefer_zone_connections yes)
		)
		(net 541)
	)
	(segment
		(start 129.225 76.61)
		(end 123.05 82.785)
		(width 0.125)
		(layer "In2.Cu")
		(net 541)
	)
	(segment
		(start 228.870708 76.26)
		(end 228.520708 76.61)
		(width 0.125)
		(layer "In2.Cu")
		(net 541)
	)
	(segment
		(start 256.25 84.46)
		(end 256.25 79.91)
		(width 0.125)
		(layer "In2.Cu")
		(net 541)
	)
	(segment
		(start 252.6 76.26)
		(end 228.870708 76.26)
		(width 0.125)
		(layer "In2.Cu")
		(net 541)
	)
	(segment
		(start 122.3 110.26)
		(end 122.3 121.31)
		(width 0.125)
		(layer "In2.Cu")
		(net 541)
	)
	(segment
		(start 120.6 123.01)
		(end 120.6 141.61)
		(width 0.125)
		(layer "In2.Cu")
		(net 541)
	)
	(segment
		(start 123.05 82.785)
		(end 123.05 109.51)
		(width 0.125)
		(layer "In2.Cu")
		(net 541)
	)
	(segment
		(start 122.3 121.31)
		(end 120.6 123.01)
		(width 0.125)
		(layer "In2.Cu")
		(net 541)
	)
	(segment
		(start 256.25 79.91)
		(end 252.6 76.26)
		(width 0.125)
		(layer "In2.Cu")
		(net 541)
	)
	(segment
		(start 123.05 109.51)
		(end 122.3 110.26)
		(width 0.125)
		(layer "In2.Cu")
		(net 541)
	)
	(segment
		(start 120.6 141.61)
		(end 121.8 142.81)
		(width 0.125)
		(layer "In2.Cu")
		(net 541)
	)
	(segment
		(start 228.520708 76.61)
		(end 129.225 76.61)
		(width 0.125)
		(layer "In2.Cu")
		(net 541)
	)
	(segment
		(start 120.55 140.911)
		(end 121.799 140.911)
		(width 0.2)
		(layer "F.Cu")
		(net 542)
	)
	(segment
		(start 121.799 140.911)
		(end 121.8 140.91)
		(width 0.2)
		(layer "F.Cu")
		(net 542)
	)
	(segment
		(start 255.75 83.829999)
		(end 254.700001 83.829999)
		(width 0.125)
		(layer "F.Cu")
		(net 542)
	)
	(via
		(at 255.75 83.829999)
		(size 0.45)
		(drill 0.1)
		(layers "F.Cu" "B.Cu")
		(remove_unused_layers yes)
		(keep_end_layers yes)
		(zone_layer_connections "In2.Cu")
		(teardrops
			(best_length_ratio 0.4)
			(max_length 1)
			(best_width_ratio 0.9)
			(max_width 2)
			(curved_edges yes)
			(filter_ratio 0.9)
			(enabled yes)
			(allow_two_segments yes)
			(prefer_zone_connections yes)
		)
		(net 542)
	)
	(via
		(at 121.8 140.91)
		(size 0.45)
		(drill 0.1)
		(layers "F.Cu" "B.Cu")
		(remove_unused_layers yes)
		(keep_end_layers yes)
		(zone_layer_connections "In2.Cu")
		(teardrops
			(best_length_ratio 0.4)
			(max_length 1)
			(best_width_ratio 0.9)
			(max_width 2)
			(curved_edges yes)
			(filter_ratio 0.9)
			(enabled yes)
			(allow_two_segments yes)
			(prefer_zone_connections yes)
		)
		(net 542)
	)
	(segment
		(start 228.820708 77.01)
		(end 129.55 77.01)
		(width 0.125)
		(layer "In2.Cu")
		(net 542)
	)
	(segment
		(start 255.75 83.829999)
		(end 255.75 80.36)
		(width 0.125)
		(layer "In2.Cu")
		(net 542)
	)
	(segment
		(start 122.8 110.81)
		(end 122.8 122.46)
		(width 0.125)
		(layer "In2.Cu")
		(net 542)
	)
	(segment
		(start 123.3 83.26)
		(end 123.3 110.31)
		(width 0.125)
		(layer "In2.Cu")
		(net 542)
	)
	(segment
		(start 123.3 110.31)
		(end 122.8 110.81)
		(width 0.125)
		(layer "In2.Cu")
		(net 542)
	)
	(segment
		(start 122.8 122.46)
		(end 121.8 123.46)
		(width 0.125)
		(layer "In2.Cu")
		(net 542)
	)
	(segment
		(start 229.130708 76.7)
		(end 228.820708 77.01)
		(width 0.125)
		(layer "In2.Cu")
		(net 542)
	)
	(segment
		(start 121.8 123.46)
		(end 121.8 140.91)
		(width 0.125)
		(layer "In2.Cu")
		(net 542)
	)
	(segment
		(start 252.09 76.7)
		(end 229.130708 76.7)
		(width 0.125)
		(layer "In2.Cu")
		(net 542)
	)
	(segment
		(start 129.55 77.01)
		(end 123.3 83.26)
		(width 0.125)
		(layer "In2.Cu")
		(net 542)
	)
	(segment
		(start 255.75 80.36)
		(end 252.09 76.7)
		(width 0.125)
		(layer "In2.Cu")
		(net 542)
	)
	(segment
		(start 256.249999 85.729998)
		(end 254.7 85.729998)
		(width 0.125)
		(layer "F.Cu")
		(net 543)
	)
	(segment
		(start 316 111.709)
		(end 316.599 111.709)
		(width 0.125)
		(layer "F.Cu")
		(net 543)
	)
	(segment
		(start 256.25 85.729999)
		(end 256.249999 85.729998)
		(width 0.125)
		(layer "F.Cu")
		(net 543)
	)
	(segment
		(start 316.599 111.709)
		(end 317.5495 112.6595)
		(width 0.125)
		(layer "F.Cu")
		(net 543)
	)
	(segment
		(start 317.5495 112.6595)
		(end 318.2 112.6595)
		(width 0.125)
		(layer "F.Cu")
		(net 543)
	)
	(via
		(at 256.25 85.729999)
		(size 0.45)
		(drill 0.1)
		(layers "F.Cu" "B.Cu")
		(remove_unused_layers yes)
		(keep_end_layers yes)
		(zone_layer_connections "In5.Cu")
		(teardrops
			(best_length_ratio 0.4)
			(max_length 1)
			(best_width_ratio 0.9)
			(max_width 2)
			(curved_edges yes)
			(filter_ratio 0.9)
			(enabled yes)
			(allow_two_segments yes)
			(prefer_zone_connections yes)
		)
		(net 543)
	)
	(via
		(at 316 111.709)
		(size 0.45)
		(drill 0.1)
		(layers "F.Cu" "B.Cu")
		(remove_unused_layers yes)
		(keep_end_layers yes)
		(zone_layer_connections "In5.Cu")
		(teardrops
			(best_length_ratio 0.4)
			(max_length 1)
			(best_width_ratio 0.9)
			(max_width 2)
			(curved_edges yes)
			(filter_ratio 0.9)
			(enabled yes)
			(allow_two_segments yes)
			(prefer_zone_connections yes)
		)
		(net 543)
	)
	(segment
		(start 307.95 105.61)
		(end 307.95 91.646092)
		(width 0.125)
		(layer "In5.Cu")
		(net 543)
	)
	(segment
		(start 293.9 84.56)
		(end 263.35 84.56)
		(width 0.125)
		(layer "In5.Cu")
		(net 543)
	)
	(segment
		(start 301.763908 85.46)
		(end 294.8 85.46)
		(width 0.125)
		(layer "In5.Cu")
		(net 543)
	)
	(segment
		(start 294.8 85.46)
		(end 293.9 84.56)
		(width 0.125)
		(layer "In5.Cu")
		(net 543)
	)
	(segment
		(start 263.35 84.56)
		(end 262.15 83.36)
		(width 0.125)
		(layer "In5.Cu")
		(net 543)
	)
	(segment
		(start 262.15 83.36)
		(end 258.619999 83.36)
		(width 0.125)
		(layer "In5.Cu")
		(net 543)
	)
	(segment
		(start 307.95 91.646092)
		(end 301.763908 85.46)
		(width 0.125)
		(layer "In5.Cu")
		(net 543)
	)
	(segment
		(start 314.049 111.709)
		(end 307.95 105.61)
		(width 0.125)
		(layer "In5.Cu")
		(net 543)
	)
	(segment
		(start 258.619999 83.36)
		(end 256.25 85.729999)
		(width 0.125)
		(layer "In5.Cu")
		(net 543)
	)
	(segment
		(start 316 111.709)
		(end 314.049 111.709)
		(width 0.125)
		(layer "In5.Cu")
		(net 543)
	)
	(segment
		(start 255.749999 85.099999)
		(end 254.7 85.099999)
		(width 0.125)
		(layer "F.Cu")
		(net 544)
	)
	(segment
		(start 255.75 85.1)
		(end 255.749999 85.099999)
		(width 0.125)
		(layer "F.Cu")
		(net 544)
	)
	(via
		(at 255.75 85.1)
		(size 0.45)
		(drill 0.1)
		(layers "F.Cu" "B.Cu")
		(remove_unused_layers yes)
		(keep_end_layers yes)
		(zone_layer_connections "In5.Cu")
		(teardrops
			(best_length_ratio 0.4)
			(max_length 1)
			(best_width_ratio 0.9)
			(max_width 2)
			(curved_edges yes)
			(filter_ratio 0.9)
			(enabled yes)
			(allow_two_segments yes)
			(prefer_zone_connections yes)
		)
		(net 544)
	)
	(via
		(at 316 113.609)
		(size 0.45)
		(drill 0.1)
		(layers "F.Cu" "B.Cu")
		(remove_unused_layers yes)
		(keep_end_layers yes)
		(zone_layer_connections "In5.Cu")
		(teardrops
			(best_length_ratio 0.4)
			(max_length 1)
			(best_width_ratio 0.9)
			(max_width 2)
			(curved_edges yes)
			(filter_ratio 0.9)
			(enabled yes)
			(allow_two_segments yes)
			(prefer_zone_connections yes)
		)
		(net 544)
	)
	(segment
		(start 255.75 86.01)
		(end 256.05 86.31)
		(width 0.125)
		(layer "In5.Cu")
		(net 544)
	)
	(segment
		(start 256.745496 86.31)
		(end 259.145496 83.91)
		(width 0.125)
		(layer "In5.Cu")
		(net 544)
	)
	(segment
		(start 259.145496 83.91)
		(end 261.95 83.91)
		(width 0.125)
		(layer "In5.Cu")
		(net 544)
	)
	(segment
		(start 293.34 85.1)
		(end 294.3 86.06)
		(width 0.125)
		(layer "In5.Cu")
		(net 544)
	)
	(segment
		(start 307.05 92.01)
		(end 307.05 106.06)
		(width 0.125)
		(layer "In5.Cu")
		(net 544)
	)
	(segment
		(start 307.05 106.06)
		(end 314.599 113.609)
		(width 0.125)
		(layer "In5.Cu")
		(net 544)
	)
	(segment
		(start 261.95 83.91)
		(end 263.14 85.1)
		(width 0.125)
		(layer "In5.Cu")
		(net 544)
	)
	(segment
		(start 294.3 86.06)
		(end 301.1 86.06)
		(width 0.125)
		(layer "In5.Cu")
		(net 544)
	)
	(segment
		(start 256.05 86.31)
		(end 256.745496 86.31)
		(width 0.125)
		(layer "In5.Cu")
		(net 544)
	)
	(segment
		(start 255.75 85.1)
		(end 255.75 86.01)
		(width 0.125)
		(layer "In5.Cu")
		(net 544)
	)
	(segment
		(start 263.14 85.1)
		(end 293.34 85.1)
		(width 0.125)
		(layer "In5.Cu")
		(net 544)
	)
	(segment
		(start 301.1 86.06)
		(end 307.05 92.01)
		(width 0.125)
		(layer "In5.Cu")
		(net 544)
	)
	(segment
		(start 314.599 113.609)
		(end 316 113.609)
		(width 0.125)
		(layer "In5.Cu")
		(net 544)
	)
	(segment
		(start 252.75 127.96)
		(end 252.75 126.835)
		(width 0.125)
		(layer "F.Cu")
		(net 545)
	)
	(segment
		(start 253.376 126.209)
		(end 254.474 126.209)
		(width 0.125)
		(layer "F.Cu")
		(net 545)
	)
	(segment
		(start 252.75 126.835)
		(end 253.376 126.209)
		(width 0.125)
		(layer "F.Cu")
		(net 545)
	)
	(segment
		(start 252 128.111)
		(end 252.599 128.111)
		(width 0.125)
		(layer "F.Cu")
		(net 545)
	)
	(segment
		(start 252.599 128.111)
		(end 252.75 127.96)
		(width 0.125)
		(layer "F.Cu")
		(net 545)
	)
	(segment
		(start 257.174 131.159)
		(end 255.025 129.01)
		(width 0.125)
		(layer "F.Cu")
		(net 546)
	)
	(segment
		(start 249.469 129.566)
		(end 249.469 130.138)
		(width 0.125)
		(layer "F.Cu")
		(net 546)
	)
	(segment
		(start 255.025 129.01)
		(end 250.025 129.01)
		(width 0.125)
		(layer "F.Cu")
		(net 546)
	)
	(segment
		(start 250.025 129.01)
		(end 249.469 129.566)
		(width 0.125)
		(layer "F.Cu")
		(net 546)
	)
	(segment
		(start 257.174 132.61)
		(end 257.174 131.159)
		(width 0.125)
		(layer "F.Cu")
		(net 546)
	)
	(segment
		(start 118.199 86.864)
		(end 120.176 86.864)
		(width 0.125)
		(layer "F.Cu")
		(net 547)
	)
	(segment
		(start 118.199 91.764)
		(end 120.176 91.764)
		(width 0.125)
		(layer "F.Cu")
		(net 548)
	)
	(segment
		(start 135.685 113.545)
		(end 136.12 113.11)
		(width 0.2)
		(layer "F.Cu")
		(net 549)
	)
	(segment
		(start 134.845 113.545)
		(end 135.685 113.545)
		(width 0.2)
		(layer "F.Cu")
		(net 549)
	)
	(segment
		(start 134.845 105.735)
		(end 135.685 105.735)
		(width 0.2)
		(layer "F.Cu")
		(net 550)
	)
	(segment
		(start 135.685 105.735)
		(end 136.12 105.3)
		(width 0.2)
		(layer "F.Cu")
		(net 550)
	)
	(segment
		(start 134.845 109.655)
		(end 135.685 109.655)
		(width 0.2)
		(layer "F.Cu")
		(net 551)
	)
	(segment
		(start 135.685 109.655)
		(end 136.12 109.22)
		(width 0.2)
		(layer "F.Cu")
		(net 551)
	)
	(segment
		(start 135.685 101.845)
		(end 136.12 101.41)
		(width 0.2)
		(layer "F.Cu")
		(net 552)
	)
	(segment
		(start 134.845 101.845)
		(end 135.685 101.845)
		(width 0.2)
		(layer "F.Cu")
		(net 552)
	)
	(segment
		(start 116.454 87.814)
		(end 115.599 87.814)
		(width 0.125)
		(layer "F.Cu")
		(net 553)
	)
	(segment
		(start 120.6 88.56)
		(end 117.2 88.56)
		(width 0.125)
		(layer "F.Cu")
		(net 553)
	)
	(segment
		(start 117.2 88.56)
		(end 116.454 87.814)
		(width 0.125)
		(layer "F.Cu")
		(net 553)
	)
	(segment
		(start 121.57 88.06)
		(end 121.1 88.06)
		(width 0.125)
		(layer "F.Cu")
		(net 553)
	)
	(segment
		(start 121.1 88.06)
		(end 120.6 88.56)
		(width 0.125)
		(layer "F.Cu")
		(net 553)
	)
	(segment
		(start 121.57 87.06)
		(end 121.57 88.06)
		(width 0.125)
		(layer "F.Cu")
		(net 553)
	)
	(segment
		(start 121.57 92.96)
		(end 121.1 92.96)
		(width 0.125)
		(layer "F.Cu")
		(net 554)
	)
	(segment
		(start 116.454 92.714)
		(end 115.599 92.714)
		(width 0.125)
		(layer "F.Cu")
		(net 554)
	)
	(segment
		(start 121.57 91.96)
		(end 121.57 92.96)
		(width 0.125)
		(layer "F.Cu")
		(net 554)
	)
	(segment
		(start 117.2 93.46)
		(end 116.454 92.714)
		(width 0.125)
		(layer "F.Cu")
		(net 554)
	)
	(segment
		(start 121.1 92.96)
		(end 120.6 93.46)
		(width 0.125)
		(layer "F.Cu")
		(net 554)
	)
	(segment
		(start 120.6 93.46)
		(end 117.2 93.46)
		(width 0.125)
		(layer "F.Cu")
		(net 554)
	)
	(segment
		(start 121.135 86.06)
		(end 121.57 86.06)
		(width 0.125)
		(layer "F.Cu")
		(net 555)
	)
	(segment
		(start 121.57 86.06)
		(end 121.569999 85.06)
		(width 0.125)
		(layer "F.Cu")
		(net 555)
	)
	(segment
		(start 120.9 86.295)
		(end 121.135 86.06)
		(width 0.125)
		(layer "F.Cu")
		(net 555)
	)
	(segment
		(start 120.9 87.51)
		(end 120.9 86.295)
		(width 0.125)
		(layer "F.Cu")
		(net 555)
	)
	(segment
		(start 118.199 87.814)
		(end 120.596 87.814)
		(width 0.125)
		(layer "F.Cu")
		(net 555)
	)
	(segment
		(start 120.596 87.814)
		(end 120.9 87.51)
		(width 0.125)
		(layer "F.Cu")
		(net 555)
	)
	(segment
		(start 121.57 90.96)
		(end 121.569999 89.96)
		(width 0.125)
		(layer "F.Cu")
		(net 556)
	)
	(segment
		(start 120.596 92.714)
		(end 120.9 92.41)
		(width 0.125)
		(layer "F.Cu")
		(net 556)
	)
	(segment
		(start 118.199 92.714)
		(end 120.596 92.714)
		(width 0.125)
		(layer "F.Cu")
		(net 556)
	)
	(segment
		(start 120.9 92.41)
		(end 120.9 91.195)
		(width 0.125)
		(layer "F.Cu")
		(net 556)
	)
	(segment
		(start 121.135 90.96)
		(end 121.57 90.96)
		(width 0.125)
		(layer "F.Cu")
		(net 556)
	)
	(segment
		(start 120.9 91.195)
		(end 121.135 90.96)
		(width 0.125)
		(layer "F.Cu")
		(net 556)
	)
	(segment
		(start 162.62 159.36)
		(end 162.62 160.36)
		(width 0.125)
		(layer "F.Cu")
		(net 557)
	)
	(segment
		(start 162.62 159.36)
		(end 161.237 159.36)
		(width 0.125)
		(layer "F.Cu")
		(net 557)
	)
	(segment
		(start 160.048 157.792)
		(end 160.55 157.29)
		(width 0.125)
		(layer "F.Cu")
		(net 558)
	)
	(segment
		(start 160.048 158.672)
		(end 160.048 157.792)
		(width 0.125)
		(layer "F.Cu")
		(net 558)
	)
	(segment
		(start 160.549 158.672)
		(end 160.549 158.291)
		(width 0.125)
		(layer "F.Cu")
		(net 559)
	)
	(segment
		(start 160.549 158.291)
		(end 161.55 157.29)
		(width 0.125)
		(layer "F.Cu")
		(net 559)
	)
	(segment
		(start 158.05 158.672)
		(end 158.05 157.79)
		(width 0.125)
		(layer "F.Cu")
		(net 560)
	)
	(segment
		(start 158.05 157.79)
		(end 157.55 157.29)
		(width 0.125)
		(layer "F.Cu")
		(net 560)
	)
	(segment
		(start 158.55 157.29)
		(end 158.55 158.672)
		(width 0.125)
		(layer "F.Cu")
		(net 561)
	)
	(segment
		(start 156.8 159.36)
		(end 156.6 159.16)
		(width 0.125)
		(layer "F.Cu")
		(net 562)
	)
	(segment
		(start 156.4 158.11)
		(end 155.779 158.11)
		(width 0.125)
		(layer "F.Cu")
		(net 562)
	)
	(segment
		(start 157.362 159.36)
		(end 156.8 159.36)
		(width 0.125)
		(layer "F.Cu")
		(net 562)
	)
	(segment
		(start 156.6 159.16)
		(end 156.6 158.31)
		(width 0.125)
		(layer "F.Cu")
		(net 562)
	)
	(segment
		(start 156.6 158.31)
		(end 156.4 158.11)
		(width 0.125)
		(layer "F.Cu")
		(net 562)
	)
	(segment
		(start 157.362 159.86)
		(end 156.529 159.86)
		(width 0.125)
		(layer "F.Cu")
		(net 563)
	)
	(segment
		(start 156.529 159.86)
		(end 155.779 159.11)
		(width 0.125)
		(layer "F.Cu")
		(net 563)
	)
	(segment
		(start 157.362 160.36)
		(end 156.029 160.36)
		(width 0.125)
		(layer "F.Cu")
		(net 564)
	)
	(segment
		(start 156.029 160.36)
		(end 155.779 160.11)
		(width 0.125)
		(layer "F.Cu")
		(net 564)
	)
	(segment
		(start 157.362 160.858)
		(end 156.031 160.858)
		(width 0.125)
		(layer "F.Cu")
		(net 565)
	)
	(segment
		(start 156.031 160.858)
		(end 155.779 161.11)
		(width 0.125)
		(layer "F.Cu")
		(net 565)
	)
	(segment
		(start 157.362 161.358)
		(end 156.531 161.358)
		(width 0.125)
		(layer "F.Cu")
		(net 566)
	)
	(segment
		(start 156.531 161.358)
		(end 155.779 162.11)
		(width 0.125)
		(layer "F.Cu")
		(net 566)
	)
	(segment
		(start 156.35 163.11)
		(end 155.779 163.11)
		(width 0.125)
		(layer "F.Cu")
		(net 567)
	)
	(segment
		(start 157.362 161.859)
		(end 156.851 161.859)
		(width 0.125)
		(layer "F.Cu")
		(net 567)
	)
	(segment
		(start 156.6 162.11)
		(end 156.6 162.86)
		(width 0.125)
		(layer "F.Cu")
		(net 567)
	)
	(segment
		(start 156.6 162.86)
		(end 156.35 163.11)
		(width 0.125)
		(layer "F.Cu")
		(net 567)
	)
	(segment
		(start 156.851 161.859)
		(end 156.6 162.11)
		(width 0.125)
		(layer "F.Cu")
		(net 567)
	)
	(segment
		(start 111.996999 75.636)
		(end 111.997999 75.635)
		(width 0.185)
		(layer "F.Cu")
		(net 568)
	)
	(segment
		(start 111.686999 75.326)
		(end 111.996999 75.636)
		(width 0.185)
		(layer "F.Cu")
		(net 568)
	)
	(segment
		(start 112.924999 75.635)
		(end 113.059999 75.5)
		(width 0.185)
		(layer "F.Cu")
		(net 568)
	)
	(segment
		(start 111.997999 75.635)
		(end 112.924999 75.635)
		(width 0.185)
		(layer "F.Cu")
		(net 568)
	)
	(segment
		(start 111.686998 76.326)
		(end 111.997999 76.015)
		(width 0.185)
		(layer "F.Cu")
		(net 569)
	)
	(segment
		(start 112.924999 76.015)
		(end 113.059999 76.15)
		(width 0.185)
		(layer "F.Cu")
		(net 569)
	)
	(segment
		(start 111.997999 76.015)
		(end 112.924999 76.015)
		(width 0.185)
		(layer "F.Cu")
		(net 569)
	)
	(segment
		(start 114.179998 78.71)
		(end 114.179999 77.73)
		(width 0.125)
		(layer "F.Cu")
		(net 570)
	)
	(segment
		(start 121.987 72.497)
		(end 121.987 71.459)
		(width 0.125)
		(layer "F.Cu")
		(net 571)
	)
	(segment
		(start 124.4 74.91)
		(end 121.987 72.497)
		(width 0.125)
		(layer "F.Cu")
		(net 571)
	)
	(segment
		(start 124.4 75.33)
		(end 124.4 74.91)
		(width 0.125)
		(layer "F.Cu")
		(net 571)
	)
	(segment
		(start 121.987 74.873)
		(end 122.15 74.71)
		(width 0.125)
		(layer "F.Cu")
		(net 572)
	)
	(segment
		(start 122.15 74.71)
		(end 123.2 74.71)
		(width 0.125)
		(layer "F.Cu")
		(net 572)
	)
	(segment
		(start 123.38 74.89)
		(end 123.38 75.33)
		(width 0.125)
		(layer "F.Cu")
		(net 572)
	)
	(segment
		(start 121.987 75.758)
		(end 121.987 74.873)
		(width 0.125)
		(layer "F.Cu")
		(net 572)
	)
	(segment
		(start 123.2 74.71)
		(end 123.38 74.89)
		(width 0.125)
		(layer "F.Cu")
		(net 572)
	)
	(via
		(at 98.82 76.81)
		(size 0.45)
		(drill 0.1)
		(layers "F.Cu" "B.Cu")
		(remove_unused_layers yes)
		(keep_end_layers yes)
		(zone_layer_connections "In5.Cu")
		(teardrops
			(best_length_ratio 0.4)
			(max_length 1)
			(best_width_ratio 0.9)
			(max_width 2)
			(curved_edges yes)
			(filter_ratio 0.9)
			(enabled yes)
			(allow_two_segments yes)
			(prefer_zone_connections yes)
		)
		(net 573)
	)
	(via
		(at 125.95 83.06)
		(size 0.45)
		(drill 0.1)
		(layers "F.Cu" "B.Cu")
		(remove_unused_layers yes)
		(keep_end_layers yes)
		(zone_layer_connections "In5.Cu")
		(teardrops
			(best_length_ratio 0.4)
			(max_length 1)
			(best_width_ratio 0.9)
			(max_width 2)
			(curved_edges yes)
			(filter_ratio 0.9)
			(enabled yes)
			(allow_two_segments yes)
			(prefer_zone_connections yes)
		)
		(net 573)
	)
	(segment
		(start 98.82 76.81)
		(end 99.32 77.31)
		(width 0.125)
		(layer "In5.Cu")
		(net 573)
	)
	(segment
		(start 106.45 77.31)
		(end 112.8 83.66)
		(width 0.125)
		(layer "In5.Cu")
		(net 573)
	)
	(segment
		(start 112.8 83.66)
		(end 125.35 83.66)
		(width 0.125)
		(layer "In5.Cu")
		(net 573)
	)
	(segment
		(start 125.35 83.66)
		(end 125.95 83.06)
		(width 0.125)
		(layer "In5.Cu")
		(net 573)
	)
	(segment
		(start 99.32 77.31)
		(end 106.45 77.31)
		(width 0.125)
		(layer "In5.Cu")
		(net 573)
	)
	(segment
		(start 309.824999 104.298999)
		(end 310.316999 104.298999)
		(width 0.125)
		(layer "F.Cu")
		(net 574)
	)
	(via
		(at 309.824999 104.298999)
		(size 0.45)
		(drill 0.1)
		(layers "F.Cu" "B.Cu")
		(remove_unused_layers yes)
		(keep_end_layers yes)
		(zone_layer_connections)
		(teardrops
			(best_length_ratio 0.4)
			(max_length 1)
			(best_width_ratio 0.9)
			(max_width 2)
			(curved_edges yes)
			(filter_ratio 0.9)
			(enabled yes)
			(allow_two_segments yes)
			(prefer_zone_connections yes)
		)
		(net 574)
	)
	(segment
		(start 309.824999 102.24)
		(end 309.824999 104.298999)
		(width 0.125)
		(layer "B.Cu")
		(net 574)
	)
	(segment
		(start 308.824999 101.28)
		(end 308.824999 100.744999)
		(width 0.125)
		(layer "B.Cu")
		(net 574)
	)
	(segment
		(start 308.824999 100.744999)
		(end 308.74 100.66)
		(width 0.125)
		(layer "B.Cu")
		(net 574)
	)
	(segment
		(start 308.864999 101.28)
		(end 309.824999 102.24)
		(width 0.125)
		(layer "B.Cu")
		(net 574)
	)
	(segment
		(start 305.574 100.66)
		(end 307.474 100.66)
		(width 0.125)
		(layer "B.Cu")
		(net 574)
	)
	(segment
		(start 308.74 100.66)
		(end 307.474 100.66)
		(width 0.125)
		(layer "B.Cu")
		(net 574)
	)
	(segment
		(start 309.973 121.461999)
		(end 310.316999 121.461999)
		(width 0.125)
		(layer "F.Cu")
		(net 575)
	)
	(segment
		(start 309.971001 121.46)
		(end 309.973 121.461999)
		(width 0.125)
		(layer "F.Cu")
		(net 575)
	)
	(segment
		(start 309.824999 121.46)
		(end 309.971001 121.46)
		(width 0.125)
		(layer "F.Cu")
		(net 575)
	)
	(via
		(at 309.824999 121.46)
		(size 0.45)
		(drill 0.1)
		(layers "F.Cu" "B.Cu")
		(remove_unused_layers yes)
		(keep_end_layers yes)
		(zone_layer_connections)
		(teardrops
			(best_length_ratio 0.4)
			(max_length 1)
			(best_width_ratio 0.9)
			(max_width 2)
			(curved_edges yes)
			(filter_ratio 0.9)
			(enabled yes)
			(allow_two_segments yes)
			(prefer_zone_connections yes)
		)
		(net 575)
	)
	(segment
		(start 308.824999 122.44)
		(end 309.784999 121.48)
		(width 0.125)
		(layer "B.Cu")
		(net 575)
	)
	(segment
		(start 309.824999 105.65)
		(end 309.971001 105.65)
		(width 0.125)
		(layer "F.Cu")
		(net 576)
	)
	(segment
		(start 309.971001 105.65)
		(end 309.973 105.651999)
		(width 0.125)
		(layer "F.Cu")
		(net 576)
	)
	(segment
		(start 309.973 105.651999)
		(end 310.316999 105.651999)
		(width 0.125)
		(layer "F.Cu")
		(net 576)
	)
	(via
		(at 309.824999 105.65)
		(size 0.45)
		(drill 0.1)
		(layers "F.Cu" "B.Cu")
		(remove_unused_layers yes)
		(keep_end_layers yes)
		(zone_layer_connections)
		(teardrops
			(best_length_ratio 0.4)
			(max_length 1)
			(best_width_ratio 0.9)
			(max_width 2)
			(curved_edges yes)
			(filter_ratio 0.9)
			(enabled yes)
			(allow_two_segments yes)
			(prefer_zone_connections yes)
		)
		(net 576)
	)
	(segment
		(start 308.824999 106.63)
		(end 309.784999 105.67)
		(width 0.125)
		(layer "B.Cu")
		(net 576)
	)
	(segment
		(start 309.824999 120.108999)
		(end 310.316999 120.108999)
		(width 0.125)
		(layer "F.Cu")
		(net 577)
	)
	(via
		(at 309.824999 120.108999)
		(size 0.45)
		(drill 0.1)
		(layers "F.Cu" "B.Cu")
		(remove_unused_layers yes)
		(keep_end_layers yes)
		(zone_layer_connections)
		(teardrops
			(best_length_ratio 0.4)
			(max_length 1)
			(best_width_ratio 0.9)
			(max_width 2)
			(curved_edges yes)
			(filter_ratio 0.9)
			(enabled yes)
			(allow_two_segments yes)
			(prefer_zone_connections yes)
		)
		(net 577)
	)
	(segment
		(start 307.464999 121.06)
		(end 307.964999 120.56)
		(width 0.125)
		(layer "B.Cu")
		(net 577)
	)
	(segment
		(start 309.373998 120.56)
		(end 309.824999 120.108999)
		(width 0.125)
		(layer "B.Cu")
		(net 577)
	)
	(segment
		(start 307.964999 120.56)
		(end 309.373998 120.56)
		(width 0.125)
		(layer "B.Cu")
		(net 577)
	)
	(segment
		(start 307.464999 121.48)
		(end 307.464999 121.06)
		(width 0.125)
		(layer "B.Cu")
		(net 577)
	)
	(segment
		(start 311.264999 118.66)
		(end 311.264999 119.160999)
		(width 0.125)
		(layer "F.Cu")
		(net 578)
	)
	(segment
		(start 306.62 131.04)
		(end 306.62 130.03)
		(width 0.125)
		(layer "F.Cu")
		(net 578)
	)
	(via
		(at 306.62 130.54)
		(size 0.45)
		(drill 0.1)
		(layers "F.Cu" "B.Cu")
		(remove_unused_layers yes)
		(keep_end_layers yes)
		(zone_layer_connections)
		(teardrops
			(best_length_ratio 0.4)
			(max_length 1)
			(best_width_ratio 0.9)
			(max_width 2)
			(curved_edges yes)
			(filter_ratio 0.9)
			(enabled yes)
			(allow_two_segments yes)
			(prefer_zone_connections yes)
		)
		(net 578)
	)
	(via
		(at 311.264999 118.66)
		(size 0.45)
		(drill 0.1)
		(layers "F.Cu" "B.Cu")
		(remove_unused_layers yes)
		(keep_end_layers yes)
		(zone_layer_connections)
		(teardrops
			(best_length_ratio 0.4)
			(max_length 1)
			(best_width_ratio 0.9)
			(max_width 2)
			(curved_edges yes)
			(filter_ratio 0.9)
			(enabled yes)
			(allow_two_segments yes)
			(prefer_zone_connections yes)
		)
		(net 578)
	)
	(segment
		(start 311.264999 118.66)
		(end 310.52 118.66)
		(width 0.125)
		(layer "B.Cu")
		(net 578)
	)
	(segment
		(start 312.85 124.31)
		(end 312.85 119.71)
		(width 0.125)
		(layer "B.Cu")
		(net 578)
	)
	(segment
		(start 311.8 118.66)
		(end 311.264999 118.66)
		(width 0.125)
		(layer "B.Cu")
		(net 578)
	)
	(segment
		(start 306.62 130.54)
		(end 312.85 124.31)
		(width 0.125)
		(layer "B.Cu")
		(net 578)
	)
	(segment
		(start 312.85 119.71)
		(end 311.8 118.66)
		(width 0.125)
		(layer "B.Cu")
		(net 578)
	)
	(segment
		(start 103.06 96.04)
		(end 100.75 96.04)
		(width 0.3)
		(layer "B.Cu")
		(net 579)
	)
	(segment
		(start 100.73 95.51)
		(end 100.73 96.06)
		(width 0.3)
		(layer "B.Cu")
		(net 579)
	)
	(segment
		(start 100.73 96.06)
		(end 100.73 96.56)
		(width 0.3)
		(layer "B.Cu")
		(net 579)
	)
	(segment
		(start 100.75 96.04)
		(end 100.73 96.06)
		(width 0.3)
		(layer "B.Cu")
		(net 579)
	)
	(segment
		(start 309.174999 120.64)
		(end 309.174999 121.61)
		(width 0.125)
		(layer "F.Cu")
		(net 580)
	)
	(segment
		(start 309.499999 121.135)
		(end 309.174999 121.135)
		(width 0.125)
		(layer "F.Cu")
		(net 580)
	)
	(segment
		(start 310.316999 121.011999)
		(end 309.623 121.011999)
		(width 0.125)
		(layer "F.Cu")
		(net 580)
	)
	(segment
		(start 309.623 121.011999)
		(end 309.499999 121.135)
		(width 0.125)
		(layer "F.Cu")
		(net 580)
	)
	(segment
		(start 310.316999 105.201999)
		(end 309.623 105.201999)
		(width 0.125)
		(layer "F.Cu")
		(net 581)
	)
	(segment
		(start 309.174999 104.83)
		(end 309.174999 105.804999)
		(width 0.125)
		(layer "F.Cu")
		(net 581)
	)
	(segment
		(start 309.499999 105.325)
		(end 309.174999 105.325)
		(width 0.125)
		(layer "F.Cu")
		(net 581)
	)
	(segment
		(start 309.623 105.201999)
		(end 309.499999 105.325)
		(width 0.125)
		(layer "F.Cu")
		(net 581)
	)
	(segment
		(start 305.66 131.04)
		(end 304.541 131.04)
		(width 0.125)
		(layer "F.Cu")
		(net 582)
	)
	(segment
		(start 312.424499 135.631)
		(end 312.424499 134.957)
		(width 0.125)
		(layer "F.Cu")
		(net 583)
	)
	(segment
		(start 312.075499 135.98)
		(end 312.424499 135.631)
		(width 0.125)
		(layer "F.Cu")
		(net 583)
	)
	(segment
		(start 312.3995 96.2395)
		(end 312.765499 96.605499)
		(width 0.125)
		(layer "F.Cu")
		(net 584)
	)
	(segment
		(start 311.805499 97.9165)
		(end 312.765499 96.9565)
		(width 0.125)
		(layer "F.Cu")
		(net 584)
	)
	(segment
		(start 312.3995 95.8835)
		(end 312.3995 96.2395)
		(width 0.125)
		(layer "F.Cu")
		(net 584)
	)
	(segment
		(start 312.765499 96.605499)
		(end 312.765499 96.9565)
		(width 0.125)
		(layer "F.Cu")
		(net 584)
	)
	(segment
		(start 313.765499 96.9565)
		(end 313.257999 96.449)
		(width 0.125)
		(layer "F.Cu")
		(net 585)
	)
	(segment
		(start 313.084 96.449)
		(end 312.8995 96.2645)
		(width 0.125)
		(layer "F.Cu")
		(net 585)
	)
	(segment
		(start 314.725499 97.9165)
		(end 313.765499 96.9565)
		(width 0.125)
		(layer "F.Cu")
		(net 585)
	)
	(segment
		(start 312.8995 96.2645)
		(end 312.8995 95.8835)
		(width 0.125)
		(layer "F.Cu")
		(net 585)
	)
	(segment
		(start 313.257999 96.449)
		(end 313.084 96.449)
		(width 0.125)
		(layer "F.Cu")
		(net 585)
	)
	(segment
		(start 313.075499 136.01)
		(end 314.005499 136.94)
		(width 0.125)
		(layer "F.Cu")
		(net 586)
	)
	(segment
		(start 313.075499 135.56)
		(end 313.075499 135.98)
		(width 0.125)
		(layer "F.Cu")
		(net 586)
	)
	(segment
		(start 312.924499 134.957)
		(end 312.924499 135.409)
		(width 0.125)
		(layer "F.Cu")
		(net 586)
	)
	(segment
		(start 312.924499 135.409)
		(end 313.075499 135.56)
		(width 0.125)
		(layer "F.Cu")
		(net 586)
	)
	(segment
		(start 302.95 84.49)
		(end 308.145 84.49)
		(width 0.125)
		(layer "F.Cu")
		(net 587)
	)
	(segment
		(start 308.145 84.49)
		(end 308.519 84.116)
		(width 0.125)
		(layer "F.Cu")
		(net 587)
	)
	(segment
		(start 308.519 84.116)
		(end 308.519 83.287)
		(width 0.125)
		(layer "F.Cu")
		(net 587)
	)
	(via
		(at 142.95 83.11)
		(size 0.45)
		(drill 0.1)
		(layers "F.Cu" "B.Cu")
		(remove_unused_layers yes)
		(keep_end_layers yes)
		(zone_layer_connections "In2.Cu")
		(teardrops
			(best_length_ratio 0.4)
			(max_length 1)
			(best_width_ratio 0.9)
			(max_width 2)
			(curved_edges yes)
			(filter_ratio 0.9)
			(enabled yes)
			(allow_two_segments yes)
			(prefer_zone_connections yes)
		)
		(net 587)
	)
	(via
		(at 302.95 84.49)
		(size 0.45)
		(drill 0.1)
		(layers "F.Cu" "B.Cu")
		(remove_unused_layers yes)
		(keep_end_layers yes)
		(zone_layer_connections "In5.Cu")
		(teardrops
			(best_length_ratio 0.4)
			(max_length 1)
			(best_width_ratio 0.9)
			(max_width 2)
			(curved_edges yes)
			(filter_ratio 0.9)
			(enabled yes)
			(allow_two_segments yes)
			(prefer_zone_connections yes)
		)
		(net 587)
	)
	(via
		(at 248.120708 80.26)
		(size 0.45)
		(drill 0.1)
		(layers "F.Cu" "B.Cu")
		(remove_unused_layers yes)
		(keep_end_layers yes)
		(zone_layer_connections "In2.Cu" "In5.Cu")
		(teardrops
			(best_length_ratio 0.4)
			(max_length 1)
			(best_width_ratio 0.9)
			(max_width 2)
			(curved_edges yes)
			(filter_ratio 0.9)
			(enabled yes)
			(allow_two_segments yes)
			(prefer_zone_connections yes)
		)
		(net 587)
	)
	(via
		(at 177 108.66)
		(size 0.45)
		(drill 0.1)
		(layers "F.Cu" "B.Cu")
		(remove_unused_layers yes)
		(keep_end_layers yes)
		(zone_layer_connections "In2.Cu")
		(teardrops
			(best_length_ratio 0.4)
			(max_length 1)
			(best_width_ratio 0.9)
			(max_width 2)
			(curved_edges yes)
			(filter_ratio 0.9)
			(enabled yes)
			(allow_two_segments yes)
			(prefer_zone_connections yes)
		)
		(net 587)
	)
	(segment
		(start 228.920708 78.81)
		(end 230.580708 77.15)
		(width 0.125)
		(layer "In2.Cu")
		(net 587)
	)
	(segment
		(start 237.560708 77.15)
		(end 240.670708 80.26)
		(width 0.125)
		(layer "In2.Cu")
		(net 587)
	)
	(segment
		(start 175.45 87.76)
		(end 184.4 78.81)
		(width 0.125)
		(layer "In2.Cu")
		(net 587)
	)
	(segment
		(start 175.45 107.11)
		(end 175.45 87.76)
		(width 0.125)
		(layer "In2.Cu")
		(net 587)
	)
	(segment
		(start 230.580708 77.15)
		(end 237.560708 77.15)
		(width 0.125)
		(layer "In2.Cu")
		(net 587)
	)
	(segment
		(start 240.670708 80.26)
		(end 248.120708 80.26)
		(width 0.125)
		(layer "In2.Cu")
		(net 587)
	)
	(segment
		(start 163 89.11)
		(end 175.45 89.11)
		(width 0.125)
		(layer "In2.Cu")
		(net 587)
	)
	(segment
		(start 142.95 83.11)
		(end 157 83.11)
		(width 0.125)
		(layer "In2.Cu")
		(net 587)
	)
	(segment
		(start 157 83.11)
		(end 163 89.11)
		(width 0.125)
		(layer "In2.Cu")
		(net 587)
	)
	(segment
		(start 177 108.66)
		(end 175.45 107.11)
		(width 0.125)
		(layer "In2.Cu")
		(net 587)
	)
	(segment
		(start 184.4 78.81)
		(end 228.920708 78.81)
		(width 0.125)
		(layer "In2.Cu")
		(net 587)
	)
	(segment
		(start 261.320708 75.68)
		(end 261.320708 77.01)
		(width 0.125)
		(layer "In5.Cu")
		(net 587)
	)
	(segment
		(start 265.74 76.99)
		(end 263.74 74.99)
		(width 0.125)
		(layer "In5.Cu")
		(net 587)
	)
	(segment
		(start 302.95 84.49)
		(end 295.45 76.99)
		(width 0.125)
		(layer "In5.Cu")
		(net 587)
	)
	(segment
		(start 259.020708 79.31)
		(end 249.070708 79.31)
		(width 0.125)
		(layer "In5.Cu")
		(net 587)
	)
	(segment
		(start 295.45 76.99)
		(end 265.74 76.99)
		(width 0.125)
		(layer "In5.Cu")
		(net 587)
	)
	(segment
		(start 261.320708 77.01)
		(end 259.020708 79.31)
		(width 0.125)
		(layer "In5.Cu")
		(net 587)
	)
	(segment
		(start 263.74 74.99)
		(end 262.010708 74.99)
		(width 0.125)
		(layer "In5.Cu")
		(net 587)
	)
	(segment
		(start 249.070708 79.31)
		(end 248.120708 80.26)
		(width 0.125)
		(layer "In5.Cu")
		(net 587)
	)
	(segment
		(start 262.010708 74.99)
		(end 261.320708 75.68)
		(width 0.125)
		(layer "In5.Cu")
		(net 587)
	)
	(segment
		(start 254.7 82.559999)
		(end 254.025 82.559999)
		(width 0.125)
		(layer "F.Cu")
		(net 588)
	)
	(segment
		(start 253.565 81.174999)
		(end 253.095 81.174999)
		(width 0.125)
		(layer "F.Cu")
		(net 588)
	)
	(segment
		(start 253.79 81.399999)
		(end 253.565 81.174999)
		(width 0.125)
		(layer "F.Cu")
		(net 588)
	)
	(segment
		(start 254.025 82.559999)
		(end 253.79 82.324999)
		(width 0.125)
		(layer "F.Cu")
		(net 588)
	)
	(segment
		(start 253.79 82.324999)
		(end 253.79 81.399999)
		(width 0.125)
		(layer "F.Cu")
		(net 588)
	)
	(segment
		(start 253.095 83.174999)
		(end 253.095 82.174999)
		(width 0.125)
		(layer "F.Cu")
		(net 589)
	)
	(segment
		(start 254.7 83.189999)
		(end 253.11 83.189999)
		(width 0.125)
		(layer "F.Cu")
		(net 589)
	)
	(segment
		(start 254.699999 88.269999)
		(end 253.324999 88.269999)
		(width 0.2)
		(layer "F.Cu")
		(net 590)
	)
	(segment
		(start 254.7 87.639999)
		(end 253.335 87.639999)
		(width 0.2)
		(layer "F.Cu")
		(net 591)
	)
	(segment
		(start 254.065 86.999999)
		(end 253.515 86.449999)
		(width 0.2)
		(layer "F.Cu")
		(net 592)
	)
	(segment
		(start 254.7 86.999999)
		(end 254.065 86.999999)
		(width 0.2)
		(layer "F.Cu")
		(net 592)
	)
	(segment
		(start 253.515 86.449999)
		(end 253.145 86.449999)
		(width 0.2)
		(layer "F.Cu")
		(net 592)
	)
	(segment
		(start 254.055 88.909999)
		(end 253.515 89.449999)
		(width 0.2)
		(layer "F.Cu")
		(net 593)
	)
	(segment
		(start 253.515 89.449999)
		(end 253.144999 89.449999)
		(width 0.2)
		(layer "F.Cu")
		(net 593)
	)
	(segment
		(start 254.7 88.909999)
		(end 254.055 88.909999)
		(width 0.2)
		(layer "F.Cu")
		(net 593)
	)
	(segment
		(start 254.07 86.369999)
		(end 253.15 85.449999)
		(width 0.125)
		(layer "F.Cu")
		(net 594)
	)
	(segment
		(start 254.7 86.369999)
		(end 254.07 86.369999)
		(width 0.125)
		(layer "F.Cu")
		(net 594)
	)
	(segment
		(start 252.190001 85.404998)
		(end 253.145 84.449999)
		(width 0.125)
		(layer "F.Cu")
		(net 595)
	)
	(via
		(at 253.145 84.449999)
		(size 0.45)
		(drill 0.1)
		(layers "F.Cu" "B.Cu")
		(remove_unused_layers yes)
		(keep_end_layers yes)
		(zone_layer_connections "In2.Cu")
		(teardrops
			(best_length_ratio 0.4)
			(max_length 1)
			(best_width_ratio 0.9)
			(max_width 2)
			(curved_edges yes)
			(filter_ratio 0.9)
			(enabled yes)
			(allow_two_segments yes)
			(prefer_zone_connections yes)
		)
		(net 595)
	)
	(via
		(at 243.820708 77.185)
		(size 0.45)
		(drill 0.1)
		(layers "F.Cu" "B.Cu")
		(remove_unused_layers yes)
		(keep_end_layers yes)
		(zone_layer_connections "In5.Cu")
		(teardrops
			(best_length_ratio 0.4)
			(max_length 1)
			(best_width_ratio 0.9)
			(max_width 2)
			(curved_edges yes)
			(filter_ratio 0.9)
			(enabled yes)
			(allow_two_segments yes)
			(prefer_zone_connections yes)
		)
		(net 595)
	)
	(via
		(at 257.550707 77.185)
		(size 0.45)
		(drill 0.1)
		(layers "F.Cu" "B.Cu")
		(remove_unused_layers yes)
		(keep_end_layers yes)
		(zone_layer_connections "In2.Cu" "In5.Cu")
		(teardrops
			(best_length_ratio 0.4)
			(max_length 1)
			(best_width_ratio 0.9)
			(max_width 2)
			(curved_edges yes)
			(filter_ratio 0.9)
			(enabled yes)
			(allow_two_segments yes)
			(prefer_zone_connections yes)
		)
		(net 595)
	)
	(segment
		(start 258.08 77.714293)
		(end 257.550707 77.185)
		(width 0.125)
		(layer "In2.Cu")
		(net 595)
	)
	(segment
		(start 253.145 84.449999)
		(end 254.985001 86.29)
		(width 0.125)
		(layer "In2.Cu")
		(net 595)
	)
	(segment
		(start 254.985001 86.29)
		(end 256.47 86.29)
		(width 0.125)
		(layer "In2.Cu")
		(net 595)
	)
	(segment
		(start 258.08 84.68)
		(end 258.08 77.714293)
		(width 0.125)
		(layer "In2.Cu")
		(net 595)
	)
	(segment
		(start 256.47 86.29)
		(end 258.08 84.68)
		(width 0.125)
		(layer "In2.Cu")
		(net 595)
	)
	(segment
		(start 257.550707 77.185)
		(end 256.975707 76.61)
		(width 0.125)
		(layer "In5.Cu")
		(net 595)
	)
	(segment
		(start 244.395708 76.61)
		(end 243.820708 77.185)
		(width 0.125)
		(layer "In5.Cu")
		(net 595)
	)
	(segment
		(start 256.975707 76.61)
		(end 244.395708 76.61)
		(width 0.125)
		(layer "In5.Cu")
		(net 595)
	)
	(segment
		(start 249.470708 88.720708)
		(end 249.470708 86.31)
		(width 0.125)
		(layer "F.Cu")
		(net 596)
	)
	(segment
		(start 257.92 84.74)
		(end 257.92 88.83)
		(width 0.125)
		(layer "F.Cu")
		(net 596)
	)
	(segment
		(start 249.470708 86.31)
		(end 242.245708 79.085)
		(width 0.125)
		(layer "F.Cu")
		(net 596)
	)
	(segment
		(start 255.5 91.25)
		(end 252 91.25)
		(width 0.125)
		(layer "F.Cu")
		(net 596)
	)
	(segment
		(start 252 91.25)
		(end 249.470708 88.720708)
		(width 0.125)
		(layer "F.Cu")
		(net 596)
	)
	(segment
		(start 257.92 88.83)
		(end 255.5 91.25)
		(width 0.125)
		(layer "F.Cu")
		(net 596)
	)
	(segment
		(start 261.54 83.829999)
		(end 258.830001 83.829999)
		(width 0.125)
		(layer "F.Cu")
		(net 596)
	)
	(segment
		(start 242.245708 79.085)
		(end 241.420708 79.085)
		(width 0.125)
		(layer "F.Cu")
		(net 596)
	)
	(segment
		(start 258.830001 83.829999)
		(end 257.92 84.74)
		(width 0.125)
		(layer "F.Cu")
		(net 596)
	)
	(segment
		(start 256.9 88.41)
		(end 255.77 89.54)
		(width 0.125)
		(layer "F.Cu")
		(net 597)
	)
	(segment
		(start 254.7 89.539999)
		(end 254.06 89.539999)
		(width 0.125)
		(layer "F.Cu")
		(net 597)
	)
	(segment
		(start 256.9 80.21)
		(end 256.9 88.41)
		(width 0.125)
		(layer "F.Cu")
		(net 597)
	)
	(segment
		(start 254.06 89.539999)
		(end 253.15 90.449999)
		(width 0.125)
		(layer "F.Cu")
		(net 597)
	)
	(segment
		(start 255.77 89.54)
		(end 254.7 89.54)
		(width 0.125)
		(layer "F.Cu")
		(net 597)
	)
	(segment
		(start 255.150707 79.085)
		(end 255.775 79.085)
		(width 0.125)
		(layer "F.Cu")
		(net 597)
	)
	(segment
		(start 255.775 79.085)
		(end 256.9 80.21)
		(width 0.125)
		(layer "F.Cu")
		(net 597)
	)
	(segment
		(start 238.25 152.930999)
		(end 238.25 151.931001)
		(width 0.125)
		(layer "F.Cu")
		(net 598)
	)
	(segment
		(start 238.25 153.962)
		(end 238.25 152.930999)
		(width 0.125)
		(layer "F.Cu")
		(net 598)
	)
	(segment
		(start 241.95 131.31)
		(end 241.8 131.46)
		(width 0.125)
		(layer "F.Cu")
		(net 599)
	)
	(segment
		(start 242.95 131.31)
		(end 241.95 131.31)
		(width 0.125)
		(layer "F.Cu")
		(net 599)
	)
	(segment
		(start 241.8 131.46)
		(end 241.8 131.88)
		(width 0.125)
		(layer "F.Cu")
		(net 599)
	)
	(segment
		(start 243.077 130.56)
		(end 243.077 131.183)
		(width 0.125)
		(layer "F.Cu")
		(net 599)
	)
	(segment
		(start 243.077 131.183)
		(end 242.95 131.31)
		(width 0.125)
		(layer "F.Cu")
		(net 599)
	)
	(segment
		(start 258.02 159.08)
		(end 254.02 159.08)
		(width 0.125)
		(layer "F.Cu")
		(net 600)
	)
	(segment
		(start 259.12 160.18)
		(end 258.02 159.08)
		(width 0.125)
		(layer "F.Cu")
		(net 600)
	)
	(segment
		(start 259.12 160.6)
		(end 259.12 160.18)
		(width 0.125)
		(layer "F.Cu")
		(net 600)
	)
	(segment
		(start 254.02 159.08)
		(end 250.535 162.565)
		(width 0.125)
		(layer "F.Cu")
		(net 600)
	)
	(segment
		(start 250.535 162.565)
		(end 249.322145 162.565)
		(width 0.125)
		(layer "F.Cu")
		(net 600)
	)
	(segment
		(start 257.423001 161.297)
		(end 256.523145 161.297)
		(width 0.125)
		(layer "F.Cu")
		(net 601)
	)
	(segment
		(start 258.120001 160.6)
		(end 257.423001 161.297)
		(width 0.125)
		(layer "F.Cu")
		(net 601)
	)
	(segment
		(start 213.203 127.725)
		(end 212.395 127.725)
		(width 0.125)
		(layer "F.Cu")
		(net 602)
	)
	(segment
		(start 211.76 126.09)
		(end 211.76 127.09)
		(width 0.125)
		(layer "F.Cu")
		(net 602)
	)
	(segment
		(start 212.395 127.725)
		(end 211.76 127.09)
		(width 0.125)
		(layer "F.Cu")
		(net 602)
	)
	(segment
		(start 213.07 133.26)
		(end 213.07 132.26)
		(width 0.125)
		(layer "F.Cu")
		(net 603)
	)
	(segment
		(start 213.45 132.26)
		(end 213.07 132.26)
		(width 0.125)
		(layer "F.Cu")
		(net 603)
	)
	(segment
		(start 213.878 131.2)
		(end 213.878 131.832)
		(width 0.125)
		(layer "F.Cu")
		(net 603)
	)
	(segment
		(start 213.878 131.832)
		(end 213.45 132.26)
		(width 0.125)
		(layer "F.Cu")
		(net 603)
	)
	(segment
		(start 215.775 134.345)
		(end 215.08 133.65)
		(width 0.125)
		(layer "F.Cu")
		(net 604)
	)
	(segment
		(start 215.925 135.235)
		(end 215.775 135.085)
		(width 0.125)
		(layer "F.Cu")
		(net 604)
	)
	(segment
		(start 215.08 133.65)
		(end 215.08 131.2)
		(width 0.125)
		(layer "F.Cu")
		(net 604)
	)
	(segment
		(start 215.925 136.47)
		(end 215.925 135.235)
		(width 0.125)
		(layer "F.Cu")
		(net 604)
	)
	(segment
		(start 215.775 135.085)
		(end 215.775 134.345)
		(width 0.125)
		(layer "F.Cu")
		(net 604)
	)
	(segment
		(start 216.935 136.46)
		(end 215.935 136.46)
		(width 0.125)
		(layer "F.Cu")
		(net 604)
	)
	(segment
		(start 217.079 131.699)
		(end 218 132.62)
		(width 0.125)
		(layer "F.Cu")
		(net 605)
	)
	(segment
		(start 217.079 131.2)
		(end 217.079 131.699)
		(width 0.125)
		(layer "F.Cu")
		(net 605)
	)
	(segment
		(start 219.432501 132.62)
		(end 218.43 132.62)
		(width 0.125)
		(layer "F.Cu")
		(net 605)
	)
	(segment
		(start 218 132.62)
		(end 218.43 132.62)
		(width 0.125)
		(layer "F.Cu")
		(net 605)
	)
	(segment
		(start 220.509695 129.029695)
		(end 221.33939 128.2)
		(width 0.125)
		(layer "F.Cu")
		(net 606)
	)
	(segment
		(start 221.33939 128.2)
		(end 222.2 128.2)
		(width 0.125)
		(layer "F.Cu")
		(net 606)
	)
	(segment
		(start 219.83 128.925)
		(end 219.934695 129.029695)
		(width 0.125)
		(layer "F.Cu")
		(net 606)
	)
	(segment
		(start 219.934695 129.029695)
		(end 220.509695 129.029695)
		(width 0.125)
		(layer "F.Cu")
		(net 606)
	)
	(segment
		(start 218.154 128.925)
		(end 219.83 128.925)
		(width 0.125)
		(layer "F.Cu")
		(net 606)
	)
	(segment
		(start 222.2 128.2)
		(end 222.2 127.195)
		(width 0.125)
		(layer "F.Cu")
		(net 606)
	)
	(segment
		(start 217.079 125.351)
		(end 218.53 123.9)
		(width 0.125)
		(layer "F.Cu")
		(net 607)
	)
	(segment
		(start 219.25 123.9)
		(end 219.25 122.9)
		(width 0.125)
		(layer "F.Cu")
		(net 607)
	)
	(segment
		(start 217.079 126.249)
		(end 217.079 125.351)
		(width 0.125)
		(layer "F.Cu")
		(net 607)
	)
	(segment
		(start 218.53 123.9)
		(end 219.25 123.9)
		(width 0.125)
		(layer "F.Cu")
		(net 607)
	)
	(segment
		(start 218.941219 127.7615)
		(end 219.22 127.482719)
		(width 0.125)
		(layer "F.Cu")
		(net 608)
	)
	(segment
		(start 218.578781 127.7615)
		(end 218.941219 127.7615)
		(width 0.125)
		(layer "F.Cu")
		(net 608)
	)
	(segment
		(start 218.154 127.725)
		(end 218.542281 127.725)
		(width 0.125)
		(layer "F.Cu")
		(net 608)
	)
	(segment
		(start 218.542281 127.725)
		(end 218.578781 127.7615)
		(width 0.125)
		(layer "F.Cu")
		(net 608)
	)
	(segment
		(start 219.22 127.482719)
		(end 219.22 125.9)
		(width 0.125)
		(layer "F.Cu")
		(net 608)
	)
	(segment
		(start 218.556 126.924)
		(end 218.63 126.85)
		(width 0.125)
		(layer "F.Cu")
		(net 609)
	)
	(segment
		(start 218.83 124.9)
		(end 219.22 124.9)
		(width 0.125)
		(layer "F.Cu")
		(net 609)
	)
	(segment
		(start 218.63 126.85)
		(end 218.63 125.1)
		(width 0.125)
		(layer "F.Cu")
		(net 609)
	)
	(segment
		(start 218.63 125.1)
		(end 218.83 124.9)
		(width 0.125)
		(layer "F.Cu")
		(net 609)
	)
	(segment
		(start 218.154 126.924)
		(end 218.556 126.924)
		(width 0.125)
		(layer "F.Cu")
		(net 609)
	)
	(segment
		(start 307.55 76.987002)
		(end 307.550001 77.483)
		(width 0.2)
		(layer "F.Cu")
		(net 610)
	)
	(segment
		(start 307.795 76.742002)
		(end 307.55 76.987002)
		(width 0.2)
		(layer "F.Cu")
		(net 610)
	)
	(segment
		(start 307.795 76.362002)
		(end 307.795 76.742002)
		(width 0.2)
		(layer "F.Cu")
		(net 610)
	)
	(segment
		(start 212.635999 128.1295)
		(end 212.640499 128.125)
		(width 0.202)
		(layer "F.Cu")
		(net 611)
	)
	(segment
		(start 210.1905 128.1255)
		(end 212.246 128.1255)
		(width 0.202)
		(layer "F.Cu")
		(net 611)
	)
	(segment
		(start 209.885 127.82)
		(end 210.1905 128.1255)
		(width 0.202)
		(layer "F.Cu")
		(net 611)
	)
	(segment
		(start 212.246 128.1255)
		(end 212.25 128.1295)
		(width 0.202)
		(layer "F.Cu")
		(net 611)
	)
	(segment
		(start 212.640499 128.125)
		(end 213.203 128.125)
		(width 0.202)
		(layer "F.Cu")
		(net 611)
	)
	(segment
		(start 212.25 128.1295)
		(end 212.635999 128.1295)
		(width 0.202)
		(layer "F.Cu")
		(net 611)
	)
	(segment
		(start 209.885 128.82)
		(end 210.1905 128.5145)
		(width 0.202)
		(layer "F.Cu")
		(net 612)
	)
	(segment
		(start 212.635999 128.5185)
		(end 212.640499 128.523)
		(width 0.202)
		(layer "F.Cu")
		(net 612)
	)
	(segment
		(start 210.1905 128.5145)
		(end 212.097137 128.5145)
		(width 0.202)
		(layer "F.Cu")
		(net 612)
	)
	(segment
		(start 212.101137 128.5185)
		(end 212.635999 128.5185)
		(width 0.202)
		(layer "F.Cu")
		(net 612)
	)
	(segment
		(start 212.640499 128.523)
		(end 213.203 128.523)
		(width 0.202)
		(layer "F.Cu")
		(net 612)
	)
	(segment
		(start 212.097137 128.5145)
		(end 212.101137 128.5185)
		(width 0.202)
		(layer "F.Cu")
		(net 612)
	)
	(segment
		(start 213.2 129.72)
		(end 213.203 129.723)
		(width 0.202)
		(layer "F.Cu")
		(net 613)
	)
	(segment
		(start 211.76 129.425)
		(end 212.055 129.72)
		(width 0.202)
		(layer "F.Cu")
		(net 613)
	)
	(segment
		(start 212.055 129.72)
		(end 213.2 129.72)
		(width 0.202)
		(layer "F.Cu")
		(net 613)
	)
	(segment
		(start 213.1995 130.1195)
		(end 213.203 130.123)
		(width 0.202)
		(layer "F.Cu")
		(net 614)
	)
	(segment
		(start 212.0655 130.1195)
		(end 213.1995 130.1195)
		(width 0.202)
		(layer "F.Cu")
		(net 614)
	)
	(segment
		(start 211.76 130.425)
		(end 212.0655 130.1195)
		(width 0.202)
		(layer "F.Cu")
		(net 614)
	)
	(segment
		(start 213.98 134.495)
		(end 214.2855 134.1895)
		(width 0.202)
		(layer "F.Cu")
		(net 615)
	)
	(segment
		(start 214.28 131.762501)
		(end 214.28 131.2)
		(width 0.202)
		(layer "F.Cu")
		(net 615)
	)
	(segment
		(start 214.2855 134.1895)
		(end 214.2855 131.768001)
		(width 0.202)
		(layer "F.Cu")
		(net 615)
	)
	(segment
		(start 214.2855 131.768001)
		(end 214.28 131.762501)
		(width 0.202)
		(layer "F.Cu")
		(net 615)
	)
	(segment
		(start 214.98 134.495)
		(end 214.6745 134.1895)
		(width 0.202)
		(layer "F.Cu")
		(net 616)
	)
	(segment
		(start 214.6745 134.1895)
		(end 214.6745 131.768001)
		(width 0.202)
		(layer "F.Cu")
		(net 616)
	)
	(segment
		(start 214.6745 131.768001)
		(end 214.68 131.762501)
		(width 0.202)
		(layer "F.Cu")
		(net 616)
	)
	(segment
		(start 214.68 131.762501)
		(end 214.68 131.2)
		(width 0.202)
		(layer "F.Cu")
		(net 616)
	)
	(segment
		(start 216.2855 131.2075)
		(end 216.2855 132.3095)
		(width 0.202)
		(layer "F.Cu")
		(net 617)
	)
	(segment
		(start 216.2855 132.3095)
		(end 215.98 132.615)
		(width 0.202)
		(layer "F.Cu")
		(net 617)
	)
	(segment
		(start 216.278 131.2)
		(end 216.2855 131.2075)
		(width 0.202)
		(layer "F.Cu")
		(net 617)
	)
	(segment
		(start 216.678 131.2)
		(end 216.6745 131.2035)
		(width 0.202)
		(layer "F.Cu")
		(net 618)
	)
	(segment
		(start 216.6745 132.3095)
		(end 216.98 132.615)
		(width 0.202)
		(layer "F.Cu")
		(net 618)
	)
	(segment
		(start 216.6745 131.2035)
		(end 216.6745 132.3095)
		(width 0.202)
		(layer "F.Cu")
		(net 618)
	)
	(segment
		(start 220.655 130.65)
		(end 220.3495 130.3445)
		(width 0.202)
		(layer "F.Cu")
		(net 619)
	)
	(segment
		(start 219.476541 130.051607)
		(end 219.427945 130.003011)
		(width 0.202)
		(layer "F.Cu")
		(net 619)
	)
	(segment
		(start 218.716501 129.723)
		(end 218.154 129.723)
		(width 0.202)
		(layer "F.Cu")
		(net 619)
	)
	(segment
		(start 218.72822 129.7175)
		(end 218.738581 129.717499)
		(width 0.202)
		(layer "F.Cu")
		(net 619)
	)
	(segment
		(start 218.72822 129.7175)
		(end 218.722001 129.7175)
		(width 0.202)
		(layer "F.Cu")
		(net 619)
	)
	(segment
		(start 220.3495 130.3445)
		(end 220.183648 130.3445)
		(width 0.202)
		(layer "F.Cu")
		(net 619)
	)
	(segment
		(start 218.722001 129.7175)
		(end 218.716501 129.723)
		(width 0.202)
		(layer "F.Cu")
		(net 619)
	)
	(arc
		(start 219.427945 130.003011)
		(mid 219.111662 129.791687)
		(end 218.738581 129.717499)
		(width 0.202)
		(layer "F.Cu")
		(net 619)
	)
	(arc
		(start 219.476541 130.051607)
		(mid 219.800964 130.26838)
		(end 220.183648 130.3445)
		(width 0.202)
		(layer "F.Cu")
		(net 619)
	)
	(segment
		(start 218.716501 129.323)
		(end 218.154 129.323)
		(width 0.202)
		(layer "F.Cu")
		(net 620)
	)
	(segment
		(start 220.34478 129.9555)
		(end 220.189349 129.955497)
		(width 0.202)
		(layer "F.Cu")
		(net 620)
	)
	(segment
		(start 220.3495 129.9555)
		(end 220.34478 129.9555)
		(width 0.202)
		(layer "F.Cu")
		(net 620)
	)
	(segment
		(start 219.747562 129.772496)
		(end 219.697401 129.722335)
		(width 0.202)
		(layer "F.Cu")
		(net 620)
	)
	(segment
		(start 218.74658 129.3285)
		(end 218.722001 129.3285)
		(width 0.202)
		(layer "F.Cu")
		(net 620)
	)
	(segment
		(start 218.722001 129.3285)
		(end 218.716501 129.323)
		(width 0.202)
		(layer "F.Cu")
		(net 620)
	)
	(segment
		(start 220.655 129.65)
		(end 220.3495 129.9555)
		(width 0.202)
		(layer "F.Cu")
		(net 620)
	)
	(arc
		(start 219.697401 129.722335)
		(mid 219.261159 129.43085)
		(end 218.74658 129.3285)
		(width 0.202)
		(layer "F.Cu")
		(net 620)
	)
	(arc
		(start 220.189349 129.955497)
		(mid 219.950255 129.907934)
		(end 219.747562 129.772496)
		(width 0.202)
		(layer "F.Cu")
		(net 620)
	)
	(segment
		(start 219.75983 128.045236)
		(end 219.570223 128.234843)
		(width 0.202)
		(layer "F.Cu")
		(net 621)
	)
	(segment
		(start 218.885414 128.5185)
		(end 218.721001 128.5185)
		(width 0.202)
		(layer "F.Cu")
		(net 621)
	)
	(segment
		(start 220.244066 127.8695)
		(end 220.184094 127.8695)
		(width 0.202)
		(layer "F.Cu")
		(net 621)
	)
	(segment
		(start 220.368066 127.9935)
		(end 220.244066 127.8695)
		(width 0.202)
		(layer "F.Cu")
		(net 621)
	)
	(segment
		(start 218.721001 128.5185)
		(end 218.716501 128.523)
		(width 0.202)
		(layer "F.Cu")
		(net 621)
	)
	(segment
		(start 218.716501 128.523)
		(end 218.154 128.523)
		(width 0.202)
		(layer "F.Cu")
		(net 621)
	)
	(via
		(at 220.368066 127.9935)
		(size 0.45)
		(drill 0.1)
		(layers "F.Cu" "B.Cu")
		(remove_unused_layers yes)
		(keep_end_layers yes)
		(zone_layer_connections)
		(teardrops
			(best_length_ratio 0.4)
			(max_length 1)
			(best_width_ratio 0.9)
			(max_width 2)
			(curved_edges yes)
			(filter_ratio 0.9)
			(enabled yes)
			(allow_two_segments yes)
			(prefer_zone_connections yes)
		)
		(net 621)
	)
	(arc
		(start 219.570223 128.234843)
		(mid 219.25603 128.44478)
		(end 218.885414 128.5185)
		(width 0.202)
		(layer "F.Cu")
		(net 621)
	)
	(arc
		(start 219.75983 128.045236)
		(mid 219.954484 127.915172)
		(end 220.184094 127.8695)
		(width 0.202)
		(layer "F.Cu")
		(net 621)
	)
	(segment
		(start 220.492066 127.8695)
		(end 220.368066 127.9935)
		(width 0.202)
		(layer "B.Cu")
		(net 621)
	)
	(segment
		(start 220.808079 127.8695)
		(end 220.492066 127.8695)
		(width 0.202)
		(layer "B.Cu")
		(net 621)
	)
	(segment
		(start 221.18 128.2)
		(end 220.878789 127.898789)
		(width 0.202)
		(layer "B.Cu")
		(net 621)
	)
	(arc
		(start 220.808079 127.8695)
		(mid 220.846347 127.877112)
		(end 220.878789 127.898789)
		(width 0.202)
		(layer "B.Cu")
		(net 621)
	)
	(segment
		(start 218.876906 128.1295)
		(end 218.721001 128.1295)
		(width 0.202)
		(layer "F.Cu")
		(net 622)
	)
	(segment
		(start 219.485422 127.769512)
		(end 219.30117 127.953764)
		(width 0.202)
		(layer "F.Cu")
		(net 622)
	)
	(segment
		(start 218.721001 128.1295)
		(end 218.716501 128.125)
		(width 0.202)
		(layer "F.Cu")
		(net 622)
	)
	(segment
		(start 220.368066 127.3565)
		(end 220.244066 127.4805)
		(width 0.202)
		(layer "F.Cu")
		(net 622)
	)
	(segment
		(start 218.716501 128.125)
		(end 218.154 128.125)
		(width 0.202)
		(layer "F.Cu")
		(net 622)
	)
	(segment
		(start 220.244066 127.4805)
		(end 220.183158 127.4805)
		(width 0.202)
		(layer "F.Cu")
		(net 622)
	)
	(via
		(at 220.368066 127.3565)
		(size 0.45)
		(drill 0.1)
		(layers "F.Cu" "B.Cu")
		(remove_unused_layers yes)
		(keep_end_layers yes)
		(zone_layer_connections)
		(teardrops
			(best_length_ratio 0.4)
			(max_length 1)
			(best_width_ratio 0.9)
			(max_width 2)
			(curved_edges yes)
			(filter_ratio 0.9)
			(enabled yes)
			(allow_two_segments yes)
			(prefer_zone_connections yes)
		)
		(net 622)
	)
	(arc
		(start 219.485422 127.769512)
		(mid 219.805546 127.555612)
		(end 220.183158 127.4805)
		(width 0.202)
		(layer "F.Cu")
		(net 622)
	)
	(arc
		(start 218.876906 128.1295)
		(mid 219.106516 128.083828)
		(end 219.30117 127.953764)
		(width 0.202)
		(layer "F.Cu")
		(net 622)
	)
	(segment
		(start 220.808079 127.4805)
		(end 220.492066 127.4805)
		(width 0.202)
		(layer "B.Cu")
		(net 622)
	)
	(segment
		(start 220.492066 127.4805)
		(end 220.368066 127.3565)
		(width 0.202)
		(layer "B.Cu")
		(net 622)
	)
	(segment
		(start 221.18 127.15)
		(end 220.878789 127.451211)
		(width 0.202)
		(layer "B.Cu")
		(net 622)
	)
	(arc
		(start 220.808079 127.4805)
		(mid 220.846347 127.472888)
		(end 220.878789 127.451211)
		(width 0.202)
		(layer "B.Cu")
		(net 622)
	)
	(segment
		(start 111.85 148.71)
		(end 111.85 148.41)
		(width 0.125)
		(layer "F.Cu")
		(net 623)
	)
	(segment
		(start 112 148.86)
		(end 111.85 148.71)
		(width 0.125)
		(layer "F.Cu")
		(net 623)
	)
	(segment
		(start 111.85 148.41)
		(end 111.4 147.96)
		(width 0.125)
		(layer "F.Cu")
		(net 623)
	)
	(segment
		(start 112.03 145.86)
		(end 112.42 145.86)
		(width 0.125)
		(layer "F.Cu")
		(net 623)
	)
	(segment
		(start 111.4 146.49)
		(end 112.03 145.86)
		(width 0.125)
		(layer "F.Cu")
		(net 623)
	)
	(segment
		(start 112.42 148.86)
		(end 112 148.86)
		(width 0.125)
		(layer "F.Cu")
		(net 623)
	)
	(segment
		(start 111.4 147.96)
		(end 111.4 146.49)
		(width 0.125)
		(layer "F.Cu")
		(net 623)
	)
	(via
		(at 111.85 148.41)
		(size 0.45)
		(drill 0.1)
		(layers "F.Cu" "B.Cu")
		(remove_unused_layers yes)
		(keep_end_layers yes)
		(zone_layer_connections)
		(teardrops
			(best_length_ratio 0.4)
			(max_length 1)
			(best_width_ratio 0.9)
			(max_width 2)
			(curved_edges yes)
			(filter_ratio 0.9)
			(enabled yes)
			(allow_two_segments yes)
			(prefer_zone_connections yes)
		)
		(net 623)
	)
	(segment
		(start 111.85 148.41)
		(end 112.151 148.109)
		(width 0.125)
		(layer "B.Cu")
		(net 623)
	)
	(segment
		(start 112.151 148.109)
		(end 112.963 148.109)
		(width 0.125)
		(layer "B.Cu")
		(net 623)
	)
	(segment
		(start 111.85 147.06)
		(end 111.85 147.61)
		(width 0.125)
		(layer "F.Cu")
		(net 624)
	)
	(segment
		(start 112.05 147.86)
		(end 111.85 147.66)
		(width 0.125)
		(layer "F.Cu")
		(net 624)
	)
	(segment
		(start 112.05 146.86)
		(end 111.85 147.06)
		(width 0.125)
		(layer "F.Cu")
		(net 624)
	)
	(segment
		(start 112.42 147.86)
		(end 112.05 147.86)
		(width 0.125)
		(layer "F.Cu")
		(net 624)
	)
	(segment
		(start 112.42 146.86)
		(end 112.05 146.86)
		(width 0.125)
		(layer "F.Cu")
		(net 624)
	)
	(segment
		(start 111.85 147.66)
		(end 111.85 147.61)
		(width 0.125)
		(layer "F.Cu")
		(net 624)
	)
	(via
		(at 111.85 147.61)
		(size 0.45)
		(drill 0.1)
		(layers "F.Cu" "B.Cu")
		(remove_unused_layers yes)
		(keep_end_layers yes)
		(zone_layer_connections)
		(teardrops
			(best_length_ratio 0.4)
			(max_length 1)
			(best_width_ratio 0.9)
			(max_width 2)
			(curved_edges yes)
			(filter_ratio 0.9)
			(enabled yes)
			(allow_two_segments yes)
			(prefer_zone_connections yes)
		)
		(net 624)
	)
	(segment
		(start 111.85 147.61)
		(end 112.962 147.61)
		(width 0.125)
		(layer "B.Cu")
		(net 624)
	)
	(segment
		(start 115.4 143.41)
		(end 115.4 143.88)
		(width 0.125)
		(layer "F.Cu")
		(net 625)
	)
	(segment
		(start 112.9 143.22)
		(end 115.21 143.22)
		(width 0.125)
		(layer "F.Cu")
		(net 625)
	)
	(segment
		(start 112.6 143.22)
		(end 112.9 143.22)
		(width 0.125)
		(layer "F.Cu")
		(net 625)
	)
	(segment
		(start 112.4 143.42)
		(end 112.6 143.22)
		(width 0.125)
		(layer "F.Cu")
		(net 625)
	)
	(segment
		(start 112.4 143.88)
		(end 112.4 143.42)
		(width 0.125)
		(layer "F.Cu")
		(net 625)
	)
	(segment
		(start 115.21 143.22)
		(end 115.4 143.41)
		(width 0.125)
		(layer "F.Cu")
		(net 625)
	)
	(via
		(at 112.9 143.22)
		(size 0.45)
		(drill 0.1)
		(layers "F.Cu" "B.Cu")
		(remove_unused_layers yes)
		(keep_end_layers yes)
		(zone_layer_connections)
		(teardrops
			(best_length_ratio 0.4)
			(max_length 1)
			(best_width_ratio 0.9)
			(max_width 2)
			(curved_edges yes)
			(filter_ratio 0.9)
			(enabled yes)
			(allow_two_segments yes)
			(prefer_zone_connections yes)
		)
		(net 625)
	)
	(segment
		(start 112.9 144.15)
		(end 113.401 144.651)
		(width 0.125)
		(layer "B.Cu")
		(net 625)
	)
	(segment
		(start 113.401 144.651)
		(end 113.401 145.673)
		(width 0.125)
		(layer "B.Cu")
		(net 625)
	)
	(segment
		(start 112.9 143.22)
		(end 112.9 144.15)
		(width 0.125)
		(layer "B.Cu")
		(net 625)
	)
	(segment
		(start 113.899 150.79)
		(end 113.849 150.84)
		(width 0.125)
		(layer "F.Cu")
		(net 626)
	)
	(segment
		(start 113.948999 150.84)
		(end 114.400001 150.84)
		(width 0.125)
		(layer "F.Cu")
		(net 626)
	)
	(segment
		(start 113.849 150.84)
		(end 113.4 150.84)
		(width 0.125)
		(layer "F.Cu")
		(net 626)
	)
	(segment
		(start 113.899 150.79)
		(end 113.948999 150.84)
		(width 0.125)
		(layer "F.Cu")
		(net 626)
	)
	(via
		(at 113.899 150.79)
		(size 0.45)
		(drill 0.1)
		(layers "F.Cu" "B.Cu")
		(remove_unused_layers yes)
		(keep_end_layers yes)
		(zone_layer_connections)
		(teardrops
			(best_length_ratio 0.4)
			(max_length 1)
			(best_width_ratio 0.9)
			(max_width 2)
			(curved_edges yes)
			(filter_ratio 0.9)
			(enabled yes)
			(allow_two_segments yes)
			(prefer_zone_connections yes)
		)
		(net 626)
	)
	(segment
		(start 113.901 150.788)
		(end 113.899 150.79)
		(width 0.125)
		(layer "B.Cu")
		(net 626)
	)
	(segment
		(start 113.901 149.048)
		(end 113.901 150.788)
		(width 0.125)
		(layer "B.Cu")
		(net 626)
	)
	(segment
		(start 115.2 151.499999)
		(end 112.589999 151.499999)
		(width 0.125)
		(layer "F.Cu")
		(net 627)
	)
	(segment
		(start 115.4 151.3)
		(end 115.2 151.499999)
		(width 0.125)
		(layer "F.Cu")
		(net 627)
	)
	(segment
		(start 112.4 151.31)
		(end 112.4 150.84)
		(width 0.125)
		(layer "F.Cu")
		(net 627)
	)
	(segment
		(start 112.589999 151.499999)
		(end 112.4 151.31)
		(width 0.125)
		(layer "F.Cu")
		(net 627)
	)
	(segment
		(start 115.4 150.84)
		(end 115.4 151.3)
		(width 0.125)
		(layer "F.Cu")
		(net 627)
	)
	(via
		(at 112.9 151.51)
		(size 0.45)
		(drill 0.1)
		(layers "F.Cu" "B.Cu")
		(remove_unused_layers yes)
		(keep_end_layers yes)
		(zone_layer_connections)
		(teardrops
			(best_length_ratio 0.4)
			(max_length 1)
			(best_width_ratio 0.9)
			(max_width 2)
			(curved_edges yes)
			(filter_ratio 0.9)
			(enabled yes)
			(allow_two_segments yes)
			(prefer_zone_connections yes)
		)
		(net 627)
	)
	(segment
		(start 112.9 150.56)
		(end 112.9 151.51)
		(width 0.125)
		(layer "B.Cu")
		(net 627)
	)
	(segment
		(start 113.401 150.059)
		(end 112.9 150.56)
		(width 0.125)
		(layer "B.Cu")
		(net 627)
	)
	(segment
		(start 113.401 149.048)
		(end 113.401 150.059)
		(width 0.125)
		(layer "B.Cu")
		(net 627)
	)
	(segment
		(start 113.901 143.93)
		(end 113.851 143.88)
		(width 0.125)
		(layer "F.Cu")
		(net 628)
	)
	(segment
		(start 113.901 143.93)
		(end 113.951 143.88)
		(width 0.125)
		(layer "F.Cu")
		(net 628)
	)
	(segment
		(start 113.951 143.88)
		(end 114.4 143.88)
		(width 0.125)
		(layer "F.Cu")
		(net 628)
	)
	(segment
		(start 113.851 143.88)
		(end 113.4 143.88)
		(width 0.125)
		(layer "F.Cu")
		(net 628)
	)
	(via
		(at 113.901 143.93)
		(size 0.45)
		(drill 0.1)
		(layers "F.Cu" "B.Cu")
		(remove_unused_layers yes)
		(keep_end_layers yes)
		(zone_layer_connections)
		(teardrops
			(best_length_ratio 0.4)
			(max_length 1)
			(best_width_ratio 0.9)
			(max_width 2)
			(curved_edges yes)
			(filter_ratio 0.9)
			(enabled yes)
			(allow_two_segments yes)
			(prefer_zone_connections yes)
		)
		(net 628)
	)
	(segment
		(start 113.901 143.93)
		(end 113.901 145.673)
		(width 0.125)
		(layer "B.Cu")
		(net 628)
	)
	(segment
		(start 121.838 148.109)
		(end 121.879 148.15)
		(width 0.125)
		(layer "B.Cu")
		(net 629)
	)
	(segment
		(start 123.18 148.15)
		(end 123.53 147.8)
		(width 0.125)
		(layer "B.Cu")
		(net 629)
	)
	(segment
		(start 123.53 147.8)
		(end 124.222 147.8)
		(width 0.125)
		(layer "B.Cu")
		(net 629)
	)
	(segment
		(start 121.879 148.15)
		(end 123.18 148.15)
		(width 0.125)
		(layer "B.Cu")
		(net 629)
	)
	(segment
		(start 197.656306 135.059802)
		(end 197.258912 134.662408)
		(width 0.125)
		(layer "B.Cu")
		(net 630)
	)
	(segment
		(start 198.412911 135.321432)
		(end 198.151281 135.059802)
		(width 0.125)
		(layer "B.Cu")
		(net 630)
	)
	(segment
		(start 198.151281 135.059802)
		(end 197.656306 135.059802)
		(width 0.125)
		(layer "B.Cu")
		(net 630)
	)
	(segment
		(start 121.25 150.33)
		(end 121.25 149.96)
		(width 0.125)
		(layer "B.Cu")
		(net 631)
	)
	(segment
		(start 121.25 149.96)
		(end 120.9 149.61)
		(width 0.125)
		(layer "B.Cu")
		(net 631)
	)
	(segment
		(start 120.9 149.61)
		(end 120.9 149.048)
		(width 0.125)
		(layer "B.Cu")
		(net 631)
	)
	(segment
		(start 197.258205 133.335169)
		(end 197.826719 132.766655)
		(width 0.125)
		(layer "B.Cu")
		(net 632)
	)
	(segment
		(start 197.826719 132.766655)
		(end 198.263711 132.766655)
		(width 0.125)
		(layer "B.Cu")
		(net 632)
	)
	(segment
		(start 132.587 84.31)
		(end 133.945 84.31)
		(width 0.125)
		(layer "F.Cu")
		(net 633)
	)
	(segment
		(start 133.945 83.310001)
		(end 133.945 84.31)
		(width 0.125)
		(layer "F.Cu")
		(net 633)
	)
	(segment
		(start 131.398 83.112001)
		(end 131.9 82.610001)
		(width 0.125)
		(layer "F.Cu")
		(net 634)
	)
	(segment
		(start 131.9 82.610001)
		(end 131.9 82.24)
		(width 0.125)
		(layer "F.Cu")
		(net 634)
	)
	(segment
		(start 131.398 83.622)
		(end 131.398 83.112001)
		(width 0.125)
		(layer "F.Cu")
		(net 634)
	)
	(segment
		(start 131.898999 83.123501)
		(end 132.1375 82.885001)
		(width 0.125)
		(layer "F.Cu")
		(net 635)
	)
	(segment
		(start 132.1375 82.885001)
		(end 132.65 82.885002)
		(width 0.125)
		(layer "F.Cu")
		(net 635)
	)
	(segment
		(start 131.899 83.622001)
		(end 131.898999 83.123501)
		(width 0.125)
		(layer "F.Cu")
		(net 635)
	)
	(segment
		(start 132.65 82.885002)
		(end 132.9 82.635001)
		(width 0.125)
		(layer "F.Cu")
		(net 635)
	)
	(segment
		(start 132.9 82.635001)
		(end 132.9 82.240001)
		(width 0.125)
		(layer "F.Cu")
		(net 635)
	)
	(segment
		(start 130.4 83.085001)
		(end 129.9 82.585001)
		(width 0.125)
		(layer "F.Cu")
		(net 636)
	)
	(segment
		(start 129.9 82.585001)
		(end 129.899999 82.24)
		(width 0.125)
		(layer "F.Cu")
		(net 636)
	)
	(segment
		(start 130.4 83.622)
		(end 130.4 83.085001)
		(width 0.125)
		(layer "F.Cu")
		(net 636)
	)
	(segment
		(start 128.274999 83.035001)
		(end 127.9 82.660001)
		(width 0.125)
		(layer "F.Cu")
		(net 637)
	)
	(segment
		(start 129.4 83.135001)
		(end 129.3 83.035001)
		(width 0.125)
		(layer "F.Cu")
		(net 637)
	)
	(segment
		(start 127.9 82.660001)
		(end 127.9 82.24)
		(width 0.125)
		(layer "F.Cu")
		(net 637)
	)
	(segment
		(start 129.4 83.622001)
		(end 129.4 83.135001)
		(width 0.125)
		(layer "F.Cu")
		(net 637)
	)
	(segment
		(start 129.3 83.035001)
		(end 128.274999 83.035001)
		(width 0.125)
		(layer "F.Cu")
		(net 637)
	)
	(segment
		(start 129.9 83.240001)
		(end 128.9 82.240001)
		(width 0.125)
		(layer "F.Cu")
		(net 638)
	)
	(segment
		(start 129.9 83.622)
		(end 129.9 83.240001)
		(width 0.125)
		(layer "F.Cu")
		(net 638)
	)
	(segment
		(start 128.712 84.310001)
		(end 128.225 84.310001)
		(width 0.125)
		(layer "F.Cu")
		(net 639)
	)
	(segment
		(start 128.05 84.135001)
		(end 128.05 83.71)
		(width 0.125)
		(layer "F.Cu")
		(net 639)
	)
	(segment
		(start 127.4 83.06)
		(end 126.905 83.06)
		(width 0.125)
		(layer "F.Cu")
		(net 639)
	)
	(segment
		(start 128.225 84.310001)
		(end 128.05 84.135001)
		(width 0.125)
		(layer "F.Cu")
		(net 639)
	)
	(segment
		(start 128.05 83.71)
		(end 127.4 83.06)
		(width 0.125)
		(layer "F.Cu")
		(net 639)
	)
	(segment
		(start 127.350001 84.060001)
		(end 126.905001 84.060001)
		(width 0.125)
		(layer "F.Cu")
		(net 640)
	)
	(segment
		(start 128.712 84.81)
		(end 128.100001 84.809999)
		(width 0.125)
		(layer "F.Cu")
		(net 640)
	)
	(segment
		(start 128.100001 84.809999)
		(end 127.350001 84.060001)
		(width 0.125)
		(layer "F.Cu")
		(net 640)
	)
	(segment
		(start 127.8 85.310001)
		(end 127.55 85.060001)
		(width 0.125)
		(layer "F.Cu")
		(net 641)
	)
	(segment
		(start 128.711999 85.310001)
		(end 127.8 85.310001)
		(width 0.125)
		(layer "F.Cu")
		(net 641)
	)
	(segment
		(start 127.55 85.060001)
		(end 126.905 85.060001)
		(width 0.125)
		(layer "F.Cu")
		(net 641)
	)
	(segment
		(start 127.549999 86.060001)
		(end 126.905 86.060001)
		(width 0.125)
		(layer "F.Cu")
		(net 642)
	)
	(segment
		(start 128.712 85.808001)
		(end 127.801999 85.808)
		(width 0.125)
		(layer "F.Cu")
		(net 642)
	)
	(segment
		(start 127.801999 85.808)
		(end 127.549999 86.060001)
		(width 0.125)
		(layer "F.Cu")
		(net 642)
	)
	(segment
		(start 128.712 86.308002)
		(end 128.127 86.308001)
		(width 0.125)
		(layer "F.Cu")
		(net 643)
	)
	(segment
		(start 127.375 87.060001)
		(end 126.905 87.06)
		(width 0.125)
		(layer "F.Cu")
		(net 643)
	)
	(segment
		(start 128.127 86.308001)
		(end 127.375 87.060001)
		(width 0.125)
		(layer "F.Cu")
		(net 643)
	)
	(segment
		(start 128.226001 86.809001)
		(end 128.049999 86.985001)
		(width 0.125)
		(layer "F.Cu")
		(net 644)
	)
	(segment
		(start 128.05 87.41)
		(end 127.4 88.06)
		(width 0.125)
		(layer "F.Cu")
		(net 644)
	)
	(segment
		(start 128.712 86.809001)
		(end 128.226001 86.809001)
		(width 0.125)
		(layer "F.Cu")
		(net 644)
	)
	(segment
		(start 128.049999 86.985001)
		(end 128.05 87.41)
		(width 0.125)
		(layer "F.Cu")
		(net 644)
	)
	(segment
		(start 127.4 88.06)
		(end 126.905 88.06)
		(width 0.125)
		(layer "F.Cu")
		(net 644)
	)
	(segment
		(start 129.15 88.335001)
		(end 129.15 89.03)
		(width 0.125)
		(layer "F.Cu")
		(net 645)
	)
	(segment
		(start 129.4 88.085)
		(end 129.15 88.335001)
		(width 0.125)
		(layer "F.Cu")
		(net 645)
	)
	(segment
		(start 129.399999 87.497001)
		(end 129.4 88.085)
		(width 0.125)
		(layer "F.Cu")
		(net 645)
	)
	(segment
		(start 130.150001 88.335001)
		(end 130.15 89.03)
		(width 0.125)
		(layer "F.Cu")
		(net 646)
	)
	(segment
		(start 129.9 88.085001)
		(end 130.150001 88.335001)
		(width 0.125)
		(layer "F.Cu")
		(net 646)
	)
	(segment
		(start 129.899999 87.497001)
		(end 129.9 88.085001)
		(width 0.125)
		(layer "F.Cu")
		(net 646)
	)
	(segment
		(start 142.52 136.33)
		(end 143.19 137)
		(width 0.125)
		(layer "F.Cu")
		(net 647)
	)
	(segment
		(start 142.52 135.88)
		(end 142.52 136.33)
		(width 0.125)
		(layer "F.Cu")
		(net 647)
	)
	(segment
		(start 141.89 144.05)
		(end 141.485 144.05)
		(width 0.125)
		(layer "F.Cu")
		(net 648)
	)
	(segment
		(start 141.485 144.05)
		(end 141.307 144.228)
		(width 0.125)
		(layer "F.Cu")
		(net 648)
	)
	(segment
		(start 141.307 144.228)
		(end 141.307 149.888)
		(width 0.125)
		(layer "F.Cu")
		(net 648)
	)
	(segment
		(start 141.307 149.888)
		(end 141.89 150.471)
		(width 0.125)
		(layer "F.Cu")
		(net 648)
	)
	(segment
		(start 141.89 150.471)
		(end 141.89 151.409)
		(width 0.125)
		(layer "F.Cu")
		(net 648)
	)
	(segment
		(start 142.85 144.05)
		(end 143.21 144.05)
		(width 0.125)
		(layer "F.Cu")
		(net 649)
	)
	(segment
		(start 143.32 143.322165)
		(end 143.1 143.102165)
		(width 0.125)
		(layer "F.Cu")
		(net 649)
	)
	(segment
		(start 143.32 143.94)
		(end 143.32 143.322165)
		(width 0.125)
		(layer "F.Cu")
		(net 649)
	)
	(segment
		(start 143.21 144.05)
		(end 143.32 143.94)
		(width 0.125)
		(layer "F.Cu")
		(net 649)
	)
	(via
		(at 143.1 143.102165)
		(size 0.45)
		(drill 0.1)
		(layers "F.Cu" "B.Cu")
		(remove_unused_layers yes)
		(keep_end_layers yes)
		(zone_layer_connections "In5.Cu")
		(teardrops
			(best_length_ratio 0.4)
			(max_length 1)
			(best_width_ratio 0.9)
			(max_width 2)
			(curved_edges yes)
			(filter_ratio 0.9)
			(enabled yes)
			(allow_two_segments yes)
			(prefer_zone_connections yes)
		)
		(net 649)
	)
	(via
		(at 148.45 137.86)
		(size 0.45)
		(drill 0.1)
		(layers "F.Cu" "B.Cu")
		(remove_unused_layers yes)
		(keep_end_layers yes)
		(zone_layer_connections "In5.Cu")
		(teardrops
			(best_length_ratio 0.4)
			(max_length 1)
			(best_width_ratio 0.9)
			(max_width 2)
			(curved_edges yes)
			(filter_ratio 0.9)
			(enabled yes)
			(allow_two_segments yes)
			(prefer_zone_connections yes)
		)
		(net 649)
	)
	(segment
		(start 148.45 137.86)
		(end 147.9375 138.3725)
		(width 0.125)
		(layer "In5.Cu")
		(net 649)
	)
	(segment
		(start 147.9375 138.3725)
		(end 147.9375 141.06193)
		(width 0.125)
		(layer "In5.Cu")
		(net 649)
	)
	(segment
		(start 147.9375 141.06193)
		(end 147.62943 141.37)
		(width 0.125)
		(layer "In5.Cu")
		(net 649)
	)
	(segment
		(start 144.832165 141.37)
		(end 143.1 143.102165)
		(width 0.125)
		(layer "In5.Cu")
		(net 649)
	)
	(segment
		(start 147.62943 141.37)
		(end 144.832165 141.37)
		(width 0.125)
		(layer "In5.Cu")
		(net 649)
	)
	(segment
		(start 141.89 147.11)
		(end 141.89 145.05)
		(width 0.125)
		(layer "F.Cu")
		(net 650)
	)
	(segment
		(start 143.38 145.05)
		(end 142.85 145.05)
		(width 0.125)
		(layer "F.Cu")
		(net 651)
	)
	(segment
		(start 143.85 144.58)
		(end 143.38 145.05)
		(width 0.125)
		(layer "F.Cu")
		(net 651)
	)
	(segment
		(start 143.85 143.11)
		(end 143.85 144.58)
		(width 0.125)
		(layer "F.Cu")
		(net 651)
	)
	(via
		(at 143.85 143.11)
		(size 0.45)
		(drill 0.1)
		(layers "F.Cu" "B.Cu")
		(remove_unused_layers yes)
		(keep_end_layers yes)
		(zone_layer_connections "In5.Cu")
		(teardrops
			(best_length_ratio 0.4)
			(max_length 1)
			(best_width_ratio 0.9)
			(max_width 2)
			(curved_edges yes)
			(filter_ratio 0.9)
			(enabled yes)
			(allow_two_segments yes)
			(prefer_zone_connections yes)
		)
		(net 651)
	)
	(via
		(at 148.45 138.86)
		(size 0.45)
		(drill 0.1)
		(layers "F.Cu" "B.Cu")
		(remove_unused_layers yes)
		(keep_end_layers yes)
		(zone_layer_connections "In5.Cu")
		(teardrops
			(best_length_ratio 0.4)
			(max_length 1)
			(best_width_ratio 0.9)
			(max_width 2)
			(curved_edges yes)
			(filter_ratio 0.9)
			(enabled yes)
			(allow_two_segments yes)
			(prefer_zone_connections yes)
		)
		(net 651)
	)
	(segment
		(start 143.85 143.11)
		(end 144.6125 142.3475)
		(width 0.125)
		(layer "In5.Cu")
		(net 651)
	)
	(segment
		(start 148.45 139.2)
		(end 148.45 138.86)
		(width 0.125)
		(layer "In5.Cu")
		(net 651)
	)
	(segment
		(start 148.9375 142.06193)
		(end 148.9375 139.6875)
		(width 0.125)
		(layer "In5.Cu")
		(net 651)
	)
	(segment
		(start 144.6125 142.3475)
		(end 148.65193 142.3475)
		(width 0.125)
		(layer "In5.Cu")
		(net 651)
	)
	(segment
		(start 148.9375 139.6875)
		(end 148.45 139.2)
		(width 0.125)
		(layer "In5.Cu")
		(net 651)
	)
	(segment
		(start 148.65193 142.3475)
		(end 148.9375 142.06193)
		(width 0.125)
		(layer "In5.Cu")
		(net 651)
	)
	(via
		(at 155.45 139.86)
		(size 0.45)
		(drill 0.1)
		(layers "F.Cu" "B.Cu")
		(remove_unused_layers yes)
		(keep_end_layers yes)
		(zone_layer_connections)
		(teardrops
			(best_length_ratio 0.4)
			(max_length 1)
			(best_width_ratio 0.9)
			(max_width 2)
			(curved_edges yes)
			(filter_ratio 0.9)
			(enabled yes)
			(allow_two_segments yes)
			(prefer_zone_connections yes)
		)
		(net 652)
	)
	(segment
		(start 155.95 140.36)
		(end 157.42 140.36)
		(width 0.125)
		(layer "B.Cu")
		(net 652)
	)
	(segment
		(start 156.21 138.36)
		(end 155.96 138.61)
		(width 0.125)
		(layer "B.Cu")
		(net 652)
	)
	(segment
		(start 155.96 139.35)
		(end 155.45 139.86)
		(width 0.125)
		(layer "B.Cu")
		(net 652)
	)
	(segment
		(start 157.42 138.36)
		(end 156.21 138.36)
		(width 0.125)
		(layer "B.Cu")
		(net 652)
	)
	(segment
		(start 155.45 139.86)
		(end 155.95 140.36)
		(width 0.125)
		(layer "B.Cu")
		(net 652)
	)
	(segment
		(start 155.96 138.61)
		(end 155.96 139.35)
		(width 0.125)
		(layer "B.Cu")
		(net 652)
	)
	(via
		(at 146.45 140.86)
		(size 0.45)
		(drill 0.1)
		(layers "F.Cu" "B.Cu")
		(remove_unused_layers yes)
		(keep_end_layers yes)
		(zone_layer_connections)
		(teardrops
			(best_length_ratio 0.4)
			(max_length 1)
			(best_width_ratio 0.9)
			(max_width 2)
			(curved_edges yes)
			(filter_ratio 0.9)
			(enabled yes)
			(allow_two_segments yes)
			(prefer_zone_connections yes)
		)
		(net 653)
	)
	(segment
		(start 146.3 140.37)
		(end 145.57 140.37)
		(width 0.125)
		(layer "B.Cu")
		(net 653)
	)
	(segment
		(start 145.26 140.06)
		(end 144.73 140.06)
		(width 0.125)
		(layer "B.Cu")
		(net 653)
	)
	(segment
		(start 146.45 140.86)
		(end 146.45 140.52)
		(width 0.125)
		(layer "B.Cu")
		(net 653)
	)
	(segment
		(start 145.57 140.37)
		(end 145.26 140.06)
		(width 0.125)
		(layer "B.Cu")
		(net 653)
	)
	(segment
		(start 146.45 140.52)
		(end 146.3 140.37)
		(width 0.125)
		(layer "B.Cu")
		(net 653)
	)
	(via
		(at 148.45 140.86)
		(size 0.45)
		(drill 0.1)
		(layers "F.Cu" "B.Cu")
		(remove_unused_layers yes)
		(keep_end_layers yes)
		(zone_layer_connections)
		(teardrops
			(best_length_ratio 0.4)
			(max_length 1)
			(best_width_ratio 0.9)
			(max_width 2)
			(curved_edges yes)
			(filter_ratio 0.9)
			(enabled yes)
			(allow_two_segments yes)
			(prefer_zone_connections yes)
		)
		(net 654)
	)
	(segment
		(start 146.18 141.37)
		(end 145.87 141.06)
		(width 0.125)
		(layer "B.Cu")
		(net 654)
	)
	(segment
		(start 145.87 141.06)
		(end 144.73 141.06)
		(width 0.125)
		(layer "B.Cu")
		(net 654)
	)
	(segment
		(start 148.18 140.86)
		(end 147.67 141.37)
		(width 0.125)
		(layer "B.Cu")
		(net 654)
	)
	(segment
		(start 148.45 140.86)
		(end 148.18 140.86)
		(width 0.125)
		(layer "B.Cu")
		(net 654)
	)
	(segment
		(start 147.67 141.37)
		(end 146.18 141.37)
		(width 0.125)
		(layer "B.Cu")
		(net 654)
	)
	(via
		(at 152.45 140.86)
		(size 0.45)
		(drill 0.1)
		(layers "F.Cu" "B.Cu")
		(remove_unused_layers yes)
		(keep_end_layers yes)
		(zone_layer_connections)
		(teardrops
			(best_length_ratio 0.4)
			(max_length 1)
			(best_width_ratio 0.9)
			(max_width 2)
			(curved_edges yes)
			(filter_ratio 0.9)
			(enabled yes)
			(allow_two_segments yes)
			(prefer_zone_connections yes)
		)
		(net 655)
	)
	(segment
		(start 153.84 141.3)
		(end 152.89 141.3)
		(width 0.125)
		(layer "B.Cu")
		(net 655)
	)
	(segment
		(start 157.42 141.36)
		(end 153.9 141.36)
		(width 0.125)
		(layer "B.Cu")
		(net 655)
	)
	(segment
		(start 152.89 141.3)
		(end 152.45 140.86)
		(width 0.125)
		(layer "B.Cu")
		(net 655)
	)
	(segment
		(start 157.42 142.36)
		(end 157.42 141.36)
		(width 0.125)
		(layer "B.Cu")
		(net 655)
	)
	(segment
		(start 153.9 141.36)
		(end 153.84 141.3)
		(width 0.125)
		(layer "B.Cu")
		(net 655)
	)
	(via
		(at 150.45 139.86)
		(size 0.45)
		(drill 0.1)
		(layers "F.Cu" "B.Cu")
		(remove_unused_layers yes)
		(keep_end_layers yes)
		(zone_layer_connections)
		(teardrops
			(best_length_ratio 0.4)
			(max_length 1)
			(best_width_ratio 0.9)
			(max_width 2)
			(curved_edges yes)
			(filter_ratio 0.9)
			(enabled yes)
			(allow_two_segments yes)
			(prefer_zone_connections yes)
		)
		(net 656)
	)
	(segment
		(start 147.21 140.35)
		(end 149.96 140.35)
		(width 0.125)
		(layer "B.Cu")
		(net 656)
	)
	(segment
		(start 145.25 138.06)
		(end 145.6 138.41)
		(width 0.125)
		(layer "B.Cu")
		(net 656)
	)
	(segment
		(start 145.6 138.75)
		(end 146.21 139.36)
		(width 0.125)
		(layer "B.Cu")
		(net 656)
	)
	(segment
		(start 146.95 139.62)
		(end 146.95 140.09)
		(width 0.125)
		(layer "B.Cu")
		(net 656)
	)
	(segment
		(start 144.73 138.06)
		(end 144.73 137.06)
		(width 0.125)
		(layer "B.Cu")
		(net 656)
	)
	(segment
		(start 146.95 140.09)
		(end 147.21 140.35)
		(width 0.125)
		(layer "B.Cu")
		(net 656)
	)
	(segment
		(start 145.6 138.41)
		(end 145.6 138.75)
		(width 0.125)
		(layer "B.Cu")
		(net 656)
	)
	(segment
		(start 149.96 140.35)
		(end 150.45 139.86)
		(width 0.125)
		(layer "B.Cu")
		(net 656)
	)
	(segment
		(start 146.21 139.36)
		(end 146.69 139.36)
		(width 0.125)
		(layer "B.Cu")
		(net 656)
	)
	(segment
		(start 146.69 139.36)
		(end 146.95 139.62)
		(width 0.125)
		(layer "B.Cu")
		(net 656)
	)
	(segment
		(start 144.73 138.06)
		(end 145.25 138.06)
		(width 0.125)
		(layer "B.Cu")
		(net 656)
	)
	(via
		(at 156.45 138.86)
		(size 0.45)
		(drill 0.1)
		(layers "F.Cu" "B.Cu")
		(remove_unused_layers yes)
		(keep_end_layers yes)
		(zone_layer_connections)
		(teardrops
			(best_length_ratio 0.4)
			(max_length 1)
			(best_width_ratio 0.9)
			(max_width 2)
			(curved_edges yes)
			(filter_ratio 0.9)
			(enabled yes)
			(allow_two_segments yes)
			(prefer_zone_connections yes)
		)
		(net 657)
	)
	(segment
		(start 156.95 139.36)
		(end 156.45 138.86)
		(width 0.125)
		(layer "B.Cu")
		(net 657)
	)
	(segment
		(start 157.42 139.36)
		(end 156.95 139.36)
		(width 0.125)
		(layer "B.Cu")
		(net 657)
	)
	(via
		(at 146.45 139.86)
		(size 0.45)
		(drill 0.1)
		(layers "F.Cu" "B.Cu")
		(remove_unused_layers yes)
		(keep_end_layers yes)
		(zone_layer_connections)
		(teardrops
			(best_length_ratio 0.4)
			(max_length 1)
			(best_width_ratio 0.9)
			(max_width 2)
			(curved_edges yes)
			(filter_ratio 0.9)
			(enabled yes)
			(allow_two_segments yes)
			(prefer_zone_connections yes)
		)
		(net 658)
	)
	(segment
		(start 146.45 139.86)
		(end 146.04 139.86)
		(width 0.125)
		(layer "B.Cu")
		(net 658)
	)
	(segment
		(start 146.04 139.86)
		(end 145.24 139.06)
		(width 0.125)
		(layer "B.Cu")
		(net 658)
	)
	(segment
		(start 145.24 139.06)
		(end 144.73 139.06)
		(width 0.125)
		(layer "B.Cu")
		(net 658)
	)
	(via
		(at 148.45 136.86)
		(size 0.45)
		(drill 0.1)
		(layers "F.Cu" "B.Cu")
		(remove_unused_layers yes)
		(keep_end_layers yes)
		(zone_layer_connections)
		(teardrops
			(best_length_ratio 0.4)
			(max_length 1)
			(best_width_ratio 0.9)
			(max_width 2)
			(curved_edges yes)
			(filter_ratio 0.9)
			(enabled yes)
			(allow_two_segments yes)
			(prefer_zone_connections yes)
		)
		(net 659)
	)
	(segment
		(start 147.43 136.06)
		(end 148 136.06)
		(width 0.125)
		(layer "B.Cu")
		(net 659)
	)
	(segment
		(start 148.45 136.51)
		(end 148.45 136.86)
		(width 0.125)
		(layer "B.Cu")
		(net 659)
	)
	(segment
		(start 148 136.06)
		(end 148.45 136.51)
		(width 0.125)
		(layer "B.Cu")
		(net 659)
	)
	(via
		(at 148.45 134.86)
		(size 0.45)
		(drill 0.1)
		(layers "F.Cu" "B.Cu")
		(remove_unused_layers yes)
		(keep_end_layers yes)
		(zone_layer_connections)
		(teardrops
			(best_length_ratio 0.4)
			(max_length 1)
			(best_width_ratio 0.9)
			(max_width 2)
			(curved_edges yes)
			(filter_ratio 0.9)
			(enabled yes)
			(allow_two_segments yes)
			(prefer_zone_connections yes)
		)
		(net 660)
	)
	(segment
		(start 148.87 134.34)
		(end 148.87 134.75)
		(width 0.125)
		(layer "B.Cu")
		(net 660)
	)
	(segment
		(start 148.76 134.86)
		(end 148.45 134.86)
		(width 0.125)
		(layer "B.Cu")
		(net 660)
	)
	(segment
		(start 149.34 133.87)
		(end 148.87 134.34)
		(width 0.125)
		(layer "B.Cu")
		(net 660)
	)
	(segment
		(start 148.87 134.75)
		(end 148.76 134.86)
		(width 0.125)
		(layer "B.Cu")
		(net 660)
	)
	(segment
		(start 145.45 138.86)
		(end 145.08 138.86)
		(width 0.125)
		(layer "F.Cu")
		(net 661)
	)
	(segment
		(start 144.1 133.14)
		(end 143.84 132.88)
		(width 0.125)
		(layer "F.Cu")
		(net 661)
	)
	(segment
		(start 143.84 132.88)
		(end 143.48 132.88)
		(width 0.125)
		(layer "F.Cu")
		(net 661)
	)
	(segment
		(start 145.08 138.86)
		(end 144.77 138.55)
		(width 0.125)
		(layer "F.Cu")
		(net 661)
	)
	(segment
		(start 144.77 135.03)
		(end 144.1 134.36)
		(width 0.125)
		(layer "F.Cu")
		(net 661)
	)
	(segment
		(start 144.1 134.36)
		(end 144.1 133.14)
		(width 0.125)
		(layer "F.Cu")
		(net 661)
	)
	(segment
		(start 144.77 138.55)
		(end 144.77 135.03)
		(width 0.125)
		(layer "F.Cu")
		(net 661)
	)
	(via
		(at 149.45 140.86)
		(size 0.45)
		(drill 0.1)
		(layers "F.Cu" "B.Cu")
		(remove_unused_layers yes)
		(keep_end_layers yes)
		(zone_layer_connections)
		(teardrops
			(best_length_ratio 0.4)
			(max_length 1)
			(best_width_ratio 0.9)
			(max_width 2)
			(curved_edges yes)
			(filter_ratio 0.9)
			(enabled yes)
			(allow_two_segments yes)
			(prefer_zone_connections yes)
		)
		(net 662)
	)
	(segment
		(start 146.17 142.31)
		(end 145.92 142.06)
		(width 0.125)
		(layer "B.Cu")
		(net 662)
	)
	(segment
		(start 147.9175 141.579294)
		(end 147.9175 142.0625)
		(width 0.125)
		(layer "B.Cu")
		(net 662)
	)
	(segment
		(start 148.196794 141.3)
		(end 147.9175 141.579294)
		(width 0.125)
		(layer "B.Cu")
		(net 662)
	)
	(segment
		(start 149.45 140.86)
		(end 149.01 141.3)
		(width 0.125)
		(layer "B.Cu")
		(net 662)
	)
	(segment
		(start 147.9175 142.0625)
		(end 147.67 142.31)
		(width 0.125)
		(layer "B.Cu")
		(net 662)
	)
	(segment
		(start 149.01 141.3)
		(end 148.196794 141.3)
		(width 0.125)
		(layer "B.Cu")
		(net 662)
	)
	(segment
		(start 145.92 142.06)
		(end 144.73 142.06)
		(width 0.125)
		(layer "B.Cu")
		(net 662)
	)
	(segment
		(start 147.67 142.31)
		(end 146.17 142.31)
		(width 0.125)
		(layer "B.Cu")
		(net 662)
	)
	(segment
		(start 143.48 133.88)
		(end 143.48 134.88)
		(width 0.125)
		(layer "F.Cu")
		(net 663)
	)
	(segment
		(start 145.45 139.86)
		(end 144.38 138.79)
		(width 0.125)
		(layer "F.Cu")
		(net 663)
	)
	(segment
		(start 144.06 134.88)
		(end 143.48 134.88)
		(width 0.125)
		(layer "F.Cu")
		(net 663)
	)
	(segment
		(start 144.38 135.2)
		(end 144.06 134.88)
		(width 0.125)
		(layer "F.Cu")
		(net 663)
	)
	(segment
		(start 144.38 138.79)
		(end 144.38 135.2)
		(width 0.125)
		(layer "F.Cu")
		(net 663)
	)
	(segment
		(start 153.14 143.17)
		(end 153.45 142.86)
		(width 0.16)
		(layer "F.Cu")
		(net 664)
	)
	(segment
		(start 153.14 146.77)
		(end 153.14 143.17)
		(width 0.16)
		(layer "F.Cu")
		(net 664)
	)
	(segment
		(start 153.33 146.96)
		(end 153.14 146.77)
		(width 0.16)
		(layer "F.Cu")
		(net 664)
	)
	(segment
		(start 152.76 146.77)
		(end 152.76 143.17)
		(width 0.16)
		(layer "F.Cu")
		(net 665)
	)
	(segment
		(start 152.76 143.17)
		(end 152.45 142.86)
		(width 0.16)
		(layer "F.Cu")
		(net 665)
	)
	(segment
		(start 152.57 146.96)
		(end 152.76 146.77)
		(width 0.16)
		(layer "F.Cu")
		(net 665)
	)
	(segment
		(start 147.14 143.17)
		(end 147.45 142.86)
		(width 0.16)
		(layer "F.Cu")
		(net 666)
	)
	(segment
		(start 147.14 146.77)
		(end 147.14 143.17)
		(width 0.16)
		(layer "F.Cu")
		(net 666)
	)
	(segment
		(start 147.33 146.96)
		(end 147.14 146.77)
		(width 0.16)
		(layer "F.Cu")
		(net 666)
	)
	(segment
		(start 149.76 143.17)
		(end 149.45 142.86)
		(width 0.16)
		(layer "F.Cu")
		(net 667)
	)
	(segment
		(start 149.57 146.96)
		(end 149.76 146.77)
		(width 0.16)
		(layer "F.Cu")
		(net 667)
	)
	(segment
		(start 149.76 146.77)
		(end 149.76 143.17)
		(width 0.16)
		(layer "F.Cu")
		(net 667)
	)
	(segment
		(start 124.36 136.33)
		(end 125.03 137)
		(width 0.125)
		(layer "F.Cu")
		(net 668)
	)
	(segment
		(start 124.36 135.88)
		(end 124.36 136.33)
		(width 0.125)
		(layer "F.Cu")
		(net 668)
	)
	(segment
		(start 123.73 144.05)
		(end 123.33 144.05)
		(width 0.125)
		(layer "F.Cu")
		(net 669)
	)
	(segment
		(start 123.33 144.05)
		(end 123.15 144.23)
		(width 0.125)
		(layer "F.Cu")
		(net 669)
	)
	(segment
		(start 123.733 150.473)
		(end 123.733 151.411)
		(width 0.125)
		(layer "F.Cu")
		(net 669)
	)
	(segment
		(start 123.15 144.23)
		(end 123.15 149.89)
		(width 0.125)
		(layer "F.Cu")
		(net 669)
	)
	(segment
		(start 123.15 149.89)
		(end 123.733 150.473)
		(width 0.125)
		(layer "F.Cu")
		(net 669)
	)
	(segment
		(start 125.05 144.05)
		(end 125.16 143.94)
		(width 0.125)
		(layer "F.Cu")
		(net 670)
	)
	(segment
		(start 125.16 143.322165)
		(end 124.94 143.102165)
		(width 0.125)
		(layer "F.Cu")
		(net 670)
	)
	(segment
		(start 125.16 143.94)
		(end 125.16 143.322165)
		(width 0.125)
		(layer "F.Cu")
		(net 670)
	)
	(segment
		(start 124.69 144.05)
		(end 125.05 144.05)
		(width 0.125)
		(layer "F.Cu")
		(net 670)
	)
	(via
		(at 130.29 137.86)
		(size 0.45)
		(drill 0.1)
		(layers "F.Cu" "B.Cu")
		(remove_unused_layers yes)
		(keep_end_layers yes)
		(zone_layer_connections "In5.Cu")
		(teardrops
			(best_length_ratio 0.4)
			(max_length 1)
			(best_width_ratio 0.9)
			(max_width 2)
			(curved_edges yes)
			(filter_ratio 0.9)
			(enabled yes)
			(allow_two_segments yes)
			(prefer_zone_connections yes)
		)
		(net 670)
	)
	(via
		(at 124.94 143.102165)
		(size 0.45)
		(drill 0.1)
		(layers "F.Cu" "B.Cu")
		(remove_unused_layers yes)
		(keep_end_layers yes)
		(zone_layer_connections "In5.Cu")
		(teardrops
			(best_length_ratio 0.4)
			(max_length 1)
			(best_width_ratio 0.9)
			(max_width 2)
			(curved_edges yes)
			(filter_ratio 0.9)
			(enabled yes)
			(allow_two_segments yes)
			(prefer_zone_connections yes)
		)
		(net 670)
	)
	(segment
		(start 126.672165 141.37)
		(end 124.94 143.102165)
		(width 0.125)
		(layer "In5.Cu")
		(net 670)
	)
	(segment
		(start 129.7775 141.06193)
		(end 129.46943 141.37)
		(width 0.125)
		(layer "In5.Cu")
		(net 670)
	)
	(segment
		(start 129.46943 141.37)
		(end 126.672165 141.37)
		(width 0.125)
		(layer "In5.Cu")
		(net 670)
	)
	(segment
		(start 129.7775 138.3725)
		(end 129.7775 141.06193)
		(width 0.125)
		(layer "In5.Cu")
		(net 670)
	)
	(segment
		(start 130.29 137.86)
		(end 129.7775 138.3725)
		(width 0.125)
		(layer "In5.Cu")
		(net 670)
	)
	(segment
		(start 123.733 147.112)
		(end 123.733 145.053)
		(width 0.125)
		(layer "F.Cu")
		(net 671)
	)
	(segment
		(start 125.69 144.58)
		(end 125.22 145.05)
		(width 0.125)
		(layer "F.Cu")
		(net 672)
	)
	(segment
		(start 125.22 145.05)
		(end 124.69 145.05)
		(width 0.125)
		(layer "F.Cu")
		(net 672)
	)
	(segment
		(start 125.69 143.11)
		(end 125.69 144.58)
		(width 0.125)
		(layer "F.Cu")
		(net 672)
	)
	(via
		(at 130.29 138.86)
		(size 0.45)
		(drill 0.1)
		(layers "F.Cu" "B.Cu")
		(remove_unused_layers yes)
		(keep_end_layers yes)
		(zone_layer_connections "In5.Cu")
		(teardrops
			(best_length_ratio 0.4)
			(max_length 1)
			(best_width_ratio 0.9)
			(max_width 2)
			(curved_edges yes)
			(filter_ratio 0.9)
			(enabled yes)
			(allow_two_segments yes)
			(prefer_zone_connections yes)
		)
		(net 672)
	)
	(via
		(at 125.69 143.11)
		(size 0.45)
		(drill 0.1)
		(layers "F.Cu" "B.Cu")
		(remove_unused_layers yes)
		(keep_end_layers yes)
		(zone_layer_connections "In5.Cu")
		(teardrops
			(best_length_ratio 0.4)
			(max_length 1)
			(best_width_ratio 0.9)
			(max_width 2)
			(curved_edges yes)
			(filter_ratio 0.9)
			(enabled yes)
			(allow_two_segments yes)
			(prefer_zone_connections yes)
		)
		(net 672)
	)
	(segment
		(start 130.29 139.18)
		(end 130.29 138.86)
		(width 0.125)
		(layer "In5.Cu")
		(net 672)
	)
	(segment
		(start 125.69 143.11)
		(end 126.4525 142.3475)
		(width 0.125)
		(layer "In5.Cu")
		(net 672)
	)
	(segment
		(start 130.49193 142.3475)
		(end 130.7775 142.06193)
		(width 0.125)
		(layer "In5.Cu")
		(net 672)
	)
	(segment
		(start 130.7775 142.06193)
		(end 130.7775 139.6675)
		(width 0.125)
		(layer "In5.Cu")
		(net 672)
	)
	(segment
		(start 126.4525 142.3475)
		(end 130.49193 142.3475)
		(width 0.125)
		(layer "In5.Cu")
		(net 672)
	)
	(segment
		(start 130.7775 139.6675)
		(end 130.29 139.18)
		(width 0.125)
		(layer "In5.Cu")
		(net 672)
	)
	(via
		(at 137.29 139.86)
		(size 0.45)
		(drill 0.1)
		(layers "F.Cu" "B.Cu")
		(remove_unused_layers yes)
		(keep_end_layers yes)
		(zone_layer_connections)
		(teardrops
			(best_length_ratio 0.4)
			(max_length 1)
			(best_width_ratio 0.9)
			(max_width 2)
			(curved_edges yes)
			(filter_ratio 0.9)
			(enabled yes)
			(allow_two_segments yes)
			(prefer_zone_connections yes)
		)
		(net 673)
	)
	(segment
		(start 137.79 140.36)
		(end 139.26 140.36)
		(width 0.125)
		(layer "B.Cu")
		(net 673)
	)
	(segment
		(start 138.05 138.36)
		(end 137.8 138.61)
		(width 0.125)
		(layer "B.Cu")
		(net 673)
	)
	(segment
		(start 137.29 139.86)
		(end 137.79 140.36)
		(width 0.125)
		(layer "B.Cu")
		(net 673)
	)
	(segment
		(start 139.26 138.36)
		(end 138.05 138.36)
		(width 0.125)
		(layer "B.Cu")
		(net 673)
	)
	(segment
		(start 137.8 139.35)
		(end 137.29 139.86)
		(width 0.125)
		(layer "B.Cu")
		(net 673)
	)
	(segment
		(start 137.8 138.61)
		(end 137.8 139.35)
		(width 0.125)
		(layer "B.Cu")
		(net 673)
	)
	(via
		(at 128.29 140.86)
		(size 0.45)
		(drill 0.1)
		(layers "F.Cu" "B.Cu")
		(remove_unused_layers yes)
		(keep_end_layers yes)
		(zone_layer_connections)
		(teardrops
			(best_length_ratio 0.4)
			(max_length 1)
			(best_width_ratio 0.9)
			(max_width 2)
			(curved_edges yes)
			(filter_ratio 0.9)
			(enabled yes)
			(allow_two_segments yes)
			(prefer_zone_connections yes)
		)
		(net 674)
	)
	(segment
		(start 128.29 140.52)
		(end 128.14 140.37)
		(width 0.125)
		(layer "B.Cu")
		(net 674)
	)
	(segment
		(start 128.29 140.86)
		(end 128.29 140.52)
		(width 0.125)
		(layer "B.Cu")
		(net 674)
	)
	(segment
		(start 128.14 140.37)
		(end 127.41 140.37)
		(width 0.125)
		(layer "B.Cu")
		(net 674)
	)
	(segment
		(start 127.1 140.06)
		(end 126.57 140.06)
		(width 0.125)
		(layer "B.Cu")
		(net 674)
	)
	(segment
		(start 127.41 140.37)
		(end 127.1 140.06)
		(width 0.125)
		(layer "B.Cu")
		(net 674)
	)
	(via
		(at 130.29 140.86)
		(size 0.45)
		(drill 0.1)
		(layers "F.Cu" "B.Cu")
		(remove_unused_layers yes)
		(keep_end_layers yes)
		(zone_layer_connections)
		(teardrops
			(best_length_ratio 0.4)
			(max_length 1)
			(best_width_ratio 0.9)
			(max_width 2)
			(curved_edges yes)
			(filter_ratio 0.9)
			(enabled yes)
			(allow_two_segments yes)
			(prefer_zone_connections yes)
		)
		(net 675)
	)
	(segment
		(start 129.51 141.37)
		(end 128.02 141.37)
		(width 0.125)
		(layer "B.Cu")
		(net 675)
	)
	(segment
		(start 127.71 141.06)
		(end 126.57 141.06)
		(width 0.125)
		(layer "B.Cu")
		(net 675)
	)
	(segment
		(start 128.02 141.37)
		(end 127.71 141.06)
		(width 0.125)
		(layer "B.Cu")
		(net 675)
	)
	(segment
		(start 130.02 140.86)
		(end 129.51 141.37)
		(width 0.125)
		(layer "B.Cu")
		(net 675)
	)
	(segment
		(start 130.29 140.86)
		(end 130.02 140.86)
		(width 0.125)
		(layer "B.Cu")
		(net 675)
	)
	(via
		(at 134.29 140.86)
		(size 0.45)
		(drill 0.1)
		(layers "F.Cu" "B.Cu")
		(remove_unused_layers yes)
		(keep_end_layers yes)
		(zone_layer_connections)
		(teardrops
			(best_length_ratio 0.4)
			(max_length 1)
			(best_width_ratio 0.9)
			(max_width 2)
			(curved_edges yes)
			(filter_ratio 0.9)
			(enabled yes)
			(allow_two_segments yes)
			(prefer_zone_connections yes)
		)
		(net 676)
	)
	(segment
		(start 135.75 141.36)
		(end 135.69 141.3)
		(width 0.125)
		(layer "B.Cu")
		(net 676)
	)
	(segment
		(start 134.73 141.3)
		(end 134.29 140.86)
		(width 0.125)
		(layer "B.Cu")
		(net 676)
	)
	(segment
		(start 139.26 142.36)
		(end 139.26 141.36)
		(width 0.125)
		(layer "B.Cu")
		(net 676)
	)
	(segment
		(start 135.69 141.3)
		(end 134.73 141.3)
		(width 0.125)
		(layer "B.Cu")
		(net 676)
	)
	(segment
		(start 139.26 141.36)
		(end 135.75 141.36)
		(width 0.125)
		(layer "B.Cu")
		(net 676)
	)
	(via
		(at 132.29 139.86)
		(size 0.45)
		(drill 0.1)
		(layers "F.Cu" "B.Cu")
		(remove_unused_layers yes)
		(keep_end_layers yes)
		(zone_layer_connections)
		(teardrops
			(best_length_ratio 0.4)
			(max_length 1)
			(best_width_ratio 0.9)
			(max_width 2)
			(curved_edges yes)
			(filter_ratio 0.9)
			(enabled yes)
			(allow_two_segments yes)
			(prefer_zone_connections yes)
		)
		(net 677)
	)
	(segment
		(start 128.79 139.62)
		(end 128.79 140.09)
		(width 0.125)
		(layer "B.Cu")
		(net 677)
	)
	(segment
		(start 126.57 138.06)
		(end 127.09 138.06)
		(width 0.125)
		(layer "B.Cu")
		(net 677)
	)
	(segment
		(start 131.8 140.35)
		(end 132.29 139.86)
		(width 0.125)
		(layer "B.Cu")
		(net 677)
	)
	(segment
		(start 129.05 140.35)
		(end 131.8 140.35)
		(width 0.125)
		(layer "B.Cu")
		(net 677)
	)
	(segment
		(start 126.57 138.06)
		(end 126.57 137.06)
		(width 0.125)
		(layer "B.Cu")
		(net 677)
	)
	(segment
		(start 127.09 138.06)
		(end 127.44 138.41)
		(width 0.125)
		(layer "B.Cu")
		(net 677)
	)
	(segment
		(start 128.53 139.36)
		(end 128.79 139.62)
		(width 0.125)
		(layer "B.Cu")
		(net 677)
	)
	(segment
		(start 127.44 138.75)
		(end 128.05 139.36)
		(width 0.125)
		(layer "B.Cu")
		(net 677)
	)
	(segment
		(start 128.05 139.36)
		(end 128.53 139.36)
		(width 0.125)
		(layer "B.Cu")
		(net 677)
	)
	(segment
		(start 128.79 140.09)
		(end 129.05 140.35)
		(width 0.125)
		(layer "B.Cu")
		(net 677)
	)
	(segment
		(start 127.44 138.41)
		(end 127.44 138.75)
		(width 0.125)
		(layer "B.Cu")
		(net 677)
	)
	(via
		(at 138.29 138.86)
		(size 0.45)
		(drill 0.1)
		(layers "F.Cu" "B.Cu")
		(remove_unused_layers yes)
		(keep_end_layers yes)
		(zone_layer_connections)
		(teardrops
			(best_length_ratio 0.4)
			(max_length 1)
			(best_width_ratio 0.9)
			(max_width 2)
			(curved_edges yes)
			(filter_ratio 0.9)
			(enabled yes)
			(allow_two_segments yes)
			(prefer_zone_connections yes)
		)
		(net 678)
	)
	(segment
		(start 138.79 139.36)
		(end 138.29 138.86)
		(width 0.125)
		(layer "B.Cu")
		(net 678)
	)
	(segment
		(start 139.26 139.36)
		(end 138.79 139.36)
		(width 0.125)
		(layer "B.Cu")
		(net 678)
	)
	(via
		(at 128.29 139.86)
		(size 0.45)
		(drill 0.1)
		(layers "F.Cu" "B.Cu")
		(remove_unused_layers yes)
		(keep_end_layers yes)
		(zone_layer_connections)
		(teardrops
			(best_length_ratio 0.4)
			(max_length 1)
			(best_width_ratio 0.9)
			(max_width 2)
			(curved_edges yes)
			(filter_ratio 0.9)
			(enabled yes)
			(allow_two_segments yes)
			(prefer_zone_connections yes)
		)
		(net 679)
	)
	(segment
		(start 127.08 139.06)
		(end 126.57 139.06)
		(width 0.125)
		(layer "B.Cu")
		(net 679)
	)
	(segment
		(start 127.88 139.86)
		(end 127.08 139.06)
		(width 0.125)
		(layer "B.Cu")
		(net 679)
	)
	(segment
		(start 128.29 139.86)
		(end 127.88 139.86)
		(width 0.125)
		(layer "B.Cu")
		(net 679)
	)
	(via
		(at 130.29 136.86)
		(size 0.45)
		(drill 0.1)
		(layers "F.Cu" "B.Cu")
		(remove_unused_layers yes)
		(keep_end_layers yes)
		(zone_layer_connections)
		(teardrops
			(best_length_ratio 0.4)
			(max_length 1)
			(best_width_ratio 0.9)
			(max_width 2)
			(curved_edges yes)
			(filter_ratio 0.9)
			(enabled yes)
			(allow_two_segments yes)
			(prefer_zone_connections yes)
		)
		(net 680)
	)
	(segment
		(start 129.84 136.06)
		(end 130.29 136.51)
		(width 0.125)
		(layer "B.Cu")
		(net 680)
	)
	(segment
		(start 129.27 136.06)
		(end 129.84 136.06)
		(width 0.125)
		(layer "B.Cu")
		(net 680)
	)
	(segment
		(start 130.29 136.51)
		(end 130.29 136.86)
		(width 0.125)
		(layer "B.Cu")
		(net 680)
	)
	(via
		(at 130.29 134.86)
		(size 0.45)
		(drill 0.1)
		(layers "F.Cu" "B.Cu")
		(remove_unused_layers yes)
		(keep_end_layers yes)
		(zone_layer_connections)
		(teardrops
			(best_length_ratio 0.4)
			(max_length 1)
			(best_width_ratio 0.9)
			(max_width 2)
			(curved_edges yes)
			(filter_ratio 0.9)
			(enabled yes)
			(allow_two_segments yes)
			(prefer_zone_connections yes)
		)
		(net 681)
	)
	(segment
		(start 130.6 134.86)
		(end 130.29 134.86)
		(width 0.125)
		(layer "B.Cu")
		(net 681)
	)
	(segment
		(start 130.71 134.34)
		(end 130.71 134.75)
		(width 0.125)
		(layer "B.Cu")
		(net 681)
	)
	(segment
		(start 131.18 133.87)
		(end 130.71 134.34)
		(width 0.125)
		(layer "B.Cu")
		(net 681)
	)
	(segment
		(start 130.71 134.75)
		(end 130.6 134.86)
		(width 0.125)
		(layer "B.Cu")
		(net 681)
	)
	(segment
		(start 125.94 134.36)
		(end 125.94 133.14)
		(width 0.125)
		(layer "F.Cu")
		(net 682)
	)
	(segment
		(start 126.61 135.03)
		(end 125.94 134.36)
		(width 0.125)
		(layer "F.Cu")
		(net 682)
	)
	(segment
		(start 125.94 133.14)
		(end 125.68 132.88)
		(width 0.125)
		(layer "F.Cu")
		(net 682)
	)
	(segment
		(start 126.92 138.86)
		(end 126.61 138.55)
		(width 0.125)
		(layer "F.Cu")
		(net 682)
	)
	(segment
		(start 125.68 132.88)
		(end 125.32 132.88)
		(width 0.125)
		(layer "F.Cu")
		(net 682)
	)
	(segment
		(start 126.61 138.55)
		(end 126.61 135.03)
		(width 0.125)
		(layer "F.Cu")
		(net 682)
	)
	(segment
		(start 127.29 138.86)
		(end 126.92 138.86)
		(width 0.125)
		(layer "F.Cu")
		(net 682)
	)
	(via
		(at 131.29 140.86)
		(size 0.45)
		(drill 0.1)
		(layers "F.Cu" "B.Cu")
		(remove_unused_layers yes)
		(keep_end_layers yes)
		(zone_layer_connections)
		(teardrops
			(best_length_ratio 0.4)
			(max_length 1)
			(best_width_ratio 0.9)
			(max_width 2)
			(curved_edges yes)
			(filter_ratio 0.9)
			(enabled yes)
			(allow_two_segments yes)
			(prefer_zone_connections yes)
		)
		(net 683)
	)
	(segment
		(start 128.01 142.31)
		(end 127.76 142.06)
		(width 0.125)
		(layer "B.Cu")
		(net 683)
	)
	(segment
		(start 129.7575 142.0625)
		(end 129.51 142.31)
		(width 0.125)
		(layer "B.Cu")
		(net 683)
	)
	(segment
		(start 129.7575 141.579294)
		(end 129.7575 142.0625)
		(width 0.125)
		(layer "B.Cu")
		(net 683)
	)
	(segment
		(start 130.036794 141.3)
		(end 129.7575 141.579294)
		(width 0.125)
		(layer "B.Cu")
		(net 683)
	)
	(segment
		(start 130.85 141.3)
		(end 130.036794 141.3)
		(width 0.125)
		(layer "B.Cu")
		(net 683)
	)
	(segment
		(start 131.29 140.86)
		(end 130.85 141.3)
		(width 0.125)
		(layer "B.Cu")
		(net 683)
	)
	(segment
		(start 129.51 142.31)
		(end 128.01 142.31)
		(width 0.125)
		(layer "B.Cu")
		(net 683)
	)
	(segment
		(start 127.76 142.06)
		(end 126.57 142.06)
		(width 0.125)
		(layer "B.Cu")
		(net 683)
	)
	(segment
		(start 126.22 135.2)
		(end 125.9 134.88)
		(width 0.125)
		(layer "F.Cu")
		(net 684)
	)
	(segment
		(start 125.9 134.88)
		(end 125.32 134.88)
		(width 0.125)
		(layer "F.Cu")
		(net 684)
	)
	(segment
		(start 127.29 139.86)
		(end 126.22 138.79)
		(width 0.125)
		(layer "F.Cu")
		(net 684)
	)
	(segment
		(start 125.32 133.88)
		(end 125.32 134.88)
		(width 0.125)
		(layer "F.Cu")
		(net 684)
	)
	(segment
		(start 126.22 138.79)
		(end 126.22 135.2)
		(width 0.125)
		(layer "F.Cu")
		(net 684)
	)
	(segment
		(start 146.76 146.77)
		(end 146.76 143.17)
		(width 0.16)
		(layer "F.Cu")
		(net 685)
	)
	(segment
		(start 146.57 146.96)
		(end 146.76 146.77)
		(width 0.16)
		(layer "F.Cu")
		(net 685)
	)
	(segment
		(start 146.76 143.17)
		(end 146.45 142.86)
		(width 0.16)
		(layer "F.Cu")
		(net 685)
	)
	(segment
		(start 150.14 143.17)
		(end 150.45 142.86)
		(width 0.16)
		(layer "F.Cu")
		(net 686)
	)
	(segment
		(start 150.14 146.77)
		(end 150.14 143.17)
		(width 0.16)
		(layer "F.Cu")
		(net 686)
	)
	(segment
		(start 150.33 146.96)
		(end 150.14 146.77)
		(width 0.16)
		(layer "F.Cu")
		(net 686)
	)
	(segment
		(start 134.98 146.77)
		(end 134.98 143.17)
		(width 0.16)
		(layer "F.Cu")
		(net 687)
	)
	(segment
		(start 134.98 143.17)
		(end 135.29 142.86)
		(width 0.16)
		(layer "F.Cu")
		(net 687)
	)
	(segment
		(start 135.17 146.96)
		(end 134.98 146.77)
		(width 0.16)
		(layer "F.Cu")
		(net 687)
	)
	(segment
		(start 134.6 146.77)
		(end 134.6 143.17)
		(width 0.16)
		(layer "F.Cu")
		(net 688)
	)
	(segment
		(start 134.6 143.17)
		(end 134.29 142.86)
		(width 0.16)
		(layer "F.Cu")
		(net 688)
	)
	(segment
		(start 134.41 146.96)
		(end 134.6 146.77)
		(width 0.16)
		(layer "F.Cu")
		(net 688)
	)
	(segment
		(start 130.325 113.485)
		(end 130.5 113.66)
		(width 0.15)
		(layer "F.Cu")
		(net 689)
	)
	(segment
		(start 128.31 113.77)
		(end 128.595 113.485)
		(width 0.15)
		(layer "F.Cu")
		(net 689)
	)
	(segment
		(start 128.595 113.485)
		(end 130.325 113.485)
		(width 0.15)
		(layer "F.Cu")
		(net 689)
	)
	(segment
		(start 128.595 113.135)
		(end 130.325 113.135)
		(width 0.15)
		(layer "F.Cu")
		(net 690)
	)
	(segment
		(start 130.325 113.135)
		(end 130.445 113.015)
		(width 0.15)
		(layer "F.Cu")
		(net 690)
	)
	(segment
		(start 128.31 112.85)
		(end 128.595 113.135)
		(width 0.15)
		(layer "F.Cu")
		(net 690)
	)
	(segment
		(start 128.595 105.675)
		(end 130.335 105.675)
		(width 0.15)
		(layer "F.Cu")
		(net 691)
	)
	(segment
		(start 130.335 105.675)
		(end 130.51 105.85)
		(width 0.15)
		(layer "F.Cu")
		(net 691)
	)
	(segment
		(start 128.31 105.96)
		(end 128.595 105.675)
		(width 0.15)
		(layer "F.Cu")
		(net 691)
	)
	(segment
		(start 128.595 105.325)
		(end 130.325 105.325)
		(width 0.15)
		(layer "F.Cu")
		(net 692)
	)
	(segment
		(start 130.325 105.325)
		(end 130.445 105.205)
		(width 0.15)
		(layer "F.Cu")
		(net 692)
	)
	(segment
		(start 128.31 105.04)
		(end 128.595 105.325)
		(width 0.15)
		(layer "F.Cu")
		(net 692)
	)
	(segment
		(start 130.335 109.595)
		(end 130.51 109.77)
		(width 0.15)
		(layer "F.Cu")
		(net 693)
	)
	(segment
		(start 128.595 109.595)
		(end 130.335 109.595)
		(width 0.15)
		(layer "F.Cu")
		(net 693)
	)
	(segment
		(start 128.31 109.88)
		(end 128.595 109.595)
		(width 0.15)
		(layer "F.Cu")
		(net 693)
	)
	(segment
		(start 130.345 109.245)
		(end 130.465 109.125)
		(width 0.15)
		(layer "F.Cu")
		(net 694)
	)
	(segment
		(start 128.31 108.96)
		(end 128.595 109.245)
		(width 0.15)
		(layer "F.Cu")
		(net 694)
	)
	(segment
		(start 128.595 109.245)
		(end 130.345 109.245)
		(width 0.15)
		(layer "F.Cu")
		(net 694)
	)
	(segment
		(start 128.31 102.07)
		(end 128.595 101.785)
		(width 0.15)
		(layer "F.Cu")
		(net 695)
	)
	(segment
		(start 128.595 101.785)
		(end 130.335 101.785)
		(width 0.15)
		(layer "F.Cu")
		(net 695)
	)
	(segment
		(start 130.335 101.785)
		(end 130.51 101.96)
		(width 0.15)
		(layer "F.Cu")
		(net 695)
	)
	(segment
		(start 128.31 101.15)
		(end 128.595 101.435)
		(width 0.15)
		(layer "F.Cu")
		(net 696)
	)
	(segment
		(start 130.335 101.435)
		(end 130.455 101.315)
		(width 0.15)
		(layer "F.Cu")
		(net 696)
	)
	(segment
		(start 128.595 101.435)
		(end 130.335 101.435)
		(width 0.15)
		(layer "F.Cu")
		(net 696)
	)
	(segment
		(start 158.05 162.547)
		(end 158.05 163.11)
		(width 0.125)
		(layer "F.Cu")
		(net 697)
	)
	(segment
		(start 158.05 163.11)
		(end 157.85 163.31)
		(width 0.125)
		(layer "F.Cu")
		(net 697)
	)
	(via
		(at 157.85 163.31)
		(size 0.45)
		(drill 0.1)
		(layers "F.Cu" "B.Cu")
		(remove_unused_layers yes)
		(keep_end_layers yes)
		(zone_layer_connections)
		(teardrops
			(best_length_ratio 0.4)
			(max_length 1)
			(best_width_ratio 0.9)
			(max_width 2)
			(curved_edges yes)
			(filter_ratio 0.9)
			(enabled yes)
			(allow_two_segments yes)
			(prefer_zone_connections yes)
		)
		(net 697)
	)
	(segment
		(start 157.85 163.31)
		(end 157.85 162.61)
		(width 0.125)
		(layer "B.Cu")
		(net 697)
	)
	(segment
		(start 158.55 162.547)
		(end 158.55 163.11)
		(width 0.125)
		(layer "F.Cu")
		(net 698)
	)
	(segment
		(start 158.55 163.11)
		(end 158.75 163.31)
		(width 0.125)
		(layer "F.Cu")
		(net 698)
	)
	(via
		(at 158.75 163.31)
		(size 0.45)
		(drill 0.1)
		(layers "F.Cu" "B.Cu")
		(remove_unused_layers yes)
		(keep_end_layers yes)
		(zone_layer_connections)
		(teardrops
			(best_length_ratio 0.4)
			(max_length 1)
			(best_width_ratio 0.9)
			(max_width 2)
			(curved_edges yes)
			(filter_ratio 0.9)
			(enabled yes)
			(allow_two_segments yes)
			(prefer_zone_connections yes)
		)
		(net 698)
	)
	(segment
		(start 158.75 163.31)
		(end 158.75 162.61)
		(width 0.125)
		(layer "B.Cu")
		(net 698)
	)
	(segment
		(start 119.5 72.81)
		(end 120.038 72.272)
		(width 0.125)
		(layer "F.Cu")
		(net 699)
	)
	(segment
		(start 115.484999 73.925)
		(end 115.484999 73.225001)
		(width 0.125)
		(layer "F.Cu")
		(net 699)
	)
	(segment
		(start 115.484999 73.225001)
		(end 115.9 72.81)
		(width 0.125)
		(layer "F.Cu")
		(net 699)
	)
	(segment
		(start 120.038 72.272)
		(end 120.038 71.459)
		(width 0.125)
		(layer "F.Cu")
		(net 699)
	)
	(segment
		(start 118.25 72.81)
		(end 119.5 72.81)
		(width 0.125)
		(layer "F.Cu")
		(net 699)
	)
	(segment
		(start 115.9 72.81)
		(end 118.25 72.81)
		(width 0.125)
		(layer "F.Cu")
		(net 699)
	)
	(segment
		(start 118.25 73.41)
		(end 118.25 72.81)
		(width 0.125)
		(layer "F.Cu")
		(net 699)
	)
	(segment
		(start 119.9 74.81)
		(end 120.038 74.948)
		(width 0.125)
		(layer "F.Cu")
		(net 700)
	)
	(segment
		(start 118.25 74.71)
		(end 118.25 75.5)
		(width 0.125)
		(layer "F.Cu")
		(net 700)
	)
	(segment
		(start 119.65 74.81)
		(end 119.9 74.81)
		(width 0.125)
		(layer "F.Cu")
		(net 700)
	)
	(segment
		(start 118.96 75.5)
		(end 119.65 74.81)
		(width 0.125)
		(layer "F.Cu")
		(net 700)
	)
	(segment
		(start 120.038 74.948)
		(end 120.038 75.758)
		(width 0.125)
		(layer "F.Cu")
		(net 700)
	)
	(segment
		(start 118.25 75.5)
		(end 118.96 75.5)
		(width 0.125)
		(layer "F.Cu")
		(net 700)
	)
	(segment
		(start 117.059999 75.5)
		(end 118.25 75.5)
		(width 0.125)
		(layer "F.Cu")
		(net 700)
	)
	(segment
		(start 116.134999 78.9)
		(end 116.134999 77.725)
		(width 0.125)
		(layer "F.Cu")
		(net 701)
	)
	(segment
		(start 118.234999 76.15)
		(end 117.059999 76.15)
		(width 0.125)
		(layer "F.Cu")
		(net 702)
	)
	(segment
		(start 261.9 85.099999)
		(end 259.98 85.099999)
		(width 0.125)
		(layer "F.Cu")
		(net 703)
	)
	(via
		(at 261.9 85.099999)
		(size 0.45)
		(drill 0.1)
		(layers "F.Cu" "B.Cu")
		(remove_unused_layers yes)
		(keep_end_layers yes)
		(zone_layer_connections)
		(teardrops
			(best_length_ratio 0.4)
			(max_length 1)
			(best_width_ratio 0.9)
			(max_width 2)
			(curved_edges yes)
			(filter_ratio 0.9)
			(enabled yes)
			(allow_two_segments yes)
			(prefer_zone_connections yes)
		)
		(net 703)
	)
	(segment
		(start 261.860001 85.06)
		(end 259.95 85.06)
		(width 0.125)
		(layer "B.Cu")
		(net 703)
	)
	(segment
		(start 261.9 85.099999)
		(end 261.860001 85.06)
		(width 0.125)
		(layer "B.Cu")
		(net 703)
	)
	(segment
		(start 260.84 85.729999)
		(end 259.98 85.729998)
		(width 0.125)
		(layer "F.Cu")
		(net 704)
	)
	(via
		(at 260.84 85.729999)
		(size 0.45)
		(drill 0.1)
		(layers "F.Cu" "B.Cu")
		(remove_unused_layers yes)
		(keep_end_layers yes)
		(zone_layer_connections)
		(teardrops
			(best_length_ratio 0.4)
			(max_length 1)
			(best_width_ratio 0.9)
			(max_width 2)
			(curved_edges yes)
			(filter_ratio 0.9)
			(enabled yes)
			(allow_two_segments yes)
			(prefer_zone_connections yes)
		)
		(net 704)
	)
	(segment
		(start 260.84 85.729999)
		(end 260.820001 85.71)
		(width 0.125)
		(layer "B.Cu")
		(net 704)
	)
	(segment
		(start 260.820001 85.71)
		(end 258.95 85.71)
		(width 0.125)
		(layer "B.Cu")
		(net 704)
	)
	(segment
		(start 261.9 86.369999)
		(end 259.98 86.369999)
		(width 0.125)
		(layer "F.Cu")
		(net 705)
	)
	(via
		(at 261.9 86.369999)
		(size 0.45)
		(drill 0.1)
		(layers "F.Cu" "B.Cu")
		(remove_unused_layers yes)
		(keep_end_layers yes)
		(zone_layer_connections)
		(teardrops
			(best_length_ratio 0.4)
			(max_length 1)
			(best_width_ratio 0.9)
			(max_width 2)
			(curved_edges yes)
			(filter_ratio 0.9)
			(enabled yes)
			(allow_two_segments yes)
			(prefer_zone_connections yes)
		)
		(net 705)
	)
	(segment
		(start 261.9 86.369999)
		(end 261.890001 86.36)
		(width 0.125)
		(layer "B.Cu")
		(net 705)
	)
	(segment
		(start 261.890001 86.36)
		(end 259.95 86.36)
		(width 0.125)
		(layer "B.Cu")
		(net 705)
	)
	(segment
		(start 259.98 86.999999)
		(end 260.84 86.999999)
		(width 0.125)
		(layer "F.Cu")
		(net 706)
	)
	(via
		(at 260.84 86.999999)
		(size 0.45)
		(drill 0.1)
		(layers "F.Cu" "B.Cu")
		(remove_unused_layers yes)
		(keep_end_layers yes)
		(zone_layer_connections)
		(teardrops
			(best_length_ratio 0.4)
			(max_length 1)
			(best_width_ratio 0.9)
			(max_width 2)
			(curved_edges yes)
			(filter_ratio 0.9)
			(enabled yes)
			(allow_two_segments yes)
			(prefer_zone_connections yes)
		)
		(net 706)
	)
	(segment
		(start 260.829999 87.01)
		(end 258.949999 87.01)
		(width 0.125)
		(layer "B.Cu")
		(net 706)
	)
	(segment
		(start 260.84 86.999999)
		(end 260.829999 87.01)
		(width 0.125)
		(layer "B.Cu")
		(net 706)
	)
	(segment
		(start 260.84 84.459999)
		(end 259.98 84.459999)
		(width 0.125)
		(layer "F.Cu")
		(net 707)
	)
	(via
		(at 260.84 84.459999)
		(size 0.45)
		(drill 0.1)
		(layers "F.Cu" "B.Cu")
		(remove_unused_layers yes)
		(keep_end_layers yes)
		(zone_layer_connections)
		(teardrops
			(best_length_ratio 0.4)
			(max_length 1)
			(best_width_ratio 0.9)
			(max_width 2)
			(curved_edges yes)
			(filter_ratio 0.9)
			(enabled yes)
			(allow_two_segments yes)
			(prefer_zone_connections yes)
		)
		(net 707)
	)
	(segment
		(start 260.84 84.459999)
		(end 260.790001 84.41)
		(width 0.125)
		(layer "B.Cu")
		(net 707)
	)
	(segment
		(start 260.790001 84.41)
		(end 258.95 84.41)
		(width 0.125)
		(layer "B.Cu")
		(net 707)
	)
	(segment
		(start 257.175 128.109)
		(end 258.224 128.109)
		(width 0.125)
		(layer "F.Cu")
		(net 708)
	)
	(segment
		(start 214.28 125.677344)
		(end 214.28 126.249)
		(width 0.125)
		(layer "F.Cu")
		(net 709)
	)
	(segment
		(start 214.370681 125.586663)
		(end 214.28 125.677344)
		(width 0.125)
		(layer "F.Cu")
		(net 709)
	)
	(via
		(at 214.370681 125.586663)
		(size 0.45)
		(drill 0.1)
		(layers "F.Cu" "B.Cu")
		(remove_unused_layers yes)
		(keep_end_layers yes)
		(zone_layer_connections)
		(teardrops
			(best_length_ratio 0.4)
			(max_length 1)
			(best_width_ratio 0.9)
			(max_width 2)
			(curved_edges yes)
			(filter_ratio 0.9)
			(enabled yes)
			(allow_two_segments yes)
			(prefer_zone_connections yes)
		)
		(net 709)
	)
	(segment
		(start 214.370681 125.586663)
		(end 214.370681 124.859319)
		(width 0.125)
		(layer "B.Cu")
		(net 709)
	)
	(segment
		(start 213.770831 125.600207)
		(end 213.878 125.707376)
		(width 0.125)
		(layer "F.Cu")
		(net 710)
	)
	(segment
		(start 213.878 125.707376)
		(end 213.878 126.249)
		(width 0.125)
		(layer "F.Cu")
		(net 710)
	)
	(via
		(at 213.770831 125.600207)
		(size 0.45)
		(drill 0.1)
		(layers "F.Cu" "B.Cu")
		(remove_unused_layers yes)
		(keep_end_layers yes)
		(zone_layer_connections)
		(teardrops
			(best_length_ratio 0.4)
			(max_length 1)
			(best_width_ratio 0.9)
			(max_width 2)
			(curved_edges yes)
			(filter_ratio 0.9)
			(enabled yes)
			(allow_two_segments yes)
			(prefer_zone_connections yes)
		)
		(net 710)
	)
	(segment
		(start 213.770831 125.600207)
		(end 213.770831 125.290831)
		(width 0.125)
		(layer "B.Cu")
		(net 710)
	)
	(segment
		(start 213.770831 125.290831)
		(end 213.33 124.85)
		(width 0.125)
		(layer "B.Cu")
		(net 710)
	)
	(segment
		(start 217.479 125.701)
		(end 217.479 126.249)
		(width 0.125)
		(layer "F.Cu")
		(net 711)
	)
	(segment
		(start 217.58 125.6)
		(end 217.479 125.701)
		(width 0.125)
		(layer "F.Cu")
		(net 711)
	)
	(via
		(at 217.58 125.6)
		(size 0.45)
		(drill 0.1)
		(layers "F.Cu" "B.Cu")
		(remove_unused_layers yes)
		(keep_end_layers yes)
		(zone_layer_connections)
		(teardrops
			(best_length_ratio 0.4)
			(max_length 1)
			(best_width_ratio 0.9)
			(max_width 2)
			(curved_edges yes)
			(filter_ratio 0.9)
			(enabled yes)
			(allow_two_segments yes)
			(prefer_zone_connections yes)
		)
		(net 711)
	)
	(segment
		(start 217.58 125.6)
		(end 217.58 124.85)
		(width 0.125)
		(layer "B.Cu")
		(net 711)
	)
	(segment
		(start 122.498 146.61)
		(end 122.499 146.611)
		(width 0.125)
		(layer "B.Cu")
		(net 712)
	)
	(segment
		(start 121.839 146.61)
		(end 122.498 146.61)
		(width 0.125)
		(layer "B.Cu")
		(net 712)
	)
	(segment
		(start 122.499 146.611)
		(end 123.4 145.71)
		(width 0.125)
		(layer "B.Cu")
		(net 712)
	)
	(segment
		(start 122.9 146.76)
		(end 122.549 147.111)
		(width 0.125)
		(layer "B.Cu")
		(net 713)
	)
	(segment
		(start 123.4 146.76)
		(end 122.9 146.76)
		(width 0.125)
		(layer "B.Cu")
		(net 713)
	)
	(segment
		(start 122.549 147.111)
		(end 121.838 147.111)
		(width 0.125)
		(layer "B.Cu")
		(net 713)
	)
	(segment
		(start 121.6 149.76)
		(end 121.85 149.76)
		(width 0.125)
		(layer "B.Cu")
		(net 714)
	)
	(segment
		(start 121.85 149.76)
		(end 122.3 150.21)
		(width 0.125)
		(layer "B.Cu")
		(net 714)
	)
	(segment
		(start 121.4 149.048)
		(end 121.4 149.56)
		(width 0.125)
		(layer "B.Cu")
		(net 714)
	)
	(segment
		(start 121.4 149.56)
		(end 121.6 149.76)
		(width 0.125)
		(layer "B.Cu")
		(net 714)
	)
	(segment
		(start 123.4 144.66)
		(end 121.15 144.66)
		(width 0.125)
		(layer "B.Cu")
		(net 715)
	)
	(segment
		(start 121.15 144.66)
		(end 120.9 144.91)
		(width 0.125)
		(layer "B.Cu")
		(net 715)
	)
	(segment
		(start 120.9 144.91)
		(end 120.9 145.673)
		(width 0.125)
		(layer "B.Cu")
		(net 715)
	)
	(segment
		(start 196.40402 131.911056)
		(end 196.057538 132.257538)
		(width 0.125)
		(layer "F.Cu")
		(net 716)
	)
	(segment
		(start 196.40402 131.790847)
		(end 196.40402 131.911056)
		(width 0.125)
		(layer "F.Cu")
		(net 716)
	)
	(segment
		(start 196.580797 131.614071)
		(end 196.40402 131.790847)
		(width 0.125)
		(layer "F.Cu")
		(net 716)
	)
	(via
		(at 196.580797 131.614071)
		(size 0.45)
		(drill 0.1)
		(layers "F.Cu" "B.Cu")
		(remove_unused_layers yes)
		(keep_end_layers yes)
		(zone_layer_connections)
		(teardrops
			(best_length_ratio 0.4)
			(max_length 1)
			(best_width_ratio 0.9)
			(max_width 2)
			(curved_edges yes)
			(filter_ratio 0.9)
			(enabled yes)
			(allow_two_segments yes)
			(prefer_zone_connections yes)
		)
		(net 716)
	)
	(segment
		(start 196.580797 131.614071)
		(end 196.580797 131.894085)
		(width 0.125)
		(layer "B.Cu")
		(net 716)
	)
	(segment
		(start 196.580797 131.894085)
		(end 196.198959 132.275923)
		(width 0.125)
		(layer "B.Cu")
		(net 716)
	)
	(segment
		(start 197.075772 132.002979)
		(end 196.8 132.278751)
		(width 0.125)
		(layer "F.Cu")
		(net 717)
	)
	(segment
		(start 196.8 132.278751)
		(end 196.8 133)
		(width 0.125)
		(layer "F.Cu")
		(net 717)
	)
	(via
		(at 197.075772 132.002979)
		(size 0.45)
		(drill 0.1)
		(layers "F.Cu" "B.Cu")
		(remove_unused_layers yes)
		(keep_end_layers yes)
		(zone_layer_connections)
		(teardrops
			(best_length_ratio 0.4)
			(max_length 1)
			(best_width_ratio 0.9)
			(max_width 2)
			(curved_edges yes)
			(filter_ratio 0.9)
			(enabled yes)
			(allow_two_segments yes)
			(prefer_zone_connections yes)
		)
		(net 717)
	)
	(segment
		(start 197.075772 132.002979)
		(end 197.075772 132.106217)
		(width 0.125)
		(layer "B.Cu")
		(net 717)
	)
	(segment
		(start 197.075772 132.106217)
		(end 196.552513 132.629476)
		(width 0.125)
		(layer "B.Cu")
		(net 717)
	)
	(via
		(at 197.85 133.7)
		(size 0.45)
		(drill 0.1)
		(layers "F.Cu" "B.Cu")
		(teardrops
			(best_length_ratio 0.4)
			(max_length 1)
			(best_width_ratio 0.9)
			(max_width 2)
			(curved_edges yes)
			(filter_ratio 0.9)
			(enabled yes)
			(allow_two_segments yes)
			(prefer_zone_connections yes)
		)
		(net 718)
	)
	(segment
		(start 197.613173 134.308148)
		(end 197.613173 134.313173)
		(width 0.125)
		(layer "B.Cu")
		(net 718)
	)
	(segment
		(start 198.25 134.6)
		(end 198.275 134.575)
		(width 0.125)
		(layer "B.Cu")
		(net 718)
	)
	(segment
		(start 198.175 134.675)
		(end 198.25 134.6)
		(width 0.125)
		(layer "B.Cu")
		(net 718)
	)
	(segment
		(start 198.275 134.125)
		(end 197.85 133.7)
		(width 0.125)
		(layer "B.Cu")
		(net 718)
	)
	(segment
		(start 197.975 134.675)
		(end 198.175 134.675)
		(width 0.125)
		(layer "B.Cu")
		(net 718)
	)
	(segment
		(start 198.275 134.575)
		(end 198.275 134.125)
		(width 0.125)
		(layer "B.Cu")
		(net 718)
	)
	(segment
		(start 197.613173 134.313173)
		(end 197.975 134.675)
		(width 0.125)
		(layer "B.Cu")
		(net 718)
	)
	(segment
		(start 194.424121 131.515076)
		(end 195.315076 131.515076)
		(width 0.125)
		(layer "F.Cu")
		(net 719)
	)
	(via
		(at 194.424121 131.515076)
		(size 0.45)
		(drill 0.1)
		(layers "F.Cu" "B.Cu")
		(remove_unused_layers yes)
		(keep_end_layers yes)
		(zone_layer_connections)
		(teardrops
			(best_length_ratio 0.4)
			(max_length 1)
			(best_width_ratio 0.9)
			(max_width 2)
			(curved_edges yes)
			(filter_ratio 0.9)
			(enabled yes)
			(allow_two_segments yes)
			(prefer_zone_connections yes)
		)
		(net 719)
	)
	(segment
		(start 194.424121 131.827617)
		(end 194.872427 132.275923)
		(width 0.125)
		(layer "B.Cu")
		(net 719)
	)
	(segment
		(start 194.424121 131.515076)
		(end 194.424121 131.827617)
		(width 0.125)
		(layer "B.Cu")
		(net 719)
	)
	(segment
		(start 145.2 130.15)
		(end 145.21 130.15)
		(width 0.125)
		(layer "F.Cu")
		(net 720)
	)
	(segment
		(start 145.21 130.15)
		(end 145.3 130.06)
		(width 0.125)
		(layer "F.Cu")
		(net 720)
	)
	(segment
		(start 145.3 130.06)
		(end 145.3 128.71)
		(width 0.125)
		(layer "F.Cu")
		(net 720)
	)
	(via
		(at 147.45 139.86)
		(size 0.45)
		(drill 0.1)
		(layers "F.Cu" "B.Cu")
		(remove_unused_layers yes)
		(keep_end_layers yes)
		(zone_layer_connections "In5.Cu")
		(teardrops
			(best_length_ratio 0.4)
			(max_length 1)
			(best_width_ratio 0.9)
			(max_width 2)
			(curved_edges yes)
			(filter_ratio 0.9)
			(enabled yes)
			(allow_two_segments yes)
			(prefer_zone_connections yes)
		)
		(net 720)
	)
	(via
		(at 145.2 130.15)
		(size 0.45)
		(drill 0.1)
		(layers "F.Cu" "B.Cu")
		(remove_unused_layers yes)
		(keep_end_layers yes)
		(zone_layer_connections "In5.Cu")
		(teardrops
			(best_length_ratio 0.4)
			(max_length 1)
			(best_width_ratio 0.9)
			(max_width 2)
			(curved_edges yes)
			(filter_ratio 0.9)
			(enabled yes)
			(allow_two_segments yes)
			(prefer_zone_connections yes)
		)
		(net 720)
	)
	(segment
		(start 145.2 130.15)
		(end 145 130.35)
		(width 0.125)
		(layer "In5.Cu")
		(net 720)
	)
	(segment
		(start 146.95 139.36)
		(end 147.45 139.86)
		(width 0.125)
		(layer "In5.Cu")
		(net 720)
	)
	(segment
		(start 145 130.35)
		(end 145 138.84)
		(width 0.125)
		(layer "In5.Cu")
		(net 720)
	)
	(segment
		(start 145.52 139.36)
		(end 146.95 139.36)
		(width 0.125)
		(layer "In5.Cu")
		(net 720)
	)
	(segment
		(start 145 138.84)
		(end 145.52 139.36)
		(width 0.125)
		(layer "In5.Cu")
		(net 720)
	)
	(segment
		(start 144.54 130.17)
		(end 144.54 130.52)
		(width 0.125)
		(layer "F.Cu")
		(net 721)
	)
	(segment
		(start 144.65 129.56)
		(end 144.65 130.06)
		(width 0.125)
		(layer "F.Cu")
		(net 721)
	)
	(segment
		(start 144.65 130.06)
		(end 144.54 130.17)
		(width 0.125)
		(layer "F.Cu")
		(net 721)
	)
	(via
		(at 144.54 130.52)
		(size 0.45)
		(drill 0.1)
		(layers "F.Cu" "B.Cu")
		(remove_unused_layers yes)
		(keep_end_layers yes)
		(zone_layer_connections "In5.Cu")
		(teardrops
			(best_length_ratio 0.4)
			(max_length 1)
			(best_width_ratio 0.9)
			(max_width 2)
			(curved_edges yes)
			(filter_ratio 0.9)
			(enabled yes)
			(allow_two_segments yes)
			(prefer_zone_connections yes)
		)
		(net 721)
	)
	(via
		(at 147.45 140.86)
		(size 0.45)
		(drill 0.1)
		(layers "F.Cu" "B.Cu")
		(remove_unused_layers yes)
		(keep_end_layers yes)
		(zone_layer_connections "In5.Cu")
		(teardrops
			(best_length_ratio 0.4)
			(max_length 1)
			(best_width_ratio 0.9)
			(max_width 2)
			(curved_edges yes)
			(filter_ratio 0.9)
			(enabled yes)
			(allow_two_segments yes)
			(prefer_zone_connections yes)
		)
		(net 721)
	)
	(segment
		(start 144.725 130.705)
		(end 144.725 138.965)
		(width 0.125)
		(layer "In5.Cu")
		(net 721)
	)
	(segment
		(start 146.13 140.37)
		(end 146.96 140.37)
		(width 0.125)
		(layer "In5.Cu")
		(net 721)
	)
	(segment
		(start 146.96 140.37)
		(end 147.45 140.86)
		(width 0.125)
		(layer "In5.Cu")
		(net 721)
	)
	(segment
		(start 144.725 138.965)
		(end 146.13 140.37)
		(width 0.125)
		(layer "In5.Cu")
		(net 721)
	)
	(segment
		(start 144.54 130.52)
		(end 144.725 130.705)
		(width 0.125)
		(layer "In5.Cu")
		(net 721)
	)
	(segment
		(start 153.1 128.71)
		(end 153.1 130.14)
		(width 0.125)
		(layer "F.Cu")
		(net 722)
	)
	(via
		(at 153.1 130.14)
		(size 0.45)
		(drill 0.1)
		(layers "F.Cu" "B.Cu")
		(remove_unused_layers yes)
		(keep_end_layers yes)
		(zone_layer_connections "In5.Cu")
		(teardrops
			(best_length_ratio 0.4)
			(max_length 1)
			(best_width_ratio 0.9)
			(max_width 2)
			(curved_edges yes)
			(filter_ratio 0.9)
			(enabled yes)
			(allow_two_segments yes)
			(prefer_zone_connections yes)
		)
		(net 722)
	)
	(via
		(at 154.45 138.86)
		(size 0.45)
		(drill 0.1)
		(layers "F.Cu" "B.Cu")
		(remove_unused_layers yes)
		(keep_end_layers yes)
		(zone_layer_connections "In5.Cu")
		(teardrops
			(best_length_ratio 0.4)
			(max_length 1)
			(best_width_ratio 0.9)
			(max_width 2)
			(curved_edges yes)
			(filter_ratio 0.9)
			(enabled yes)
			(allow_two_segments yes)
			(prefer_zone_connections yes)
		)
		(net 722)
	)
	(segment
		(start 154.95 138.36)
		(end 154.45 138.86)
		(width 0.125)
		(layer "In5.Cu")
		(net 722)
	)
	(segment
		(start 153.35 131.61)
		(end 153.61 131.61)
		(width 0.125)
		(layer "In5.Cu")
		(net 722)
	)
	(segment
		(start 153.1 130.14)
		(end 153.1 131.36)
		(width 0.125)
		(layer "In5.Cu")
		(net 722)
	)
	(segment
		(start 154.95 136.16)
		(end 154.95 138.36)
		(width 0.125)
		(layer "In5.Cu")
		(net 722)
	)
	(segment
		(start 155.9 133.54)
		(end 155.9 135.21)
		(width 0.125)
		(layer "In5.Cu")
		(net 722)
	)
	(segment
		(start 153.61 131.61)
		(end 154.5275 132.5275)
		(width 0.125)
		(layer "In5.Cu")
		(net 722)
	)
	(segment
		(start 153.1 131.36)
		(end 153.35 131.61)
		(width 0.125)
		(layer "In5.Cu")
		(net 722)
	)
	(segment
		(start 154.5275 132.5275)
		(end 154.8875 132.5275)
		(width 0.125)
		(layer "In5.Cu")
		(net 722)
	)
	(segment
		(start 155.9 135.21)
		(end 154.95 136.16)
		(width 0.125)
		(layer "In5.Cu")
		(net 722)
	)
	(segment
		(start 154.8875 132.5275)
		(end 155.9 133.54)
		(width 0.125)
		(layer "In5.Cu")
		(net 722)
	)
	(segment
		(start 151.8 128.71)
		(end 151.8 130.14)
		(width 0.125)
		(layer "F.Cu")
		(net 723)
	)
	(via
		(at 151.8 130.14)
		(size 0.45)
		(drill 0.1)
		(layers "F.Cu" "B.Cu")
		(remove_unused_layers yes)
		(keep_end_layers yes)
		(zone_layer_connections "In5.Cu")
		(teardrops
			(best_length_ratio 0.4)
			(max_length 1)
			(best_width_ratio 0.9)
			(max_width 2)
			(curved_edges yes)
			(filter_ratio 0.9)
			(enabled yes)
			(allow_two_segments yes)
			(prefer_zone_connections yes)
		)
		(net 723)
	)
	(via
		(at 153.45 136.86)
		(size 0.45)
		(drill 0.1)
		(layers "F.Cu" "B.Cu")
		(remove_unused_layers yes)
		(keep_end_layers yes)
		(zone_layer_connections "In5.Cu")
		(teardrops
			(best_length_ratio 0.4)
			(max_length 1)
			(best_width_ratio 0.9)
			(max_width 2)
			(curved_edges yes)
			(filter_ratio 0.9)
			(enabled yes)
			(allow_two_segments yes)
			(prefer_zone_connections yes)
		)
		(net 723)
	)
	(segment
		(start 153.66 132.41)
		(end 154 132.75)
		(width 0.125)
		(layer "In5.Cu")
		(net 723)
	)
	(segment
		(start 154 132.75)
		(end 154 135.91)
		(width 0.125)
		(layer "In5.Cu")
		(net 723)
	)
	(segment
		(start 153.45 136.46)
		(end 153.45 136.86)
		(width 0.125)
		(layer "In5.Cu")
		(net 723)
	)
	(segment
		(start 154 135.91)
		(end 153.45 136.46)
		(width 0.125)
		(layer "In5.Cu")
		(net 723)
	)
	(segment
		(start 153.12 132.41)
		(end 153.66 132.41)
		(width 0.125)
		(layer "In5.Cu")
		(net 723)
	)
	(segment
		(start 151.8 131.09)
		(end 153.12 132.41)
		(width 0.125)
		(layer "In5.Cu")
		(net 723)
	)
	(segment
		(start 151.8 130.14)
		(end 151.8 131.09)
		(width 0.125)
		(layer "In5.Cu")
		(net 723)
	)
	(segment
		(start 153.75 129.56)
		(end 153.75 130.51)
		(width 0.125)
		(layer "F.Cu")
		(net 724)
	)
	(via
		(at 155.45 138.86)
		(size 0.45)
		(drill 0.1)
		(layers "F.Cu" "B.Cu")
		(remove_unused_layers yes)
		(keep_end_layers yes)
		(zone_layer_connections "In5.Cu")
		(teardrops
			(best_length_ratio 0.4)
			(max_length 1)
			(best_width_ratio 0.9)
			(max_width 2)
			(curved_edges yes)
			(filter_ratio 0.9)
			(enabled yes)
			(allow_two_segments yes)
			(prefer_zone_connections yes)
		)
		(net 724)
	)
	(via
		(at 153.75 130.51)
		(size 0.45)
		(drill 0.1)
		(layers "F.Cu" "B.Cu")
		(remove_unused_layers yes)
		(keep_end_layers yes)
		(zone_layer_connections "In5.Cu")
		(teardrops
			(best_length_ratio 0.4)
			(max_length 1)
			(best_width_ratio 0.9)
			(max_width 2)
			(curved_edges yes)
			(filter_ratio 0.9)
			(enabled yes)
			(allow_two_segments yes)
			(prefer_zone_connections yes)
		)
		(net 724)
	)
	(segment
		(start 154.05 131.36)
		(end 154.55 131.36)
		(width 0.125)
		(layer "In5.Cu")
		(net 724)
	)
	(segment
		(start 155.94 132.75)
		(end 155.94 133)
		(width 0.125)
		(layer "In5.Cu")
		(net 724)
	)
	(segment
		(start 156.31 133.37)
		(end 156.31 135.35)
		(width 0.125)
		(layer "In5.Cu")
		(net 724)
	)
	(segment
		(start 155.98 135.68)
		(end 155.98 137.96)
		(width 0.125)
		(layer "In5.Cu")
		(net 724)
	)
	(segment
		(start 155.98 137.96)
		(end 155.45 138.49)
		(width 0.125)
		(layer "In5.Cu")
		(net 724)
	)
	(segment
		(start 154.55 131.36)
		(end 155.94 132.75)
		(width 0.125)
		(layer "In5.Cu")
		(net 724)
	)
	(segment
		(start 153.75 130.51)
		(end 153.75 131.06)
		(width 0.125)
		(layer "In5.Cu")
		(net 724)
	)
	(segment
		(start 155.45 138.49)
		(end 155.45 138.86)
		(width 0.125)
		(layer "In5.Cu")
		(net 724)
	)
	(segment
		(start 153.75 131.06)
		(end 154.05 131.36)
		(width 0.125)
		(layer "In5.Cu")
		(net 724)
	)
	(segment
		(start 155.94 133)
		(end 156.31 133.37)
		(width 0.125)
		(layer "In5.Cu")
		(net 724)
	)
	(segment
		(start 156.31 135.35)
		(end 155.98 135.68)
		(width 0.125)
		(layer "In5.Cu")
		(net 724)
	)
	(segment
		(start 152.45 129.56)
		(end 152.45 130.51)
		(width 0.125)
		(layer "F.Cu")
		(net 725)
	)
	(via
		(at 153.45 138.86)
		(size 0.45)
		(drill 0.1)
		(layers "F.Cu" "B.Cu")
		(remove_unused_layers yes)
		(keep_end_layers yes)
		(zone_layer_connections "In5.Cu")
		(teardrops
			(best_length_ratio 0.4)
			(max_length 1)
			(best_width_ratio 0.9)
			(max_width 2)
			(curved_edges yes)
			(filter_ratio 0.9)
			(enabled yes)
			(allow_two_segments yes)
			(prefer_zone_connections yes)
		)
		(net 725)
	)
	(via
		(at 152.45 130.51)
		(size 0.45)
		(drill 0.1)
		(layers "F.Cu" "B.Cu")
		(remove_unused_layers yes)
		(keep_end_layers yes)
		(zone_layer_connections "In5.Cu")
		(teardrops
			(best_length_ratio 0.4)
			(max_length 1)
			(best_width_ratio 0.9)
			(max_width 2)
			(curved_edges yes)
			(filter_ratio 0.9)
			(enabled yes)
			(allow_two_segments yes)
			(prefer_zone_connections yes)
		)
		(net 725)
	)
	(segment
		(start 154.8875 135.6825)
		(end 153.95 136.62)
		(width 0.125)
		(layer "In5.Cu")
		(net 725)
	)
	(segment
		(start 153.624454 132.01)
		(end 154.8875 133.273046)
		(width 0.125)
		(layer "In5.Cu")
		(net 725)
	)
	(segment
		(start 153.95 138.36)
		(end 153.45 138.86)
		(width 0.125)
		(layer "In5.Cu")
		(net 725)
	)
	(segment
		(start 153.21 132.01)
		(end 153.624454 132.01)
		(width 0.125)
		(layer "In5.Cu")
		(net 725)
	)
	(segment
		(start 154.8875 133.273046)
		(end 154.8875 135.6825)
		(width 0.125)
		(layer "In5.Cu")
		(net 725)
	)
	(segment
		(start 152.45 131.25)
		(end 153.21 132.01)
		(width 0.125)
		(layer "In5.Cu")
		(net 725)
	)
	(segment
		(start 153.95 136.62)
		(end 153.95 138.36)
		(width 0.125)
		(layer "In5.Cu")
		(net 725)
	)
	(segment
		(start 152.45 130.51)
		(end 152.45 131.25)
		(width 0.125)
		(layer "In5.Cu")
		(net 725)
	)
	(segment
		(start 151.15 129.56)
		(end 151.15 130.51)
		(width 0.125)
		(layer "F.Cu")
		(net 726)
	)
	(via
		(at 152.45 135.86)
		(size 0.45)
		(drill 0.1)
		(layers "F.Cu" "B.Cu")
		(remove_unused_layers yes)
		(keep_end_layers yes)
		(zone_layer_connections "In5.Cu")
		(teardrops
			(best_length_ratio 0.4)
			(max_length 1)
			(best_width_ratio 0.9)
			(max_width 2)
			(curved_edges yes)
			(filter_ratio 0.9)
			(enabled yes)
			(allow_two_segments yes)
			(prefer_zone_connections yes)
		)
		(net 726)
	)
	(via
		(at 151.15 130.51)
		(size 0.45)
		(drill 0.1)
		(layers "F.Cu" "B.Cu")
		(remove_unused_layers yes)
		(keep_end_layers yes)
		(zone_layer_connections "In5.Cu")
		(teardrops
			(best_length_ratio 0.4)
			(max_length 1)
			(best_width_ratio 0.9)
			(max_width 2)
			(curved_edges yes)
			(filter_ratio 0.9)
			(enabled yes)
			(allow_two_segments yes)
			(prefer_zone_connections yes)
		)
		(net 726)
	)
	(segment
		(start 152.95 132.76)
		(end 152.95 135.36)
		(width 0.125)
		(layer "In5.Cu")
		(net 726)
	)
	(segment
		(start 151.15 130.96)
		(end 152.95 132.76)
		(width 0.125)
		(layer "In5.Cu")
		(net 726)
	)
	(segment
		(start 152.95 135.36)
		(end 152.45 135.86)
		(width 0.125)
		(layer "In5.Cu")
		(net 726)
	)
	(segment
		(start 151.15 130.51)
		(end 151.15 130.96)
		(width 0.125)
		(layer "In5.Cu")
		(net 726)
	)
	(segment
		(start 149.2 128.71)
		(end 149.2 130.14)
		(width 0.125)
		(layer "F.Cu")
		(net 727)
	)
	(via
		(at 148.45 139.86)
		(size 0.45)
		(drill 0.1)
		(layers "F.Cu" "B.Cu")
		(remove_unused_layers yes)
		(keep_end_layers yes)
		(zone_layer_connections "In2.Cu")
		(teardrops
			(best_length_ratio 0.4)
			(max_length 1)
			(best_width_ratio 0.9)
			(max_width 2)
			(curved_edges yes)
			(filter_ratio 0.9)
			(enabled yes)
			(allow_two_segments yes)
			(prefer_zone_connections yes)
		)
		(net 727)
	)
	(via
		(at 149.2 130.14)
		(size 0.45)
		(drill 0.1)
		(layers "F.Cu" "B.Cu")
		(remove_unused_layers yes)
		(keep_end_layers yes)
		(zone_layer_connections "In2.Cu")
		(teardrops
			(best_length_ratio 0.4)
			(max_length 1)
			(best_width_ratio 0.9)
			(max_width 2)
			(curved_edges yes)
			(filter_ratio 0.9)
			(enabled yes)
			(allow_two_segments yes)
			(prefer_zone_connections yes)
		)
		(net 727)
	)
	(segment
		(start 148.95 131.12)
		(end 148.95 139.36)
		(width 0.125)
		(layer "In2.Cu")
		(net 727)
	)
	(segment
		(start 149.2 130.14)
		(end 149.2 130.87)
		(width 0.125)
		(layer "In2.Cu")
		(net 727)
	)
	(segment
		(start 149.2 130.87)
		(end 148.95 131.12)
		(width 0.125)
		(layer "In2.Cu")
		(net 727)
	)
	(segment
		(start 148.95 139.36)
		(end 148.45 139.86)
		(width 0.125)
		(layer "In2.Cu")
		(net 727)
	)
	(segment
		(start 147.9 128.71)
		(end 147.9 130.14)
		(width 0.125)
		(layer "F.Cu")
		(net 728)
	)
	(via
		(at 154.45 141.86)
		(size 0.45)
		(drill 0.1)
		(layers "F.Cu" "B.Cu")
		(remove_unused_layers yes)
		(keep_end_layers yes)
		(zone_layer_connections "In5.Cu")
		(teardrops
			(best_length_ratio 0.4)
			(max_length 1)
			(best_width_ratio 0.9)
			(max_width 2)
			(curved_edges yes)
			(filter_ratio 0.9)
			(enabled yes)
			(allow_two_segments yes)
			(prefer_zone_connections yes)
		)
		(net 728)
	)
	(via
		(at 147.9 130.14)
		(size 0.45)
		(drill 0.1)
		(layers "F.Cu" "B.Cu")
		(remove_unused_layers yes)
		(keep_end_layers yes)
		(zone_layer_connections "In5.Cu")
		(teardrops
			(best_length_ratio 0.4)
			(max_length 1)
			(best_width_ratio 0.9)
			(max_width 2)
			(curved_edges yes)
			(filter_ratio 0.9)
			(enabled yes)
			(allow_two_segments yes)
			(prefer_zone_connections yes)
		)
		(net 728)
	)
	(segment
		(start 150.25 141.36)
		(end 153.95 141.36)
		(width 0.125)
		(layer "In5.Cu")
		(net 728)
	)
	(segment
		(start 149 132.791281)
		(end 149 137.028719)
		(width 0.125)
		(layer "In5.Cu")
		(net 728)
	)
	(segment
		(start 149 137.028719)
		(end 149.268781 137.2975)
		(width 0.125)
		(layer "In5.Cu")
		(net 728)
	)
	(segment
		(start 149.268781 137.2975)
		(end 149.506219 137.2975)
		(width 0.125)
		(layer "In5.Cu")
		(net 728)
	)
	(segment
		(start 149.95 137.741281)
		(end 149.95 141.06)
		(width 0.125)
		(layer "In5.Cu")
		(net 728)
	)
	(segment
		(start 147.9 131.691281)
		(end 149 132.791281)
		(width 0.125)
		(layer "In5.Cu")
		(net 728)
	)
	(segment
		(start 149.506219 137.2975)
		(end 149.95 137.741281)
		(width 0.125)
		(layer "In5.Cu")
		(net 728)
	)
	(segment
		(start 153.95 141.36)
		(end 154.45 141.86)
		(width 0.125)
		(layer "In5.Cu")
		(net 728)
	)
	(segment
		(start 149.95 141.06)
		(end 150.25 141.36)
		(width 0.125)
		(layer "In5.Cu")
		(net 728)
	)
	(segment
		(start 147.9 130.14)
		(end 147.9 131.691281)
		(width 0.125)
		(layer "In5.Cu")
		(net 728)
	)
	(segment
		(start 154.4 128.71)
		(end 154.4 130.14)
		(width 0.125)
		(layer "F.Cu")
		(net 729)
	)
	(via
		(at 153.45 134.86)
		(size 0.45)
		(drill 0.1)
		(layers "F.Cu" "B.Cu")
		(remove_unused_layers yes)
		(keep_end_layers yes)
		(zone_layer_connections "In2.Cu")
		(teardrops
			(best_length_ratio 0.4)
			(max_length 1)
			(best_width_ratio 0.9)
			(max_width 2)
			(curved_edges yes)
			(filter_ratio 0.9)
			(enabled yes)
			(allow_two_segments yes)
			(prefer_zone_connections yes)
		)
		(net 729)
	)
	(via
		(at 154.4 130.14)
		(size 0.45)
		(drill 0.1)
		(layers "F.Cu" "B.Cu")
		(remove_unused_layers yes)
		(keep_end_layers yes)
		(zone_layer_connections "In2.Cu")
		(teardrops
			(best_length_ratio 0.4)
			(max_length 1)
			(best_width_ratio 0.9)
			(max_width 2)
			(curved_edges yes)
			(filter_ratio 0.9)
			(enabled yes)
			(allow_two_segments yes)
			(prefer_zone_connections yes)
		)
		(net 729)
	)
	(segment
		(start 153.95 131.15)
		(end 153.95 134.36)
		(width 0.125)
		(layer "In2.Cu")
		(net 729)
	)
	(segment
		(start 154.4 130.14)
		(end 154.4 130.7)
		(width 0.125)
		(layer "In2.Cu")
		(net 729)
	)
	(segment
		(start 153.95 134.36)
		(end 153.45 134.86)
		(width 0.125)
		(layer "In2.Cu")
		(net 729)
	)
	(segment
		(start 154.4 130.7)
		(end 153.95 131.15)
		(width 0.125)
		(layer "In2.Cu")
		(net 729)
	)
	(segment
		(start 155.05 129.56)
		(end 155.05 130.51)
		(width 0.125)
		(layer "F.Cu")
		(net 730)
	)
	(via
		(at 155.05 130.51)
		(size 0.45)
		(drill 0.1)
		(layers "F.Cu" "B.Cu")
		(remove_unused_layers yes)
		(keep_end_layers yes)
		(zone_layer_connections "In5.Cu")
		(teardrops
			(best_length_ratio 0.4)
			(max_length 1)
			(best_width_ratio 0.9)
			(max_width 2)
			(curved_edges yes)
			(filter_ratio 0.9)
			(enabled yes)
			(allow_two_segments yes)
			(prefer_zone_connections yes)
		)
		(net 730)
	)
	(via
		(at 154.45 139.86)
		(size 0.45)
		(drill 0.1)
		(layers "F.Cu" "B.Cu")
		(remove_unused_layers yes)
		(keep_end_layers yes)
		(zone_layer_connections "In5.Cu")
		(teardrops
			(best_length_ratio 0.4)
			(max_length 1)
			(best_width_ratio 0.9)
			(max_width 2)
			(curved_edges yes)
			(filter_ratio 0.9)
			(enabled yes)
			(allow_two_segments yes)
			(prefer_zone_connections yes)
		)
		(net 730)
	)
	(segment
		(start 154.95 139.36)
		(end 155.85 139.36)
		(width 0.125)
		(layer "In5.Cu")
		(net 730)
	)
	(segment
		(start 155.85 139.36)
		(end 156.0125 139.1975)
		(width 0.125)
		(layer "In5.Cu")
		(net 730)
	)
	(segment
		(start 156.0125 138.5475)
		(end 156.95 137.61)
		(width 0.125)
		(layer "In5.Cu")
		(net 730)
	)
	(segment
		(start 156.15 132.2)
		(end 155.05 131.1)
		(width 0.125)
		(layer "In5.Cu")
		(net 730)
	)
	(segment
		(start 154.45 139.86)
		(end 154.95 139.36)
		(width 0.125)
		(layer "In5.Cu")
		(net 730)
	)
	(segment
		(start 156.95 132.5)
		(end 156.65 132.2)
		(width 0.125)
		(layer "In5.Cu")
		(net 730)
	)
	(segment
		(start 156.95 137.61)
		(end 156.95 132.5)
		(width 0.125)
		(layer "In5.Cu")
		(net 730)
	)
	(segment
		(start 155.05 131.1)
		(end 155.05 130.51)
		(width 0.125)
		(layer "In5.Cu")
		(net 730)
	)
	(segment
		(start 156.0125 139.1975)
		(end 156.0125 138.5475)
		(width 0.125)
		(layer "In5.Cu")
		(net 730)
	)
	(segment
		(start 156.65 132.2)
		(end 156.15 132.2)
		(width 0.125)
		(layer "In5.Cu")
		(net 730)
	)
	(segment
		(start 148.55 129.56)
		(end 148.55 130.51)
		(width 0.125)
		(layer "F.Cu")
		(net 731)
	)
	(via
		(at 148.55 130.51)
		(size 0.45)
		(drill 0.1)
		(layers "F.Cu" "B.Cu")
		(remove_unused_layers yes)
		(keep_end_layers yes)
		(zone_layer_connections "In5.Cu")
		(teardrops
			(best_length_ratio 0.4)
			(max_length 1)
			(best_width_ratio 0.9)
			(max_width 2)
			(curved_edges yes)
			(filter_ratio 0.9)
			(enabled yes)
			(allow_two_segments yes)
			(prefer_zone_connections yes)
		)
		(net 731)
	)
	(via
		(at 154.45 140.86)
		(size 0.45)
		(drill 0.1)
		(layers "F.Cu" "B.Cu")
		(remove_unused_layers yes)
		(keep_end_layers yes)
		(zone_layer_connections "In5.Cu")
		(teardrops
			(best_length_ratio 0.4)
			(max_length 1)
			(best_width_ratio 0.9)
			(max_width 2)
			(curved_edges yes)
			(filter_ratio 0.9)
			(enabled yes)
			(allow_two_segments yes)
			(prefer_zone_connections yes)
		)
		(net 731)
	)
	(segment
		(start 149.568719 132.36)
		(end 149.9 132.691281)
		(width 0.125)
		(layer "In5.Cu")
		(net 731)
	)
	(segment
		(start 151.2 140.36)
		(end 153.95 140.36)
		(width 0.125)
		(layer "In5.Cu")
		(net 731)
	)
	(segment
		(start 148.55 130.51)
		(end 148.55 131.71)
		(width 0.125)
		(layer "In5.Cu")
		(net 731)
	)
	(segment
		(start 149.9 132.691281)
		(end 149.9 137.06)
		(width 0.125)
		(layer "In5.Cu")
		(net 731)
	)
	(segment
		(start 153.95 140.36)
		(end 154.45 140.86)
		(width 0.125)
		(layer "In5.Cu")
		(net 731)
	)
	(segment
		(start 150.506221 137.2975)
		(end 150.91 137.701279)
		(width 0.125)
		(layer "In5.Cu")
		(net 731)
	)
	(segment
		(start 150.91 140.07)
		(end 151.2 140.36)
		(width 0.125)
		(layer "In5.Cu")
		(net 731)
	)
	(segment
		(start 149.9 137.06)
		(end 150.1375 137.2975)
		(width 0.125)
		(layer "In5.Cu")
		(net 731)
	)
	(segment
		(start 150.1375 137.2975)
		(end 150.506221 137.2975)
		(width 0.125)
		(layer "In5.Cu")
		(net 731)
	)
	(segment
		(start 150.91 137.701279)
		(end 150.91 140.07)
		(width 0.125)
		(layer "In5.Cu")
		(net 731)
	)
	(segment
		(start 149.2 132.36)
		(end 149.568719 132.36)
		(width 0.125)
		(layer "In5.Cu")
		(net 731)
	)
	(segment
		(start 148.55 131.71)
		(end 149.2 132.36)
		(width 0.125)
		(layer "In5.Cu")
		(net 731)
	)
	(segment
		(start 156.35 129.56)
		(end 157.25 130.46)
		(width 0.125)
		(layer "F.Cu")
		(net 732)
	)
	(segment
		(start 157.25 139.05)
		(end 156.44 139.86)
		(width 0.125)
		(layer "F.Cu")
		(net 732)
	)
	(segment
		(start 157.25 130.46)
		(end 157.25 139.05)
		(width 0.125)
		(layer "F.Cu")
		(net 732)
	)
	(segment
		(start 156.44 140.86)
		(end 157.75 139.55)
		(width 0.125)
		(layer "F.Cu")
		(net 733)
	)
	(segment
		(start 157.75 129.46)
		(end 157 128.71)
		(width 0.125)
		(layer "F.Cu")
		(net 733)
	)
	(segment
		(start 157.75 139.55)
		(end 157.75 129.46)
		(width 0.125)
		(layer "F.Cu")
		(net 733)
	)
	(segment
		(start 149.85 129.56)
		(end 149.85 130.51)
		(width 0.125)
		(layer "F.Cu")
		(net 734)
	)
	(via
		(at 152.45 139.86)
		(size 0.45)
		(drill 0.1)
		(layers "F.Cu" "B.Cu")
		(remove_unused_layers yes)
		(keep_end_layers yes)
		(zone_layer_connections "In5.Cu")
		(teardrops
			(best_length_ratio 0.4)
			(max_length 1)
			(best_width_ratio 0.9)
			(max_width 2)
			(curved_edges yes)
			(filter_ratio 0.9)
			(enabled yes)
			(allow_two_segments yes)
			(prefer_zone_connections yes)
		)
		(net 734)
	)
	(via
		(at 149.85 130.51)
		(size 0.45)
		(drill 0.1)
		(layers "F.Cu" "B.Cu")
		(remove_unused_layers yes)
		(keep_end_layers yes)
		(zone_layer_connections "In5.Cu")
		(teardrops
			(best_length_ratio 0.4)
			(max_length 1)
			(best_width_ratio 0.9)
			(max_width 2)
			(curved_edges yes)
			(filter_ratio 0.9)
			(enabled yes)
			(allow_two_segments yes)
			(prefer_zone_connections yes)
		)
		(net 734)
	)
	(segment
		(start 150.95 132.741281)
		(end 150.95 136.978719)
		(width 0.125)
		(layer "In5.Cu")
		(net 734)
	)
	(segment
		(start 151.65 137.31)
		(end 151.96 137.62)
		(width 0.125)
		(layer "In5.Cu")
		(net 734)
	)
	(segment
		(start 151.281281 137.31)
		(end 151.65 137.31)
		(width 0.125)
		(layer "In5.Cu")
		(net 734)
	)
	(segment
		(start 149.85 132.09)
		(end 150.12 132.36)
		(width 0.125)
		(layer "In5.Cu")
		(net 734)
	)
	(segment
		(start 150.568719 132.36)
		(end 150.95 132.741281)
		(width 0.125)
		(layer "In5.Cu")
		(net 734)
	)
	(segment
		(start 151.96 137.62)
		(end 151.96 139.37)
		(width 0.125)
		(layer "In5.Cu")
		(net 734)
	)
	(segment
		(start 150.12 132.36)
		(end 150.568719 132.36)
		(width 0.125)
		(layer "In5.Cu")
		(net 734)
	)
	(segment
		(start 151.96 139.37)
		(end 152.45 139.86)
		(width 0.125)
		(layer "In5.Cu")
		(net 734)
	)
	(segment
		(start 150.95 136.978719)
		(end 151.281281 137.31)
		(width 0.125)
		(layer "In5.Cu")
		(net 734)
	)
	(segment
		(start 149.85 130.51)
		(end 149.85 132.09)
		(width 0.125)
		(layer "In5.Cu")
		(net 734)
	)
	(segment
		(start 155.7 128.71)
		(end 155.7 130.86)
		(width 0.125)
		(layer "F.Cu")
		(net 735)
	)
	(via
		(at 155.7 130.86)
		(size 0.45)
		(drill 0.1)
		(layers "F.Cu" "B.Cu")
		(remove_unused_layers yes)
		(keep_end_layers yes)
		(zone_layer_connections "In5.Cu")
		(teardrops
			(best_length_ratio 0.4)
			(max_length 1)
			(best_width_ratio 0.9)
			(max_width 2)
			(curved_edges yes)
			(filter_ratio 0.9)
			(enabled yes)
			(allow_two_segments yes)
			(prefer_zone_connections yes)
		)
		(net 735)
	)
	(via
		(at 155.45 140.86)
		(size 0.45)
		(drill 0.1)
		(layers "F.Cu" "B.Cu")
		(remove_unused_layers yes)
		(keep_end_layers yes)
		(zone_layer_connections "In5.Cu")
		(teardrops
			(best_length_ratio 0.4)
			(max_length 1)
			(best_width_ratio 0.9)
			(max_width 2)
			(curved_edges yes)
			(filter_ratio 0.9)
			(enabled yes)
			(allow_two_segments yes)
			(prefer_zone_connections yes)
		)
		(net 735)
	)
	(segment
		(start 156.06 130.86)
		(end 157.4 132.2)
		(width 0.125)
		(layer "In5.Cu")
		(net 735)
	)
	(segment
		(start 155.7 130.86)
		(end 156.06 130.86)
		(width 0.125)
		(layer "In5.Cu")
		(net 735)
	)
	(segment
		(start 157.4 132.2)
		(end 157.4 138.91)
		(width 0.125)
		(layer "In5.Cu")
		(net 735)
	)
	(segment
		(start 157.4 138.91)
		(end 155.45 140.86)
		(width 0.125)
		(layer "In5.Cu")
		(net 735)
	)
	(segment
		(start 150.5 128.71)
		(end 150.5 130.14)
		(width 0.125)
		(layer "F.Cu")
		(net 736)
	)
	(via
		(at 153.45 139.86)
		(size 0.45)
		(drill 0.1)
		(layers "F.Cu" "B.Cu")
		(remove_unused_layers yes)
		(keep_end_layers yes)
		(zone_layer_connections "In5.Cu")
		(teardrops
			(best_length_ratio 0.4)
			(max_length 1)
			(best_width_ratio 0.9)
			(max_width 2)
			(curved_edges yes)
			(filter_ratio 0.9)
			(enabled yes)
			(allow_two_segments yes)
			(prefer_zone_connections yes)
		)
		(net 736)
	)
	(via
		(at 150.5 130.14)
		(size 0.45)
		(drill 0.1)
		(layers "F.Cu" "B.Cu")
		(remove_unused_layers yes)
		(keep_end_layers yes)
		(zone_layer_connections "In5.Cu")
		(teardrops
			(best_length_ratio 0.4)
			(max_length 1)
			(best_width_ratio 0.9)
			(max_width 2)
			(curved_edges yes)
			(filter_ratio 0.9)
			(enabled yes)
			(allow_two_segments yes)
			(prefer_zone_connections yes)
		)
		(net 736)
	)
	(segment
		(start 150.57 130.21)
		(end 150.57 131.28)
		(width 0.125)
		(layer "In5.Cu")
		(net 736)
	)
	(segment
		(start 151.21 132.37)
		(end 151.66 132.37)
		(width 0.125)
		(layer "In5.Cu")
		(net 736)
	)
	(segment
		(start 151.95 132.66)
		(end 151.95 136.978719)
		(width 0.125)
		(layer "In5.Cu")
		(net 736)
	)
	(segment
		(start 151.66 132.37)
		(end 151.95 132.66)
		(width 0.125)
		(layer "In5.Cu")
		(net 736)
	)
	(segment
		(start 150.8875 131.5975)
		(end 150.8875 132.0475)
		(width 0.125)
		(layer "In5.Cu")
		(net 736)
	)
	(segment
		(start 150.57 131.28)
		(end 150.8875 131.5975)
		(width 0.125)
		(layer "In5.Cu")
		(net 736)
	)
	(segment
		(start 152.79 137.3)
		(end 153 137.51)
		(width 0.125)
		(layer "In5.Cu")
		(net 736)
	)
	(segment
		(start 150.5 130.14)
		(end 150.57 130.21)
		(width 0.125)
		(layer "In5.Cu")
		(net 736)
	)
	(segment
		(start 152.271281 137.3)
		(end 152.79 137.3)
		(width 0.125)
		(layer "In5.Cu")
		(net 736)
	)
	(segment
		(start 153 137.51)
		(end 153 139.41)
		(width 0.125)
		(layer "In5.Cu")
		(net 736)
	)
	(segment
		(start 150.8875 132.0475)
		(end 151.21 132.37)
		(width 0.125)
		(layer "In5.Cu")
		(net 736)
	)
	(segment
		(start 151.95 136.978719)
		(end 152.271281 137.3)
		(width 0.125)
		(layer "In5.Cu")
		(net 736)
	)
	(segment
		(start 153 139.41)
		(end 153.45 139.86)
		(width 0.125)
		(layer "In5.Cu")
		(net 736)
	)
	(segment
		(start 146.6 128.71)
		(end 146.6 130.14)
		(width 0.125)
		(layer "F.Cu")
		(net 737)
	)
	(via
		(at 147.45 138.86)
		(size 0.45)
		(drill 0.1)
		(layers "F.Cu" "B.Cu")
		(remove_unused_layers yes)
		(keep_end_layers yes)
		(zone_layer_connections "In5.Cu")
		(teardrops
			(best_length_ratio 0.4)
			(max_length 1)
			(best_width_ratio 0.9)
			(max_width 2)
			(curved_edges yes)
			(filter_ratio 0.9)
			(enabled yes)
			(allow_two_segments yes)
			(prefer_zone_connections yes)
		)
		(net 737)
	)
	(via
		(at 146.6 130.14)
		(size 0.45)
		(drill 0.1)
		(layers "F.Cu" "B.Cu")
		(remove_unused_layers yes)
		(keep_end_layers yes)
		(zone_layer_connections "In5.Cu")
		(teardrops
			(best_length_ratio 0.4)
			(max_length 1)
			(best_width_ratio 0.9)
			(max_width 2)
			(curved_edges yes)
			(filter_ratio 0.9)
			(enabled yes)
			(allow_two_segments yes)
			(prefer_zone_connections yes)
		)
		(net 737)
	)
	(segment
		(start 146.95 138.36)
		(end 147.45 138.86)
		(width 0.125)
		(layer "In5.Cu")
		(net 737)
	)
	(segment
		(start 146.32 135.38)
		(end 146.32 136.86)
		(width 0.125)
		(layer "In5.Cu")
		(net 737)
	)
	(segment
		(start 146.32 136.86)
		(end 146 137.18)
		(width 0.125)
		(layer "In5.Cu")
		(net 737)
	)
	(segment
		(start 146 137.18)
		(end 146 138.11)
		(width 0.125)
		(layer "In5.Cu")
		(net 737)
	)
	(segment
		(start 146 133.691281)
		(end 146 135.06)
		(width 0.125)
		(layer "In5.Cu")
		(net 737)
	)
	(segment
		(start 146.6 133.091281)
		(end 146 133.691281)
		(width 0.125)
		(layer "In5.Cu")
		(net 737)
	)
	(segment
		(start 146 135.06)
		(end 146.32 135.38)
		(width 0.125)
		(layer "In5.Cu")
		(net 737)
	)
	(segment
		(start 146 138.11)
		(end 146.25 138.36)
		(width 0.125)
		(layer "In5.Cu")
		(net 737)
	)
	(segment
		(start 146.6 130.14)
		(end 146.6 133.091281)
		(width 0.125)
		(layer "In5.Cu")
		(net 737)
	)
	(segment
		(start 146.25 138.36)
		(end 146.95 138.36)
		(width 0.125)
		(layer "In5.Cu")
		(net 737)
	)
	(segment
		(start 145.95 129.56)
		(end 145.95 130.51)
		(width 0.125)
		(layer "F.Cu")
		(net 738)
	)
	(via
		(at 145.95 130.51)
		(size 0.45)
		(drill 0.1)
		(layers "F.Cu" "B.Cu")
		(remove_unused_layers yes)
		(keep_end_layers yes)
		(zone_layer_connections "In5.Cu")
		(teardrops
			(best_length_ratio 0.4)
			(max_length 1)
			(best_width_ratio 0.9)
			(max_width 2)
			(curved_edges yes)
			(filter_ratio 0.9)
			(enabled yes)
			(allow_two_segments yes)
			(prefer_zone_connections yes)
		)
		(net 738)
	)
	(via
		(at 146.45 138.86)
		(size 0.45)
		(drill 0.1)
		(layers "F.Cu" "B.Cu")
		(remove_unused_layers yes)
		(keep_end_layers yes)
		(zone_layer_connections "In5.Cu")
		(teardrops
			(best_length_ratio 0.4)
			(max_length 1)
			(best_width_ratio 0.9)
			(max_width 2)
			(curved_edges yes)
			(filter_ratio 0.9)
			(enabled yes)
			(allow_two_segments yes)
			(prefer_zone_connections yes)
		)
		(net 738)
	)
	(segment
		(start 146.1 138.86)
		(end 146.45 138.86)
		(width 0.125)
		(layer "In5.Cu")
		(net 738)
	)
	(segment
		(start 145.95 130.51)
		(end 145.95 133.16)
		(width 0.125)
		(layer "In5.Cu")
		(net 738)
	)
	(segment
		(start 145.59 133.52)
		(end 145.59 135.25)
		(width 0.125)
		(layer "In5.Cu")
		(net 738)
	)
	(segment
		(start 145.6 136.96)
		(end 145.6 138.36)
		(width 0.125)
		(layer "In5.Cu")
		(net 738)
	)
	(segment
		(start 145.6 138.36)
		(end 146.1 138.86)
		(width 0.125)
		(layer "In5.Cu")
		(net 738)
	)
	(segment
		(start 145.59 135.25)
		(end 145.95 135.61)
		(width 0.125)
		(layer "In5.Cu")
		(net 738)
	)
	(segment
		(start 145.95 135.61)
		(end 145.95 136.61)
		(width 0.125)
		(layer "In5.Cu")
		(net 738)
	)
	(segment
		(start 145.95 133.16)
		(end 145.59 133.52)
		(width 0.125)
		(layer "In5.Cu")
		(net 738)
	)
	(segment
		(start 145.95 136.61)
		(end 145.6 136.96)
		(width 0.125)
		(layer "In5.Cu")
		(net 738)
	)
	(segment
		(start 147.25 129.56)
		(end 147.25 130.51)
		(width 0.125)
		(layer "F.Cu")
		(net 739)
	)
	(via
		(at 149.45 139.86)
		(size 0.45)
		(drill 0.1)
		(layers "F.Cu" "B.Cu")
		(remove_unused_layers yes)
		(keep_end_layers yes)
		(zone_layer_connections "In5.Cu")
		(teardrops
			(best_length_ratio 0.4)
			(max_length 1)
			(best_width_ratio 0.9)
			(max_width 2)
			(curved_edges yes)
			(filter_ratio 0.9)
			(enabled yes)
			(allow_two_segments yes)
			(prefer_zone_connections yes)
		)
		(net 739)
	)
	(via
		(at 147.25 130.51)
		(size 0.45)
		(drill 0.1)
		(layers "F.Cu" "B.Cu")
		(remove_unused_layers yes)
		(keep_end_layers yes)
		(zone_layer_connections "In5.Cu")
		(teardrops
			(best_length_ratio 0.4)
			(max_length 1)
			(best_width_ratio 0.9)
			(max_width 2)
			(curved_edges yes)
			(filter_ratio 0.9)
			(enabled yes)
			(allow_two_segments yes)
			(prefer_zone_connections yes)
		)
		(net 739)
	)
	(segment
		(start 148.96 139.05)
		(end 149.45 139.54)
		(width 0.125)
		(layer "In5.Cu")
		(net 739)
	)
	(segment
		(start 148.96 137.62)
		(end 148.96 139.05)
		(width 0.125)
		(layer "In5.Cu")
		(net 739)
	)
	(segment
		(start 149.45 139.54)
		(end 149.45 139.86)
		(width 0.125)
		(layer "In5.Cu")
		(net 739)
	)
	(segment
		(start 147.35 137.36)
		(end 148.7 137.36)
		(width 0.125)
		(layer "In5.Cu")
		(net 739)
	)
	(segment
		(start 147.25 130.51)
		(end 147.25 131.41)
		(width 0.125)
		(layer "In5.Cu")
		(net 739)
	)
	(segment
		(start 148.7 137.36)
		(end 148.96 137.62)
		(width 0.125)
		(layer "In5.Cu")
		(net 739)
	)
	(segment
		(start 147.25 131.41)
		(end 146.95 131.71)
		(width 0.125)
		(layer "In5.Cu")
		(net 739)
	)
	(segment
		(start 146.95 131.71)
		(end 146.95 136.96)
		(width 0.125)
		(layer "In5.Cu")
		(net 739)
	)
	(segment
		(start 146.95 136.96)
		(end 147.35 137.36)
		(width 0.125)
		(layer "In5.Cu")
		(net 739)
	)
	(segment
		(start 127.18 130.1)
		(end 127.14 130.06)
		(width 0.125)
		(layer "F.Cu")
		(net 740)
	)
	(segment
		(start 127.14 130.06)
		(end 127.14 128.71)
		(width 0.125)
		(layer "F.Cu")
		(net 740)
	)
	(segment
		(start 127.18 130.16)
		(end 127.18 130.1)
		(width 0.125)
		(layer "F.Cu")
		(net 740)
	)
	(via
		(at 127.18 130.16)
		(size 0.45)
		(drill 0.1)
		(layers "F.Cu" "B.Cu")
		(remove_unused_layers yes)
		(keep_end_layers yes)
		(zone_layer_connections "In5.Cu")
		(teardrops
			(best_length_ratio 0.4)
			(max_length 1)
			(best_width_ratio 0.9)
			(max_width 2)
			(curved_edges yes)
			(filter_ratio 0.9)
			(enabled yes)
			(allow_two_segments yes)
			(prefer_zone_connections yes)
		)
		(net 740)
	)
	(via
		(at 129.29 139.86)
		(size 0.45)
		(drill 0.1)
		(layers "F.Cu" "B.Cu")
		(remove_unused_layers yes)
		(keep_end_layers yes)
		(zone_layer_connections "In5.Cu")
		(teardrops
			(best_length_ratio 0.4)
			(max_length 1)
			(best_width_ratio 0.9)
			(max_width 2)
			(curved_edges yes)
			(filter_ratio 0.9)
			(enabled yes)
			(allow_two_segments yes)
			(prefer_zone_connections yes)
		)
		(net 740)
	)
	(segment
		(start 126.84 130.5)
		(end 126.84 138.84)
		(width 0.125)
		(layer "In5.Cu")
		(net 740)
	)
	(segment
		(start 127.36 139.36)
		(end 128.79 139.36)
		(width 0.125)
		(layer "In5.Cu")
		(net 740)
	)
	(segment
		(start 126.84 138.84)
		(end 127.36 139.36)
		(width 0.125)
		(layer "In5.Cu")
		(net 740)
	)
	(segment
		(start 128.79 139.36)
		(end 129.29 139.86)
		(width 0.125)
		(layer "In5.Cu")
		(net 740)
	)
	(segment
		(start 127.18 130.16)
		(end 126.84 130.5)
		(width 0.125)
		(layer "In5.Cu")
		(net 740)
	)
	(segment
		(start 126.355 130.675)
		(end 126.355 130.195)
		(width 0.125)
		(layer "F.Cu")
		(net 741)
	)
	(segment
		(start 126.49 130.06)
		(end 126.49 129.56)
		(width 0.125)
		(layer "F.Cu")
		(net 741)
	)
	(segment
		(start 126.355 130.195)
		(end 126.49 130.06)
		(width 0.125)
		(layer "F.Cu")
		(net 741)
	)
	(via
		(at 129.29 140.86)
		(size 0.45)
		(drill 0.1)
		(layers "F.Cu" "B.Cu")
		(remove_unused_layers yes)
		(keep_end_layers yes)
		(zone_layer_connections "In5.Cu")
		(teardrops
			(best_length_ratio 0.4)
			(max_length 1)
			(best_width_ratio 0.9)
			(max_width 2)
			(curved_edges yes)
			(filter_ratio 0.9)
			(enabled yes)
			(allow_two_segments yes)
			(prefer_zone_connections yes)
		)
		(net 741)
	)
	(via
		(at 126.355 130.675)
		(size 0.45)
		(drill 0.1)
		(layers "F.Cu" "B.Cu")
		(remove_unused_layers yes)
		(keep_end_layers yes)
		(zone_layer_connections "In5.Cu")
		(teardrops
			(best_length_ratio 0.4)
			(max_length 1)
			(best_width_ratio 0.9)
			(max_width 2)
			(curved_edges yes)
			(filter_ratio 0.9)
			(enabled yes)
			(allow_two_segments yes)
			(prefer_zone_connections yes)
		)
		(net 741)
	)
	(segment
		(start 126.565 130.885)
		(end 126.565 138.965)
		(width 0.125)
		(layer "In5.Cu")
		(net 741)
	)
	(segment
		(start 126.565 138.965)
		(end 127.96 140.36)
		(width 0.125)
		(layer "In5.Cu")
		(net 741)
	)
	(segment
		(start 128.79 140.36)
		(end 129.29 140.86)
		(width 0.125)
		(layer "In5.Cu")
		(net 741)
	)
	(segment
		(start 127.96 140.36)
		(end 128.79 140.36)
		(width 0.125)
		(layer "In5.Cu")
		(net 741)
	)
	(segment
		(start 126.355 130.675)
		(end 126.565 130.885)
		(width 0.125)
		(layer "In5.Cu")
		(net 741)
	)
	(segment
		(start 134.94 128.71)
		(end 134.94 130.14)
		(width 0.125)
		(layer "F.Cu")
		(net 742)
	)
	(via
		(at 136.29 138.86)
		(size 0.45)
		(drill 0.1)
		(layers "F.Cu" "B.Cu")
		(remove_unused_layers yes)
		(keep_end_layers yes)
		(zone_layer_connections "In5.Cu")
		(teardrops
			(best_length_ratio 0.4)
			(max_length 1)
			(best_width_ratio 0.9)
			(max_width 2)
			(curved_edges yes)
			(filter_ratio 0.9)
			(enabled yes)
			(allow_two_segments yes)
			(prefer_zone_connections yes)
		)
		(net 742)
	)
	(via
		(at 134.94 130.14)
		(size 0.45)
		(drill 0.1)
		(layers "F.Cu" "B.Cu")
		(remove_unused_layers yes)
		(keep_end_layers yes)
		(zone_layer_connections "In5.Cu")
		(teardrops
			(best_length_ratio 0.4)
			(max_length 1)
			(best_width_ratio 0.9)
			(max_width 2)
			(curved_edges yes)
			(filter_ratio 0.9)
			(enabled yes)
			(allow_two_segments yes)
			(prefer_zone_connections yes)
		)
		(net 742)
	)
	(segment
		(start 136.399136 132.5525)
		(end 136.7375 132.5525)
		(width 0.125)
		(layer "In5.Cu")
		(net 742)
	)
	(segment
		(start 134.94 130.14)
		(end 134.94 131.375)
		(width 0.125)
		(layer "In5.Cu")
		(net 742)
	)
	(segment
		(start 136.8 136.185)
		(end 136.8 138.385)
		(width 0.125)
		(layer "In5.Cu")
		(net 742)
	)
	(segment
		(start 137.75 133.565)
		(end 137.75 135.235)
		(width 0.125)
		(layer "In5.Cu")
		(net 742)
	)
	(segment
		(start 135.8775 132.0275)
		(end 135.8775 132.030864)
		(width 0.125)
		(layer "In5.Cu")
		(net 742)
	)
	(segment
		(start 135.2 131.635)
		(end 135.485 131.635)
		(width 0.125)
		(layer "In5.Cu")
		(net 742)
	)
	(segment
		(start 137.75 135.235)
		(end 136.8 136.185)
		(width 0.125)
		(layer "In5.Cu")
		(net 742)
	)
	(segment
		(start 136.7375 132.5525)
		(end 137.75 133.565)
		(width 0.125)
		(layer "In5.Cu")
		(net 742)
	)
	(segment
		(start 135.8775 132.030864)
		(end 136.399136 132.5525)
		(width 0.125)
		(layer "In5.Cu")
		(net 742)
	)
	(segment
		(start 136.8 138.385)
		(end 136.3 138.885)
		(width 0.125)
		(layer "In5.Cu")
		(net 742)
	)
	(segment
		(start 134.94 131.375)
		(end 135.2 131.635)
		(width 0.125)
		(layer "In5.Cu")
		(net 742)
	)
	(segment
		(start 135.485 131.635)
		(end 135.8775 132.0275)
		(width 0.125)
		(layer "In5.Cu")
		(net 742)
	)
	(segment
		(start 133.64 128.71)
		(end 133.64 130.14)
		(width 0.125)
		(layer "F.Cu")
		(net 743)
	)
	(via
		(at 133.64 130.14)
		(size 0.45)
		(drill 0.1)
		(layers "F.Cu" "B.Cu")
		(remove_unused_layers yes)
		(keep_end_layers yes)
		(zone_layer_connections "In5.Cu")
		(teardrops
			(best_length_ratio 0.4)
			(max_length 1)
			(best_width_ratio 0.9)
			(max_width 2)
			(curved_edges yes)
			(filter_ratio 0.9)
			(enabled yes)
			(allow_two_segments yes)
			(prefer_zone_connections yes)
		)
		(net 743)
	)
	(via
		(at 135.29 136.86)
		(size 0.45)
		(drill 0.1)
		(layers "F.Cu" "B.Cu")
		(remove_unused_layers yes)
		(keep_end_layers yes)
		(zone_layer_connections "In5.Cu")
		(teardrops
			(best_length_ratio 0.4)
			(max_length 1)
			(best_width_ratio 0.9)
			(max_width 2)
			(curved_edges yes)
			(filter_ratio 0.9)
			(enabled yes)
			(allow_two_segments yes)
			(prefer_zone_connections yes)
		)
		(net 743)
	)
	(segment
		(start 134.96 132.415)
		(end 135.5275 132.415)
		(width 0.125)
		(layer "In5.Cu")
		(net 743)
	)
	(segment
		(start 135.84 135.915)
		(end 135.29 136.465)
		(width 0.125)
		(layer "In5.Cu")
		(net 743)
	)
	(segment
		(start 135.5275 132.415)
		(end 135.84 132.7275)
		(width 0.125)
		(layer "In5.Cu")
		(net 743)
	)
	(segment
		(start 135.29 136.465)
		(end 135.29 136.865)
		(width 0.125)
		(layer "In5.Cu")
		(net 743)
	)
	(segment
		(start 135.84 132.7275)
		(end 135.84 135.915)
		(width 0.125)
		(layer "In5.Cu")
		(net 743)
	)
	(segment
		(start 133.64 130.14)
		(end 133.64 131.095)
		(width 0.125)
		(layer "In5.Cu")
		(net 743)
	)
	(segment
		(start 133.64 131.095)
		(end 134.96 132.415)
		(width 0.125)
		(layer "In5.Cu")
		(net 743)
	)
	(segment
		(start 135.59 129.56)
		(end 135.59 130.51)
		(width 0.125)
		(layer "F.Cu")
		(net 744)
	)
	(via
		(at 135.59 130.51)
		(size 0.45)
		(drill 0.1)
		(layers "F.Cu" "B.Cu")
		(remove_unused_layers yes)
		(keep_end_layers yes)
		(zone_layer_connections "In5.Cu")
		(teardrops
			(best_length_ratio 0.4)
			(max_length 1)
			(best_width_ratio 0.9)
			(max_width 2)
			(curved_edges yes)
			(filter_ratio 0.9)
			(enabled yes)
			(allow_two_segments yes)
			(prefer_zone_connections yes)
		)
		(net 744)
	)
	(via
		(at 137.29 138.86)
		(size 0.45)
		(drill 0.1)
		(layers "F.Cu" "B.Cu")
		(remove_unused_layers yes)
		(keep_end_layers yes)
		(zone_layer_connections "In5.Cu")
		(teardrops
			(best_length_ratio 0.4)
			(max_length 1)
			(best_width_ratio 0.9)
			(max_width 2)
			(curved_edges yes)
			(filter_ratio 0.9)
			(enabled yes)
			(allow_two_segments yes)
			(prefer_zone_connections yes)
		)
		(net 744)
	)
	(segment
		(start 135.915 131.385)
		(end 136.4 131.385)
		(width 0.125)
		(layer "In5.Cu")
		(net 744)
	)
	(segment
		(start 135.59 131.06)
		(end 135.915 131.385)
		(width 0.125)
		(layer "In5.Cu")
		(net 744)
	)
	(segment
		(start 137.79 132.775)
		(end 137.79 133.025)
		(width 0.125)
		(layer "In5.Cu")
		(net 744)
	)
	(segment
		(start 138.16 135.375)
		(end 137.83 135.705)
		(width 0.125)
		(layer "In5.Cu")
		(net 744)
	)
	(segment
		(start 137.83 135.705)
		(end 137.83 137.985)
		(width 0.125)
		(layer "In5.Cu")
		(net 744)
	)
	(segment
		(start 137.83 137.985)
		(end 137.3 138.515)
		(width 0.125)
		(layer "In5.Cu")
		(net 744)
	)
	(segment
		(start 136.4 131.385)
		(end 137.79 132.775)
		(width 0.125)
		(layer "In5.Cu")
		(net 744)
	)
	(segment
		(start 138.16 133.395)
		(end 138.16 135.375)
		(width 0.125)
		(layer "In5.Cu")
		(net 744)
	)
	(segment
		(start 135.59 130.51)
		(end 135.59 131.06)
		(width 0.125)
		(layer "In5.Cu")
		(net 744)
	)
	(segment
		(start 137.3 138.515)
		(end 137.3 138.885)
		(width 0.125)
		(layer "In5.Cu")
		(net 744)
	)
	(segment
		(start 137.79 133.025)
		(end 138.16 133.395)
		(width 0.125)
		(layer "In5.Cu")
		(net 744)
	)
	(segment
		(start 134.29 129.56)
		(end 134.29 130.51)
		(width 0.125)
		(layer "F.Cu")
		(net 745)
	)
	(via
		(at 134.29 130.51)
		(size 0.45)
		(drill 0.1)
		(layers "F.Cu" "B.Cu")
		(remove_unused_layers yes)
		(keep_end_layers yes)
		(zone_layer_connections "In5.Cu")
		(teardrops
			(best_length_ratio 0.4)
			(max_length 1)
			(best_width_ratio 0.9)
			(max_width 2)
			(curved_edges yes)
			(filter_ratio 0.9)
			(enabled yes)
			(allow_two_segments yes)
			(prefer_zone_connections yes)
		)
		(net 745)
	)
	(via
		(at 135.29 138.86)
		(size 0.45)
		(drill 0.1)
		(layers "F.Cu" "B.Cu")
		(remove_unused_layers yes)
		(keep_end_layers yes)
		(zone_layer_connections "In5.Cu")
		(teardrops
			(best_length_ratio 0.4)
			(max_length 1)
			(best_width_ratio 0.9)
			(max_width 2)
			(curved_edges yes)
			(filter_ratio 0.9)
			(enabled yes)
			(allow_two_segments yes)
			(prefer_zone_connections yes)
		)
		(net 745)
	)
	(segment
		(start 135.501054 132.035)
		(end 136.7375 133.271446)
		(width 0.125)
		(layer "In5.Cu")
		(net 745)
	)
	(segment
		(start 134.29 131.265)
		(end 135.06 132.035)
		(width 0.125)
		(layer "In5.Cu")
		(net 745)
	)
	(segment
		(start 134.29 130.51)
		(end 134.29 131.265)
		(width 0.125)
		(layer "In5.Cu")
		(net 745)
	)
	(segment
		(start 135.8 138.385)
		(end 135.3 138.885)
		(width 0.125)
		(layer "In5.Cu")
		(net 745)
	)
	(segment
		(start 136.7375 133.271446)
		(end 136.7375 135.7075)
		(width 0.125)
		(layer "In5.Cu")
		(net 745)
	)
	(segment
		(start 135.8 136.645)
		(end 135.8 138.385)
		(width 0.125)
		(layer "In5.Cu")
		(net 745)
	)
	(segment
		(start 135.06 132.035)
		(end 135.501054 132.035)
		(width 0.125)
		(layer "In5.Cu")
		(net 745)
	)
	(segment
		(start 136.7375 135.7075)
		(end 135.8 136.645)
		(width 0.125)
		(layer "In5.Cu")
		(net 745)
	)
	(segment
		(start 132.99 129.56)
		(end 132.99 130.51)
		(width 0.125)
		(layer "F.Cu")
		(net 746)
	)
	(via
		(at 134.29 135.86)
		(size 0.45)
		(drill 0.1)
		(layers "F.Cu" "B.Cu")
		(remove_unused_layers yes)
		(keep_end_layers yes)
		(zone_layer_connections "In5.Cu")
		(teardrops
			(best_length_ratio 0.4)
			(max_length 1)
			(best_width_ratio 0.9)
			(max_width 2)
			(curved_edges yes)
			(filter_ratio 0.9)
			(enabled yes)
			(allow_two_segments yes)
			(prefer_zone_connections yes)
		)
		(net 746)
	)
	(via
		(at 132.99 130.51)
		(size 0.45)
		(drill 0.1)
		(layers "F.Cu" "B.Cu")
		(remove_unused_layers yes)
		(keep_end_layers yes)
		(zone_layer_connections "In5.Cu")
		(teardrops
			(best_length_ratio 0.4)
			(max_length 1)
			(best_width_ratio 0.9)
			(max_width 2)
			(curved_edges yes)
			(filter_ratio 0.9)
			(enabled yes)
			(allow_two_segments yes)
			(prefer_zone_connections yes)
		)
		(net 746)
	)
	(segment
		(start 132.99 130.51)
		(end 132.99 130.96)
		(width 0.125)
		(layer "In5.Cu")
		(net 746)
	)
	(segment
		(start 134.79 135.36)
		(end 134.29 135.86)
		(width 0.125)
		(layer "In5.Cu")
		(net 746)
	)
	(segment
		(start 134.79 132.76)
		(end 134.79 135.36)
		(width 0.125)
		(layer "In5.Cu")
		(net 746)
	)
	(segment
		(start 132.99 130.96)
		(end 134.79 132.76)
		(width 0.125)
		(layer "In5.Cu")
		(net 746)
	)
	(segment
		(start 131.04 128.71)
		(end 131.04 130.14)
		(width 0.125)
		(layer "F.Cu")
		(net 747)
	)
	(via
		(at 131.04 130.14)
		(size 0.45)
		(drill 0.1)
		(layers "F.Cu" "B.Cu")
		(remove_unused_layers yes)
		(keep_end_layers yes)
		(zone_layer_connections "In2.Cu")
		(teardrops
			(best_length_ratio 0.4)
			(max_length 1)
			(best_width_ratio 0.9)
			(max_width 2)
			(curved_edges yes)
			(filter_ratio 0.9)
			(enabled yes)
			(allow_two_segments yes)
			(prefer_zone_connections yes)
		)
		(net 747)
	)
	(via
		(at 130.29 139.86)
		(size 0.45)
		(drill 0.1)
		(layers "F.Cu" "B.Cu")
		(remove_unused_layers yes)
		(keep_end_layers yes)
		(zone_layer_connections "In2.Cu")
		(teardrops
			(best_length_ratio 0.4)
			(max_length 1)
			(best_width_ratio 0.9)
			(max_width 2)
			(curved_edges yes)
			(filter_ratio 0.9)
			(enabled yes)
			(allow_two_segments yes)
			(prefer_zone_connections yes)
		)
		(net 747)
	)
	(segment
		(start 131.04 130.87)
		(end 130.79 131.12)
		(width 0.125)
		(layer "In2.Cu")
		(net 747)
	)
	(segment
		(start 130.79 131.12)
		(end 130.79 139.36)
		(width 0.125)
		(layer "In2.Cu")
		(net 747)
	)
	(segment
		(start 130.79 139.36)
		(end 130.29 139.86)
		(width 0.125)
		(layer "In2.Cu")
		(net 747)
	)
	(segment
		(start 131.04 130.14)
		(end 131.04 130.87)
		(width 0.125)
		(layer "In2.Cu")
		(net 747)
	)
	(segment
		(start 129.74 128.71)
		(end 129.74 130.14)
		(width 0.125)
		(layer "F.Cu")
		(net 748)
	)
	(via
		(at 129.74 130.14)
		(size 0.45)
		(drill 0.1)
		(layers "F.Cu" "B.Cu")
		(remove_unused_layers yes)
		(keep_end_layers yes)
		(zone_layer_connections "In5.Cu")
		(teardrops
			(best_length_ratio 0.4)
			(max_length 1)
			(best_width_ratio 0.9)
			(max_width 2)
			(curved_edges yes)
			(filter_ratio 0.9)
			(enabled yes)
			(allow_two_segments yes)
			(prefer_zone_connections yes)
		)
		(net 748)
	)
	(via
		(at 136.29 141.86)
		(size 0.45)
		(drill 0.1)
		(layers "F.Cu" "B.Cu")
		(remove_unused_layers yes)
		(keep_end_layers yes)
		(zone_layer_connections "In5.Cu")
		(teardrops
			(best_length_ratio 0.4)
			(max_length 1)
			(best_width_ratio 0.9)
			(max_width 2)
			(curved_edges yes)
			(filter_ratio 0.9)
			(enabled yes)
			(allow_two_segments yes)
			(prefer_zone_connections yes)
		)
		(net 748)
	)
	(segment
		(start 131.79 137.741281)
		(end 131.79 141.06)
		(width 0.125)
		(layer "In5.Cu")
		(net 748)
	)
	(segment
		(start 130.84 137.028719)
		(end 131.108781 137.2975)
		(width 0.125)
		(layer "In5.Cu")
		(net 748)
	)
	(segment
		(start 132.09 141.36)
		(end 135.79 141.36)
		(width 0.125)
		(layer "In5.Cu")
		(net 748)
	)
	(segment
		(start 135.79 141.36)
		(end 136.29 141.86)
		(width 0.125)
		(layer "In5.Cu")
		(net 748)
	)
	(segment
		(start 130.84 132.791281)
		(end 130.84 137.028719)
		(width 0.125)
		(layer "In5.Cu")
		(net 748)
	)
	(segment
		(start 129.74 130.14)
		(end 129.74 131.691281)
		(width 0.125)
		(layer "In5.Cu")
		(net 748)
	)
	(segment
		(start 131.79 141.06)
		(end 132.09 141.36)
		(width 0.125)
		(layer "In5.Cu")
		(net 748)
	)
	(segment
		(start 131.346219 137.2975)
		(end 131.79 137.741281)
		(width 0.125)
		(layer "In5.Cu")
		(net 748)
	)
	(segment
		(start 131.108781 137.2975)
		(end 131.346219 137.2975)
		(width 0.125)
		(layer "In5.Cu")
		(net 748)
	)
	(segment
		(start 129.74 131.691281)
		(end 130.84 132.791281)
		(width 0.125)
		(layer "In5.Cu")
		(net 748)
	)
	(segment
		(start 136.24 128.71)
		(end 136.24 130.14)
		(width 0.125)
		(layer "F.Cu")
		(net 749)
	)
	(via
		(at 135.29 134.86)
		(size 0.45)
		(drill 0.1)
		(layers "F.Cu" "B.Cu")
		(remove_unused_layers yes)
		(keep_end_layers yes)
		(zone_layer_connections "In2.Cu")
		(teardrops
			(best_length_ratio 0.4)
			(max_length 1)
			(best_width_ratio 0.9)
			(max_width 2)
			(curved_edges yes)
			(filter_ratio 0.9)
			(enabled yes)
			(allow_two_segments yes)
			(prefer_zone_connections yes)
		)
		(net 749)
	)
	(via
		(at 136.24 130.14)
		(size 0.45)
		(drill 0.1)
		(layers "F.Cu" "B.Cu")
		(remove_unused_layers yes)
		(keep_end_layers yes)
		(zone_layer_connections "In2.Cu")
		(teardrops
			(best_length_ratio 0.4)
			(max_length 1)
			(best_width_ratio 0.9)
			(max_width 2)
			(curved_edges yes)
			(filter_ratio 0.9)
			(enabled yes)
			(allow_two_segments yes)
			(prefer_zone_connections yes)
		)
		(net 749)
	)
	(segment
		(start 135.79 131.07)
		(end 135.79 134.36)
		(width 0.125)
		(layer "In2.Cu")
		(net 749)
	)
	(segment
		(start 136.24 130.62)
		(end 135.79 131.07)
		(width 0.125)
		(layer "In2.Cu")
		(net 749)
	)
	(segment
		(start 136.24 130.14)
		(end 136.24 130.62)
		(width 0.125)
		(layer "In2.Cu")
		(net 749)
	)
	(segment
		(start 135.79 134.36)
		(end 135.29 134.86)
		(width 0.125)
		(layer "In2.Cu")
		(net 749)
	)
	(segment
		(start 136.89 129.56)
		(end 136.89 130.51)
		(width 0.125)
		(layer "F.Cu")
		(net 750)
	)
	(via
		(at 136.89 130.51)
		(size 0.45)
		(drill 0.1)
		(layers "F.Cu" "B.Cu")
		(remove_unused_layers yes)
		(keep_end_layers yes)
		(zone_layer_connections "In5.Cu")
		(teardrops
			(best_length_ratio 0.4)
			(max_length 1)
			(best_width_ratio 0.9)
			(max_width 2)
			(curved_edges yes)
			(filter_ratio 0.9)
			(enabled yes)
			(allow_two_segments yes)
			(prefer_zone_connections yes)
		)
		(net 750)
	)
	(via
		(at 136.29 139.86)
		(size 0.45)
		(drill 0.1)
		(layers "F.Cu" "B.Cu")
		(remove_unused_layers yes)
		(keep_end_layers yes)
		(zone_layer_connections "In5.Cu")
		(teardrops
			(best_length_ratio 0.4)
			(max_length 1)
			(best_width_ratio 0.9)
			(max_width 2)
			(curved_edges yes)
			(filter_ratio 0.9)
			(enabled yes)
			(allow_two_segments yes)
			(prefer_zone_connections yes)
		)
		(net 750)
	)
	(segment
		(start 136.8 139.385)
		(end 136.3 139.885)
		(width 0.125)
		(layer "In5.Cu")
		(net 750)
	)
	(segment
		(start 138.7375 132.5875)
		(end 138.7375 137.6975)
		(width 0.125)
		(layer "In5.Cu")
		(net 750)
	)
	(segment
		(start 137.8625 138.5725)
		(end 137.8625 139.2225)
		(width 0.125)
		(layer "In5.Cu")
		(net 750)
	)
	(segment
		(start 136.89 130.74)
		(end 138.7375 132.5875)
		(width 0.125)
		(layer "In5.Cu")
		(net 750)
	)
	(segment
		(start 137.7 139.385)
		(end 136.8 139.385)
		(width 0.125)
		(layer "In5.Cu")
		(net 750)
	)
	(segment
		(start 138.7375 137.6975)
		(end 137.8625 138.5725)
		(width 0.125)
		(layer "In5.Cu")
		(net 750)
	)
	(segment
		(start 137.8625 139.2225)
		(end 137.7 139.385)
		(width 0.125)
		(layer "In5.Cu")
		(net 750)
	)
	(segment
		(start 136.89 130.51)
		(end 136.89 130.74)
		(width 0.125)
		(layer "In5.Cu")
		(net 750)
	)
	(segment
		(start 130.39 129.56)
		(end 130.39 130.51)
		(width 0.125)
		(layer "F.Cu")
		(net 751)
	)
	(via
		(at 136.29 140.86)
		(size 0.45)
		(drill 0.1)
		(layers "F.Cu" "B.Cu")
		(remove_unused_layers yes)
		(keep_end_layers yes)
		(zone_layer_connections "In5.Cu")
		(teardrops
			(best_length_ratio 0.4)
			(max_length 1)
			(best_width_ratio 0.9)
			(max_width 2)
			(curved_edges yes)
			(filter_ratio 0.9)
			(enabled yes)
			(allow_two_segments yes)
			(prefer_zone_connections yes)
		)
		(net 751)
	)
	(via
		(at 130.39 130.51)
		(size 0.45)
		(drill 0.1)
		(layers "F.Cu" "B.Cu")
		(remove_unused_layers yes)
		(keep_end_layers yes)
		(zone_layer_connections "In5.Cu")
		(teardrops
			(best_length_ratio 0.4)
			(max_length 1)
			(best_width_ratio 0.9)
			(max_width 2)
			(curved_edges yes)
			(filter_ratio 0.9)
			(enabled yes)
			(allow_two_segments yes)
			(prefer_zone_connections yes)
		)
		(net 751)
	)
	(segment
		(start 131.9875 137.3225)
		(end 132.356221 137.3225)
		(width 0.125)
		(layer "In5.Cu")
		(net 751)
	)
	(segment
		(start 131.75 132.716281)
		(end 131.75 137.085)
		(width 0.125)
		(layer "In5.Cu")
		(net 751)
	)
	(segment
		(start 131.065 132.385)
		(end 131.418719 132.385)
		(width 0.125)
		(layer "In5.Cu")
		(net 751)
	)
	(segment
		(start 132.76 140.095)
		(end 133.05 140.385)
		(width 0.125)
		(layer "In5.Cu")
		(net 751)
	)
	(segment
		(start 132.76 137.726279)
		(end 132.76 140.095)
		(width 0.125)
		(layer "In5.Cu")
		(net 751)
	)
	(segment
		(start 130.39 130.51)
		(end 130.39 131.71)
		(width 0.125)
		(layer "In5.Cu")
		(net 751)
	)
	(segment
		(start 131.75 137.085)
		(end 131.9875 137.3225)
		(width 0.125)
		(layer "In5.Cu")
		(net 751)
	)
	(segment
		(start 131.418719 132.385)
		(end 131.75 132.716281)
		(width 0.125)
		(layer "In5.Cu")
		(net 751)
	)
	(segment
		(start 135.8 140.385)
		(end 136.3 140.885)
		(width 0.125)
		(layer "In5.Cu")
		(net 751)
	)
	(segment
		(start 130.39 131.71)
		(end 131.065 132.385)
		(width 0.125)
		(layer "In5.Cu")
		(net 751)
	)
	(segment
		(start 133.05 140.385)
		(end 135.8 140.385)
		(width 0.125)
		(layer "In5.Cu")
		(net 751)
	)
	(segment
		(start 132.356221 137.3225)
		(end 132.76 137.726279)
		(width 0.125)
		(layer "In5.Cu")
		(net 751)
	)
	(segment
		(start 139.1 130.46)
		(end 139.1 139.05)
		(width 0.125)
		(layer "F.Cu")
		(net 752)
	)
	(segment
		(start 139.1 139.05)
		(end 138.29 139.86)
		(width 0.125)
		(layer "F.Cu")
		(net 752)
	)
	(segment
		(start 138.2 129.56)
		(end 139.1 130.46)
		(width 0.125)
		(layer "F.Cu")
		(net 752)
	)
	(segment
		(start 138.29 140.86)
		(end 139.6 139.55)
		(width 0.125)
		(layer "F.Cu")
		(net 753)
	)
	(segment
		(start 139.6 139.55)
		(end 139.6 129.46)
		(width 0.125)
		(layer "F.Cu")
		(net 753)
	)
	(segment
		(start 139.6 129.46)
		(end 138.85 128.71)
		(width 0.125)
		(layer "F.Cu")
		(net 753)
	)
	(segment
		(start 131.69 129.56)
		(end 131.69 130.51)
		(width 0.125)
		(layer "F.Cu")
		(net 754)
	)
	(via
		(at 131.69 130.51)
		(size 0.45)
		(drill 0.1)
		(layers "F.Cu" "B.Cu")
		(remove_unused_layers yes)
		(keep_end_layers yes)
		(zone_layer_connections "In5.Cu")
		(teardrops
			(best_length_ratio 0.4)
			(max_length 1)
			(best_width_ratio 0.9)
			(max_width 2)
			(curved_edges yes)
			(filter_ratio 0.9)
			(enabled yes)
			(allow_two_segments yes)
			(prefer_zone_connections yes)
		)
		(net 754)
	)
	(via
		(at 134.29 139.86)
		(size 0.45)
		(drill 0.1)
		(layers "F.Cu" "B.Cu")
		(remove_unused_layers yes)
		(keep_end_layers yes)
		(zone_layer_connections "In5.Cu")
		(teardrops
			(best_length_ratio 0.4)
			(max_length 1)
			(best_width_ratio 0.9)
			(max_width 2)
			(curved_edges yes)
			(filter_ratio 0.9)
			(enabled yes)
			(allow_two_segments yes)
			(prefer_zone_connections yes)
		)
		(net 754)
	)
	(segment
		(start 133.81 137.645)
		(end 133.81 139.395)
		(width 0.125)
		(layer "In5.Cu")
		(net 754)
	)
	(segment
		(start 133.5 137.335)
		(end 133.81 137.645)
		(width 0.125)
		(layer "In5.Cu")
		(net 754)
	)
	(segment
		(start 133.131281 137.335)
		(end 133.5 137.335)
		(width 0.125)
		(layer "In5.Cu")
		(net 754)
	)
	(segment
		(start 132.8 132.766281)
		(end 132.8 137.003719)
		(width 0.125)
		(layer "In5.Cu")
		(net 754)
	)
	(segment
		(start 132.418719 132.385)
		(end 132.8 132.766281)
		(width 0.125)
		(layer "In5.Cu")
		(net 754)
	)
	(segment
		(start 133.81 139.395)
		(end 134.3 139.885)
		(width 0.125)
		(layer "In5.Cu")
		(net 754)
	)
	(segment
		(start 131.69 132.09)
		(end 131.985 132.385)
		(width 0.125)
		(layer "In5.Cu")
		(net 754)
	)
	(segment
		(start 132.8 137.003719)
		(end 133.131281 137.335)
		(width 0.125)
		(layer "In5.Cu")
		(net 754)
	)
	(segment
		(start 131.69 130.51)
		(end 131.69 132.09)
		(width 0.125)
		(layer "In5.Cu")
		(net 754)
	)
	(segment
		(start 131.985 132.385)
		(end 132.418719 132.385)
		(width 0.125)
		(layer "In5.Cu")
		(net 754)
	)
	(segment
		(start 137.54 128.71)
		(end 137.54 130.14)
		(width 0.125)
		(layer "F.Cu")
		(net 755)
	)
	(via
		(at 137.29 140.86)
		(size 0.45)
		(drill 0.1)
		(layers "F.Cu" "B.Cu")
		(remove_unused_layers yes)
		(keep_end_layers yes)
		(zone_layer_connections "In5.Cu")
		(teardrops
			(best_length_ratio 0.4)
			(max_length 1)
			(best_width_ratio 0.9)
			(max_width 2)
			(curved_edges yes)
			(filter_ratio 0.9)
			(enabled yes)
			(allow_two_segments yes)
			(prefer_zone_connections yes)
		)
		(net 755)
	)
	(via
		(at 137.54 130.14)
		(size 0.45)
		(drill 0.1)
		(layers "F.Cu" "B.Cu")
		(remove_unused_layers yes)
		(keep_end_layers yes)
		(zone_layer_connections "In5.Cu")
		(teardrops
			(best_length_ratio 0.4)
			(max_length 1)
			(best_width_ratio 0.9)
			(max_width 2)
			(curved_edges yes)
			(filter_ratio 0.9)
			(enabled yes)
			(allow_two_segments yes)
			(prefer_zone_connections yes)
		)
		(net 755)
	)
	(segment
		(start 137.54 130.69)
		(end 139.2 132.35)
		(width 0.125)
		(layer "In5.Cu")
		(net 755)
	)
	(segment
		(start 137.54 130.14)
		(end 137.54 130.69)
		(width 0.125)
		(layer "In5.Cu")
		(net 755)
	)
	(segment
		(start 139.2 138.985)
		(end 137.3 140.885)
		(width 0.125)
		(layer "In5.Cu")
		(net 755)
	)
	(segment
		(start 139.2 132.35)
		(end 139.2 138.985)
		(width 0.125)
		(layer "In5.Cu")
		(net 755)
	)
	(segment
		(start 132.34 128.71)
		(end 132.34 130.15)
		(width 0.125)
		(layer "F.Cu")
		(net 756)
	)
	(via
		(at 132.34 130.15)
		(size 0.45)
		(drill 0.1)
		(layers "F.Cu" "B.Cu")
		(remove_unused_layers yes)
		(keep_end_layers yes)
		(zone_layer_connections "In5.Cu")
		(teardrops
			(best_length_ratio 0.4)
			(max_length 1)
			(best_width_ratio 0.9)
			(max_width 2)
			(curved_edges yes)
			(filter_ratio 0.9)
			(enabled yes)
			(allow_two_segments yes)
			(prefer_zone_connections yes)
		)
		(net 756)
	)
	(via
		(at 135.29 139.86)
		(size 0.45)
		(drill 0.1)
		(layers "F.Cu" "B.Cu")
		(remove_unused_layers yes)
		(keep_end_layers yes)
		(zone_layer_connections "In5.Cu")
		(teardrops
			(best_length_ratio 0.4)
			(max_length 1)
			(best_width_ratio 0.9)
			(max_width 2)
			(curved_edges yes)
			(filter_ratio 0.9)
			(enabled yes)
			(allow_two_segments yes)
			(prefer_zone_connections yes)
		)
		(net 756)
	)
	(segment
		(start 132.34 130.15)
		(end 132.41 130.22)
		(width 0.125)
		(layer "In5.Cu")
		(net 756)
	)
	(segment
		(start 132.7375 132.0725)
		(end 133.06 132.395)
		(width 0.125)
		(layer "In5.Cu")
		(net 756)
	)
	(segment
		(start 134.64 137.325)
		(end 134.85 137.535)
		(width 0.125)
		(layer "In5.Cu")
		(net 756)
	)
	(segment
		(start 134.121281 137.325)
		(end 134.64 137.325)
		(width 0.125)
		(layer "In5.Cu")
		(net 756)
	)
	(segment
		(start 134.85 139.435)
		(end 135.3 139.885)
		(width 0.125)
		(layer "In5.Cu")
		(net 756)
	)
	(segment
		(start 133.51 132.395)
		(end 133.8 132.685)
		(width 0.125)
		(layer "In5.Cu")
		(net 756)
	)
	(segment
		(start 132.41 130.22)
		(end 132.41 131.24)
		(width 0.125)
		(layer "In5.Cu")
		(net 756)
	)
	(segment
		(start 133.06 132.395)
		(end 133.51 132.395)
		(width 0.125)
		(layer "In5.Cu")
		(net 756)
	)
	(segment
		(start 134.85 137.535)
		(end 134.85 139.435)
		(width 0.125)
		(layer "In5.Cu")
		(net 756)
	)
	(segment
		(start 133.8 132.685)
		(end 133.8 137.003719)
		(width 0.125)
		(layer "In5.Cu")
		(net 756)
	)
	(segment
		(start 133.8 137.003719)
		(end 134.121281 137.325)
		(width 0.125)
		(layer "In5.Cu")
		(net 756)
	)
	(segment
		(start 132.41 131.24)
		(end 132.7375 131.5675)
		(width 0.125)
		(layer "In5.Cu")
		(net 756)
	)
	(segment
		(start 132.7375 131.5675)
		(end 132.7375 132.0725)
		(width 0.125)
		(layer "In5.Cu")
		(net 756)
	)
	(segment
		(start 128.44 128.71)
		(end 128.44 130.14)
		(width 0.125)
		(layer "F.Cu")
		(net 757)
	)
	(via
		(at 129.29 138.86)
		(size 0.45)
		(drill 0.1)
		(layers "F.Cu" "B.Cu")
		(remove_unused_layers yes)
		(keep_end_layers yes)
		(zone_layer_connections "In5.Cu")
		(teardrops
			(best_length_ratio 0.4)
			(max_length 1)
			(best_width_ratio 0.9)
			(max_width 2)
			(curved_edges yes)
			(filter_ratio 0.9)
			(enabled yes)
			(allow_two_segments yes)
			(prefer_zone_connections yes)
		)
		(net 757)
	)
	(via
		(at 128.44 130.14)
		(size 0.45)
		(drill 0.1)
		(layers "F.Cu" "B.Cu")
		(remove_unused_layers yes)
		(keep_end_layers yes)
		(zone_layer_connections "In5.Cu")
		(teardrops
			(best_length_ratio 0.4)
			(max_length 1)
			(best_width_ratio 0.9)
			(max_width 2)
			(curved_edges yes)
			(filter_ratio 0.9)
			(enabled yes)
			(allow_two_segments yes)
			(prefer_zone_connections yes)
		)
		(net 757)
	)
	(segment
		(start 128.44 133.091281)
		(end 127.84 133.691281)
		(width 0.125)
		(layer "In5.Cu")
		(net 757)
	)
	(segment
		(start 127.84 138.11)
		(end 128.09 138.36)
		(width 0.125)
		(layer "In5.Cu")
		(net 757)
	)
	(segment
		(start 128.09 138.36)
		(end 128.79 138.36)
		(width 0.125)
		(layer "In5.Cu")
		(net 757)
	)
	(segment
		(start 127.84 133.691281)
		(end 127.84 135.06)
		(width 0.125)
		(layer "In5.Cu")
		(net 757)
	)
	(segment
		(start 128.79 138.36)
		(end 129.29 138.86)
		(width 0.125)
		(layer "In5.Cu")
		(net 757)
	)
	(segment
		(start 127.84 137.18)
		(end 127.84 138.11)
		(width 0.125)
		(layer "In5.Cu")
		(net 757)
	)
	(segment
		(start 127.84 135.06)
		(end 128.16 135.38)
		(width 0.125)
		(layer "In5.Cu")
		(net 757)
	)
	(segment
		(start 128.16 136.86)
		(end 127.84 137.18)
		(width 0.125)
		(layer "In5.Cu")
		(net 757)
	)
	(segment
		(start 128.44 130.14)
		(end 128.44 133.091281)
		(width 0.125)
		(layer "In5.Cu")
		(net 757)
	)
	(segment
		(start 128.16 135.38)
		(end 128.16 136.86)
		(width 0.125)
		(layer "In5.Cu")
		(net 757)
	)
	(segment
		(start 127.79 129.56)
		(end 127.79 130.51)
		(width 0.125)
		(layer "F.Cu")
		(net 758)
	)
	(via
		(at 128.29 138.86)
		(size 0.45)
		(drill 0.1)
		(layers "F.Cu" "B.Cu")
		(remove_unused_layers yes)
		(keep_end_layers yes)
		(zone_layer_connections "In5.Cu")
		(teardrops
			(best_length_ratio 0.4)
			(max_length 1)
			(best_width_ratio 0.9)
			(max_width 2)
			(curved_edges yes)
			(filter_ratio 0.9)
			(enabled yes)
			(allow_two_segments yes)
			(prefer_zone_connections yes)
		)
		(net 758)
	)
	(via
		(at 127.79 130.51)
		(size 0.45)
		(drill 0.1)
		(layers "F.Cu" "B.Cu")
		(remove_unused_layers yes)
		(keep_end_layers yes)
		(zone_layer_connections "In5.Cu")
		(teardrops
			(best_length_ratio 0.4)
			(max_length 1)
			(best_width_ratio 0.9)
			(max_width 2)
			(curved_edges yes)
			(filter_ratio 0.9)
			(enabled yes)
			(allow_two_segments yes)
			(prefer_zone_connections yes)
		)
		(net 758)
	)
	(segment
		(start 127.44 138.36)
		(end 127.94 138.86)
		(width 0.125)
		(layer "In5.Cu")
		(net 758)
	)
	(segment
		(start 127.79 136.61)
		(end 127.44 136.96)
		(width 0.125)
		(layer "In5.Cu")
		(net 758)
	)
	(segment
		(start 127.43 135.25)
		(end 127.79 135.61)
		(width 0.125)
		(layer "In5.Cu")
		(net 758)
	)
	(segment
		(start 127.79 133.16)
		(end 127.43 133.52)
		(width 0.125)
		(layer "In5.Cu")
		(net 758)
	)
	(segment
		(start 127.44 136.96)
		(end 127.44 138.36)
		(width 0.125)
		(layer "In5.Cu")
		(net 758)
	)
	(segment
		(start 127.43 133.52)
		(end 127.43 135.25)
		(width 0.125)
		(layer "In5.Cu")
		(net 758)
	)
	(segment
		(start 127.94 138.86)
		(end 128.29 138.86)
		(width 0.125)
		(layer "In5.Cu")
		(net 758)
	)
	(segment
		(start 127.79 130.51)
		(end 127.79 133.16)
		(width 0.125)
		(layer "In5.Cu")
		(net 758)
	)
	(segment
		(start 127.79 135.61)
		(end 127.79 136.61)
		(width 0.125)
		(layer "In5.Cu")
		(net 758)
	)
	(segment
		(start 129.09 129.56)
		(end 129.09 130.51)
		(width 0.125)
		(layer "F.Cu")
		(net 759)
	)
	(via
		(at 129.09 130.51)
		(size 0.45)
		(drill 0.1)
		(layers "F.Cu" "B.Cu")
		(remove_unused_layers yes)
		(keep_end_layers yes)
		(zone_layer_connections "In5.Cu")
		(teardrops
			(best_length_ratio 0.4)
			(max_length 1)
			(best_width_ratio 0.9)
			(max_width 2)
			(curved_edges yes)
			(filter_ratio 0.9)
			(enabled yes)
			(allow_two_segments yes)
			(prefer_zone_connections yes)
		)
		(net 759)
	)
	(via
		(at 131.29 139.86)
		(size 0.45)
		(drill 0.1)
		(layers "F.Cu" "B.Cu")
		(remove_unused_layers yes)
		(keep_end_layers yes)
		(zone_layer_connections "In5.Cu")
		(teardrops
			(best_length_ratio 0.4)
			(max_length 1)
			(best_width_ratio 0.9)
			(max_width 2)
			(curved_edges yes)
			(filter_ratio 0.9)
			(enabled yes)
			(allow_two_segments yes)
			(prefer_zone_connections yes)
		)
		(net 759)
	)
	(segment
		(start 129.09 131.41)
		(end 128.79 131.71)
		(width 0.125)
		(layer "In5.Cu")
		(net 759)
	)
	(segment
		(start 130.8 137.62)
		(end 130.8 139.05)
		(width 0.125)
		(layer "In5.Cu")
		(net 759)
	)
	(segment
		(start 129.09 130.51)
		(end 129.09 131.41)
		(width 0.125)
		(layer "In5.Cu")
		(net 759)
	)
	(segment
		(start 128.79 136.96)
		(end 129.19 137.36)
		(width 0.125)
		(layer "In5.Cu")
		(net 759)
	)
	(segment
		(start 131.29 139.54)
		(end 131.29 139.86)
		(width 0.125)
		(layer "In5.Cu")
		(net 759)
	)
	(segment
		(start 129.19 137.36)
		(end 130.54 137.36)
		(width 0.125)
		(layer "In5.Cu")
		(net 759)
	)
	(segment
		(start 130.54 137.36)
		(end 130.8 137.62)
		(width 0.125)
		(layer "In5.Cu")
		(net 759)
	)
	(segment
		(start 130.8 139.05)
		(end 131.29 139.54)
		(width 0.125)
		(layer "In5.Cu")
		(net 759)
	)
	(segment
		(start 128.79 131.71)
		(end 128.79 136.96)
		(width 0.125)
		(layer "In5.Cu")
		(net 759)
	)
	(segment
		(start 315.287 161.408)
		(end 315.3425 161.4635)
		(width 0.202)
		(layer "F.Cu")
		(net 771)
	)
	(segment
		(start 315.903498 161.688432)
		(end 316.013409 161.798343)
		(width 0.202)
		(layer "F.Cu")
		(net 771)
	)
	(segment
		(start 270.324 159.8055)
		(end 270.2 159.6815)
		(width 0.202)
		(layer "F.Cu")
		(net 771)
	)
	(segment
		(start 203.025 156.685)
		(end 203.025 155.96)
		(width 0.202)
		(layer "F.Cu")
		(net 771)
	)
	(segment
		(start 315.3425 161.4635)
		(end 315.346481 161.4635)
		(width 0.202)
		(layer "F.Cu")
		(net 771)
	)
	(segment
		(start 203.819434 154.4555)
		(end 219.226 154.4555)
		(width 0.202)
		(layer "F.Cu")
		(net 771)
	)
	(segment
		(start 301.861434 161.4635)
		(end 299.869434 163.4555)
		(width 0.202)
		(layer "F.Cu")
		(net 771)
	)
	(segment
		(start 316.296251 161.9155)
		(end 318.0195 161.9155)
		(width 0.202)
		(layer "F.Cu")
		(net 771)
	)
	(segment
		(start 203.025 155.96)
		(end 203.0805 155.9045)
		(width 0.202)
		(layer "F.Cu")
		(net 771)
	)
	(segment
		(start 299.869434 163.4555)
		(end 280.930566 163.4555)
		(width 0.202)
		(layer "F.Cu")
		(net 771)
	)
	(segment
		(start 314.363 161.408)
		(end 314.3075 161.4635)
		(width 0.202)
		(layer "F.Cu")
		(net 771)
	)
	(segment
		(start 203.0805 155.9045)
		(end 203.0805 155.194434)
		(width 0.202)
		(layer "F.Cu")
		(net 771)
	)
	(segment
		(start 203.0805 155.194434)
		(end 203.819434 154.4555)
		(width 0.202)
		(layer "F.Cu")
		(net 771)
	)
	(segment
		(start 318.0195 161.9155)
		(end 318.225 161.71)
		(width 0.202)
		(layer "F.Cu")
		(net 771)
	)
	(segment
		(start 314.3075 161.4635)
		(end 301.861434 161.4635)
		(width 0.202)
		(layer "F.Cu")
		(net 771)
	)
	(segment
		(start 219.226 154.4555)
		(end 219.35 154.3315)
		(width 0.202)
		(layer "F.Cu")
		(net 771)
	)
	(segment
		(start 277.280566 159.8055)
		(end 270.324 159.8055)
		(width 0.202)
		(layer "F.Cu")
		(net 771)
	)
	(segment
		(start 315.135 161.41)
		(end 314.363 161.41)
		(width 0.202)
		(layer "F.Cu")
		(net 771)
	)
	(segment
		(start 280.930566 163.4555)
		(end 277.280566 159.8055)
		(width 0.202)
		(layer "F.Cu")
		(net 771)
	)
	(segment
		(start 315.346481 161.4635)
		(end 315.360446 161.4635)
		(width 0.202)
		(layer "F.Cu")
		(net 771)
	)
	(via
		(at 270.2 159.6815)
		(size 0.45)
		(drill 0.1)
		(layers "F.Cu" "B.Cu")
		(teardrops
			(best_length_ratio 0.4)
			(max_length 1)
			(best_width_ratio 0.9)
			(max_width 2)
			(curved_edges yes)
			(filter_ratio 0.9)
			(enabled yes)
			(allow_two_segments yes)
			(prefer_zone_connections yes)
		)
		(net 771)
	)
	(via
		(at 219.35 154.3315)
		(size 0.45)
		(drill 0.1)
		(layers "F.Cu" "B.Cu")
		(teardrops
			(best_length_ratio 0.4)
			(max_length 1)
			(best_width_ratio 0.9)
			(max_width 2)
			(curved_edges yes)
			(filter_ratio 0.9)
			(enabled yes)
			(allow_two_segments yes)
			(prefer_zone_connections yes)
		)
		(net 771)
	)
	(arc
		(start 315.903498 161.688432)
		(mid 315.654344 161.521955)
		(end 315.360446 161.4635)
		(width 0.202)
		(layer "F.Cu")
		(net 771)
	)
	(arc
		(start 316.013409 161.798343)
		(mid 316.143178 161.885052)
		(end 316.296251 161.9155)
		(width 0.202)
		(layer "F.Cu")
		(net 771)
	)
	(segment
		(start 225.730566 154.8555)
		(end 233.980566 163.1055)
		(width 0.202)
		(layer "B.Cu")
		(net 771)
	)
	(segment
		(start 233.980566 163.1055)
		(end 252.719434 163.1055)
		(width 0.202)
		(layer "B.Cu")
		(net 771)
	)
	(segment
		(start 254.219434 161.6055)
		(end 258.419434 161.6055)
		(width 0.202)
		(layer "B.Cu")
		(net 771)
	)
	(segment
		(start 270.076 159.8055)
		(end 270.2 159.6815)
		(width 0.202)
		(layer "B.Cu")
		(net 771)
	)
	(segment
		(start 219.35 154.3315)
		(end 219.474 154.4555)
		(width 0.202)
		(layer "B.Cu")
		(net 771)
	)
	(segment
		(start 219.474 154.4555)
		(end 220.380566 154.4555)
		(width 0.202)
		(layer "B.Cu")
		(net 771)
	)
	(segment
		(start 258.419434 161.6055)
		(end 260.219434 159.8055)
		(width 0.202)
		(layer "B.Cu")
		(net 771)
	)
	(segment
		(start 260.219434 159.8055)
		(end 270.076 159.8055)
		(width 0.202)
		(layer "B.Cu")
		(net 771)
	)
	(segment
		(start 220.380566 154.4555)
		(end 220.780566 154.8555)
		(width 0.202)
		(layer "B.Cu")
		(net 771)
	)
	(segment
		(start 220.780566 154.8555)
		(end 225.730566 154.8555)
		(width 0.202)
		(layer "B.Cu")
		(net 771)
	)
	(segment
		(start 252.719434 163.1055)
		(end 254.219434 161.6055)
		(width 0.202)
		(layer "B.Cu")
		(net 771)
	)
	(segment
		(start 318.0195 162.3045)
		(end 318.225 162.51)
		(width 0.202)
		(layer "F.Cu")
		(net 772)
	)
	(segment
		(start 207.339708 155.138454)
		(end 207.339708 155.0445)
		(width 0.202)
		(layer "F.Cu")
		(net 772)
	)
	(segment
		(start 203.980566 154.8445)
		(end 206.639708 154.8445)
		(width 0.202)
		(layer "F.Cu")
		(net 772)
	)
	(segment
		(start 207.539708 154.8445)
		(end 207.639708 154.8445)
		(width 0.202)
		(layer "F.Cu")
		(net 772)
	)
	(segment
		(start 203.4695 155.9045)
		(end 203.4695 155.355566)
		(width 0.202)
		(layer "F.Cu")
		(net 772)
	)
	(segment
		(start 203.4695 155.355566)
		(end 203.980566 154.8445)
		(width 0.202)
		(layer "F.Cu")
		(net 772)
	)
	(segment
		(start 203.525 155.96)
		(end 203.4695 155.9045)
		(width 0.202)
		(layer "F.Cu")
		(net 772)
	)
	(segment
		(start 315.287 161.908)
		(end 315.3425 161.8525)
		(width 0.202)
		(layer "F.Cu")
		(net 772)
	)
	(segment
		(start 207.639708 154.8445)
		(end 208.593262 154.8445)
		(width 0.202)
		(layer "F.Cu")
		(net 772)
	)
	(segment
		(start 300.030566 163.8445)
		(end 280.769434 163.8445)
		(width 0.202)
		(layer "F.Cu")
		(net 772)
	)
	(segment
		(start 206.839708 155.0445)
		(end 206.839708 155.138454)
		(width 0.202)
		(layer "F.Cu")
		(net 772)
	)
	(segment
		(start 315.135 161.91)
		(end 314.363 161.91)
		(width 0.202)
		(layer "F.Cu")
		(net 772)
	)
	(segment
		(start 277.119434 160.1945)
		(end 270.324 160.1945)
		(width 0.202)
		(layer "F.Cu")
		(net 772)
	)
	(segment
		(start 208.593262 154.8445)
		(end 219.226 154.8445)
		(width 0.202)
		(layer "F.Cu")
		(net 772)
	)
	(segment
		(start 203.525 156.685)
		(end 203.525 155.96)
		(width 0.202)
		(layer "F.Cu")
		(net 772)
	)
	(segment
		(start 280.769434 163.8445)
		(end 277.119434 160.1945)
		(width 0.202)
		(layer "F.Cu")
		(net 772)
	)
	(segment
		(start 314.3075 161.8525)
		(end 302.022566 161.8525)
		(width 0.202)
		(layer "F.Cu")
		(net 772)
	)
	(segment
		(start 302.022566 161.8525)
		(end 300.030566 163.8445)
		(width 0.202)
		(layer "F.Cu")
		(net 772)
	)
	(segment
		(start 315.634592 161.969658)
		(end 315.74275 162.077816)
		(width 0.202)
		(layer "F.Cu")
		(net 772)
	)
	(segment
		(start 314.363 161.908)
		(end 314.3075 161.8525)
		(width 0.202)
		(layer "F.Cu")
		(net 772)
	)
	(segment
		(start 270.324 160.1945)
		(end 270.2 160.3185)
		(width 0.202)
		(layer "F.Cu")
		(net 772)
	)
	(segment
		(start 315.3425 161.8525)
		(end 315.351749 161.8525)
		(width 0.202)
		(layer "F.Cu")
		(net 772)
	)
	(segment
		(start 207.039708 155.338454)
		(end 207.139708 155.338454)
		(width 0.202)
		(layer "F.Cu")
		(net 772)
	)
	(segment
		(start 219.226 154.8445)
		(end 219.35 154.9685)
		(width 0.202)
		(layer "F.Cu")
		(net 772)
	)
	(segment
		(start 316.290016 162.3045)
		(end 318.0195 162.3045)
		(width 0.202)
		(layer "F.Cu")
		(net 772)
	)
	(via
		(at 270.2 160.3185)
		(size 0.45)
		(drill 0.1)
		(layers "F.Cu" "B.Cu")
		(teardrops
			(best_length_ratio 0.4)
			(max_length 1)
			(best_width_ratio 0.9)
			(max_width 2)
			(curved_edges yes)
			(filter_ratio 0.9)
			(enabled yes)
			(allow_two_segments yes)
			(prefer_zone_connections yes)
		)
		(net 772)
	)
	(via
		(at 219.35 154.9685)
		(size 0.45)
		(drill 0.1)
		(layers "F.Cu" "B.Cu")
		(teardrops
			(best_length_ratio 0.4)
			(max_length 1)
			(best_width_ratio 0.9)
			(max_width 2)
			(curved_edges yes)
			(filter_ratio 0.9)
			(enabled yes)
			(allow_two_segments yes)
			(prefer_zone_connections yes)
		)
		(net 772)
	)
	(arc
		(start 207.139708 155.338454)
		(mid 207.281129 155.279875)
		(end 207.339708 155.138454)
		(width 0.202)
		(layer "F.Cu")
		(net 772)
	)
	(arc
		(start 315.74275 162.077816)
		(mid 315.993838 162.245587)
		(end 316.290016 162.3045)
		(width 0.202)
		(layer "F.Cu")
		(net 772)
	)
	(arc
		(start 206.839708 155.138454)
		(mid 206.898287 155.279875)
		(end 207.039708 155.338454)
		(width 0.202)
		(layer "F.Cu")
		(net 772)
	)
	(arc
		(start 206.639708 154.8445)
		(mid 206.781129 154.903079)
		(end 206.839708 155.0445)
		(width 0.202)
		(layer "F.Cu")
		(net 772)
	)
	(arc
		(start 207.339708 155.0445)
		(mid 207.398287 154.903079)
		(end 207.539708 154.8445)
		(width 0.202)
		(layer "F.Cu")
		(net 772)
	)
	(arc
		(start 315.634592 161.969658)
		(mid 315.504823 161.882949)
		(end 315.351749 161.8525)
		(width 0.202)
		(layer "F.Cu")
		(net 772)
	)
	(segment
		(start 225.569434 155.2445)
		(end 233.819434 163.4945)
		(width 0.202)
		(layer "B.Cu")
		(net 772)
	)
	(segment
		(start 219.35 154.9685)
		(end 219.474 154.8445)
		(width 0.202)
		(layer "B.Cu")
		(net 772)
	)
	(segment
		(start 254.380566 161.9945)
		(end 258.580566 161.9945)
		(width 0.202)
		(layer "B.Cu")
		(net 772)
	)
	(segment
		(start 220.619434 155.2445)
		(end 225.569434 155.2445)
		(width 0.202)
		(layer "B.Cu")
		(net 772)
	)
	(segment
		(start 219.474 154.8445)
		(end 220.219434 154.8445)
		(width 0.202)
		(layer "B.Cu")
		(net 772)
	)
	(segment
		(start 258.580566 161.9945)
		(end 260.380566 160.1945)
		(width 0.202)
		(layer "B.Cu")
		(net 772)
	)
	(segment
		(start 260.380566 160.1945)
		(end 270.076 160.1945)
		(width 0.202)
		(layer "B.Cu")
		(net 772)
	)
	(segment
		(start 270.076 160.1945)
		(end 270.2 160.3185)
		(width 0.202)
		(layer "B.Cu")
		(net 772)
	)
	(segment
		(start 233.819434 163.4945)
		(end 252.880566 163.4945)
		(width 0.202)
		(layer "B.Cu")
		(net 772)
	)
	(segment
		(start 220.219434 154.8445)
		(end 220.619434 155.2445)
		(width 0.202)
		(layer "B.Cu")
		(net 772)
	)
	(segment
		(start 252.880566 163.4945)
		(end 254.380566 161.9945)
		(width 0.202)
		(layer "B.Cu")
		(net 772)
	)
	(segment
		(start 263.218 79.072)
		(end 260.94 81.35)
		(width 0.125)
		(layer "F.Cu")
		(net 780)
	)
	(segment
		(start 260.94 82.999998)
		(end 260.75 83.189999)
		(width 0.125)
		(layer "F.Cu")
		(net 780)
	)
	(segment
		(start 260.75 83.189999)
		(end 259.98 83.189999)
		(width 0.125)
		(layer "F.Cu")
		(net 780)
	)
	(segment
		(start 260.94 81.35)
		(end 260.94 82.999998)
		(width 0.125)
		(layer "F.Cu")
		(net 780)
	)
	(segment
		(start 264.581708 79.072)
		(end 263.218 79.072)
		(width 0.125)
		(layer "F.Cu")
		(net 780)
	)
	(segment
		(start 257.75 80.329999)
		(end 257.75 81.71)
		(width 0.125)
		(layer "F.Cu")
		(net 781)
	)
	(segment
		(start 254.244708 76.66)
		(end 256.4 76.66)
		(width 0.125)
		(layer "F.Cu")
		(net 781)
	)
	(segment
		(start 250.851709 79.072)
		(end 251.832708 79.072)
		(width 0.125)
		(layer "F.Cu")
		(net 781)
	)
	(segment
		(start 257.75 81.71)
		(end 258.6 82.56)
		(width 0.125)
		(layer "F.Cu")
		(net 781)
	)
	(segment
		(start 256.4 78.979999)
		(end 257.75 80.329999)
		(width 0.125)
		(layer "F.Cu")
		(net 781)
	)
	(segment
		(start 256.4 76.66)
		(end 256.4 78.979999)
		(width 0.125)
		(layer "F.Cu")
		(net 781)
	)
	(segment
		(start 258.6 82.56)
		(end 259.98 82.56)
		(width 0.125)
		(layer "F.Cu")
		(net 781)
	)
	(segment
		(start 251.832708 79.072)
		(end 254.244708 76.66)
		(width 0.125)
		(layer "F.Cu")
		(net 781)
	)
	(segment
		(start 258.175707 79.085)
		(end 258.325707 79.235)
		(width 0.125)
		(layer "F.Cu")
		(net 782)
	)
	(segment
		(start 257.550707 79.085)
		(end 258.175707 79.085)
		(width 0.125)
		(layer "F.Cu")
		(net 782)
	)
	(segment
		(start 258.325707 79.235)
		(end 259.125707 79.235)
		(width 0.125)
		(layer "F.Cu")
		(net 782)
	)
	(segment
		(start 259.125707 79.235)
		(end 259.288707 79.072)
		(width 0.125)
		(layer "F.Cu")
		(net 782)
	)
	(segment
		(start 259.288707 79.072)
		(end 260.282708 79.072)
		(width 0.125)
		(layer "F.Cu")
		(net 782)
	)
	(segment
		(start 245.395708 79.235)
		(end 245.558708 79.072)
		(width 0.125)
		(layer "F.Cu")
		(net 783)
	)
	(segment
		(start 243.820708 79.085)
		(end 244.445708 79.085)
		(width 0.125)
		(layer "F.Cu")
		(net 783)
	)
	(segment
		(start 245.558708 79.072)
		(end 246.552709 79.072)
		(width 0.125)
		(layer "F.Cu")
		(net 783)
	)
	(segment
		(start 244.445708 79.085)
		(end 244.595708 79.235)
		(width 0.125)
		(layer "F.Cu")
		(net 783)
	)
	(segment
		(start 244.595708 79.235)
		(end 245.395708 79.235)
		(width 0.125)
		(layer "F.Cu")
		(net 783)
	)
	(segment
		(start 309.257 151.917)
		(end 309.257 152.433)
		(width 0.125)
		(layer "F.Cu")
		(net 784)
	)
	(segment
		(start 308.256 152.433)
		(end 308.256 151.954)
		(width 0.125)
		(layer "F.Cu")
		(net 784)
	)
	(segment
		(start 309.15 151.81)
		(end 309.257 151.917)
		(width 0.125)
		(layer "F.Cu")
		(net 784)
	)
	(segment
		(start 308.756 151.816)
		(end 308.75 151.81)
		(width 0.125)
		(layer "F.Cu")
		(net 784)
	)
	(segment
		(start 308.75 151.81)
		(end 309.15 151.81)
		(width 0.125)
		(layer "F.Cu")
		(net 784)
	)
	(segment
		(start 308.4 151.81)
		(end 308.75 151.81)
		(width 0.125)
		(layer "F.Cu")
		(net 784)
	)
	(segment
		(start 308.756 152.433)
		(end 308.756 151.816)
		(width 0.125)
		(layer "F.Cu")
		(net 784)
	)
	(segment
		(start 308.256 151.954)
		(end 308.4 151.81)
		(width 0.125)
		(layer "F.Cu")
		(net 784)
	)
	(segment
		(start 249.969 132.387)
		(end 249.969 132.887)
		(width 0.125)
		(layer "F.Cu")
		(net 785)
	)
	(segment
		(start 249.0555 132.2995)
		(end 249.8815 132.2995)
		(width 0.125)
		(layer "F.Cu")
		(net 785)
	)
	(segment
		(start 248.968 132.387)
		(end 249.0555 132.2995)
		(width 0.125)
		(layer "F.Cu")
		(net 785)
	)
	(segment
		(start 248.968 132.887)
		(end 248.968 132.387)
		(width 0.125)
		(layer "F.Cu")
		(net 785)
	)
	(segment
		(start 249.8815 132.2995)
		(end 249.969 132.387)
		(width 0.125)
		(layer "F.Cu")
		(net 785)
	)
	(segment
		(start 309.017 80.538)
		(end 309.017 79.354)
		(width 0.125)
		(layer "F.Cu")
		(net 790)
	)
	(segment
		(start 308.519001 80.538)
		(end 308.519 79.814)
		(width 0.125)
		(layer "F.Cu")
		(net 790)
	)
	(segment
		(start 308.519 79.814)
		(end 308.998 79.335)
		(width 0.125)
		(layer "F.Cu")
		(net 790)
	)
	(segment
		(start 201.525 151.135)
		(end 201.525 150.41)
		(width 0.202)
		(layer "F.Cu")
		(net 866)
	)
	(segment
		(start 201.5805 150.3545)
		(end 201.5805 147.894434)
		(width 0.202)
		(layer "F.Cu")
		(net 866)
	)
	(segment
		(start 201.525 150.41)
		(end 201.5805 150.3545)
		(width 0.202)
		(layer "F.Cu")
		(net 866)
	)
	(segment
		(start 268.876 138.9055)
		(end 269 138.7815)
		(width 0.202)
		(layer "F.Cu")
		(net 866)
	)
	(segment
		(start 262.919434 138.9055)
		(end 268.876 138.9055)
		(width 0.202)
		(layer "F.Cu")
		(net 866)
	)
	(segment
		(start 261.919434 139.9055)
		(end 262.919434 138.9055)
		(width 0.202)
		(layer "F.Cu")
		(net 866)
	)
	(segment
		(start 201.5805 147.894434)
		(end 209.569434 139.9055)
		(width 0.202)
		(layer "F.Cu")
		(net 866)
	)
	(segment
		(start 209.569434 139.9055)
		(end 261.919434 139.9055)
		(width 0.202)
		(layer "F.Cu")
		(net 866)
	)
	(via
		(at 269 138.7815)
		(size 0.45)
		(drill 0.1)
		(layers "F.Cu" "B.Cu")
		(teardrops
			(best_length_ratio 0.4)
			(max_length 1)
			(best_width_ratio 0.9)
			(max_width 2)
			(curved_edges yes)
			(filter_ratio 0.9)
			(enabled yes)
			(allow_two_segments yes)
			(prefer_zone_connections yes)
		)
		(net 866)
	)
	(segment
		(start 315.3425 159.9675)
		(end 315.434591 159.9675)
		(width 0.202)
		(layer "B.Cu")
		(net 866)
	)
	(segment
		(start 277.6945 141.719434)
		(end 274.880566 138.9055)
		(width 0.202)
		(layer "B.Cu")
		(net 866)
	)
	(segment
		(start 269.124 138.9055)
		(end 269 138.7815)
		(width 0.202)
		(layer "B.Cu")
		(net 866)
	)
	(segment
		(start 314.365 159.91)
		(end 314.3095 159.9655)
		(width 0.202)
		(layer "B.Cu")
		(net 866)
	)
	(segment
		(start 315.137 159.91)
		(end 314.365 159.91)
		(width 0.202)
		(layer "B.Cu")
		(net 866)
	)
	(segment
		(start 315.576013 159.908921)
		(end 315.707372 159.777562)
		(width 0.202)
		(layer "B.Cu")
		(net 866)
	)
	(segment
		(start 292.430566 162.1055)
		(end 277.6945 147.369434)
		(width 0.202)
		(layer "B.Cu")
		(net 866)
	)
	(segment
		(start 315.287 159.912)
		(end 315.3425 159.9675)
		(width 0.202)
		(layer "B.Cu")
		(net 866)
	)
	(segment
		(start 300.359434 162.1055)
		(end 292.430566 162.1055)
		(width 0.202)
		(layer "B.Cu")
		(net 866)
	)
	(segment
		(start 314.3095 159.9655)
		(end 302.499434 159.9655)
		(width 0.202)
		(layer "B.Cu")
		(net 866)
	)
	(segment
		(start 302.499434 159.9655)
		(end 300.359434 162.1055)
		(width 0.202)
		(layer "B.Cu")
		(net 866)
	)
	(segment
		(start 318.0195 159.5155)
		(end 318.225 159.31)
		(width 0.202)
		(layer "B.Cu")
		(net 866)
	)
	(segment
		(start 316.340046 159.5155)
		(end 318.0195 159.5155)
		(width 0.202)
		(layer "B.Cu")
		(net 866)
	)
	(segment
		(start 274.880566 138.9055)
		(end 269.124 138.9055)
		(width 0.202)
		(layer "B.Cu")
		(net 866)
	)
	(segment
		(start 277.6945 147.369434)
		(end 277.6945 141.719434)
		(width 0.202)
		(layer "B.Cu")
		(net 866)
	)
	(arc
		(start 315.434591 159.9675)
		(mid 315.511128 159.952276)
		(end 315.576013 159.908921)
		(width 0.202)
		(layer "B.Cu")
		(net 866)
	)
	(arc
		(start 315.707372 159.777562)
		(mid 315.997645 159.583608)
		(end 316.340046 159.5155)
		(width 0.202)
		(layer "B.Cu")
		(net 866)
	)
	(segment
		(start 236.65 140.2945)
		(end 262.080566 140.2945)
		(width 0.202)
		(layer "F.Cu")
		(net 867)
	)
	(segment
		(start 234.755787 140.576784)
		(end 234.953503 140.576784)
		(width 0.202)
		(layer "F.Cu")
		(net 867)
	)
	(segment
		(start 262.080566 140.2945)
		(end 263.080566 139.2945)
		(width 0.202)
		(layer "F.Cu")
		(net 867)
	)
	(segment
		(start 263.080566 139.2945)
		(end 268.876 139.2945)
		(width 0.202)
		(layer "F.Cu")
		(net 867)
	)
	(segment
		(start 236.195787 140.2945)
		(end 236.393503 140.2945)
		(width 0.202)
		(layer "F.Cu")
		(net 867)
	)
	(segment
		(start 235.715787 140.576784)
		(end 235.913503 140.576784)
		(width 0.202)
		(layer "F.Cu")
		(net 867)
	)
	(segment
		(start 202.025 151.135)
		(end 202.025 150.41)
		(width 0.202)
		(layer "F.Cu")
		(net 867)
	)
	(segment
		(start 202.025 150.41)
		(end 201.9695 150.3545)
		(width 0.202)
		(layer "F.Cu")
		(net 867)
	)
	(segment
		(start 235.235787 140.2945)
		(end 235.433503 140.2945)
		(width 0.202)
		(layer "F.Cu")
		(net 867)
	)
	(segment
		(start 201.9695 148.055566)
		(end 209.730566 140.2945)
		(width 0.202)
		(layer "F.Cu")
		(net 867)
	)
	(segment
		(start 209.730566 140.2945)
		(end 234.473503 140.2945)
		(width 0.202)
		(layer "F.Cu")
		(net 867)
	)
	(segment
		(start 268.876 139.2945)
		(end 269 139.4185)
		(width 0.202)
		(layer "F.Cu")
		(net 867)
	)
	(segment
		(start 201.9695 150.3545)
		(end 201.9695 148.055566)
		(width 0.202)
		(layer "F.Cu")
		(net 867)
	)
	(segment
		(start 236.393503 140.2945)
		(end 236.65 140.2945)
		(width 0.202)
		(layer "F.Cu")
		(net 867)
	)
	(via
		(at 269 139.4185)
		(size 0.45)
		(drill 0.1)
		(layers "F.Cu" "B.Cu")
		(teardrops
			(best_length_ratio 0.4)
			(max_length 1)
			(best_width_ratio 0.9)
			(max_width 2)
			(curved_edges yes)
			(filter_ratio 0.9)
			(enabled yes)
			(allow_two_segments yes)
			(prefer_zone_connections yes)
		)
		(net 867)
	)
	(arc
		(start 234.473503 140.2945)
		(mid 234.573305 140.33584)
		(end 234.614645 140.435642)
		(width 0.202)
		(layer "F.Cu")
		(net 867)
	)
	(arc
		(start 236.054645 140.435642)
		(mid 236.095985 140.33584)
		(end 236.195787 140.2945)
		(width 0.202)
		(layer "F.Cu")
		(net 867)
	)
	(arc
		(start 235.094645 140.435642)
		(mid 235.135985 140.33584)
		(end 235.235787 140.2945)
		(width 0.202)
		(layer "F.Cu")
		(net 867)
	)
	(arc
		(start 234.953503 140.576784)
		(mid 235.053305 140.535444)
		(end 235.094645 140.435642)
		(width 0.202)
		(layer "F.Cu")
		(net 867)
	)
	(arc
		(start 234.614645 140.435642)
		(mid 234.655985 140.535444)
		(end 234.755787 140.576784)
		(width 0.202)
		(layer "F.Cu")
		(net 867)
	)
	(arc
		(start 235.433503 140.2945)
		(mid 235.533305 140.33584)
		(end 235.574645 140.435642)
		(width 0.202)
		(layer "F.Cu")
		(net 867)
	)
	(arc
		(start 235.574645 140.435642)
		(mid 235.615985 140.535444)
		(end 235.715787 140.576784)
		(width 0.202)
		(layer "F.Cu")
		(net 867)
	)
	(arc
		(start 235.913503 140.576784)
		(mid 236.013305 140.535444)
		(end 236.054645 140.435642)
		(width 0.202)
		(layer "F.Cu")
		(net 867)
	)
	(segment
		(start 316.362916 159.9045)
		(end 318.0195 159.9045)
		(width 0.202)
		(layer "B.Cu")
		(net 867)
	)
	(segment
		(start 300.520566 162.4945)
		(end 292.269434 162.4945)
		(width 0.202)
		(layer "B.Cu")
		(net 867)
	)
	(segment
		(start 269.124 139.2945)
		(end 269 139.4185)
		(width 0.202)
		(layer "B.Cu")
		(net 867)
	)
	(segment
		(start 292.269434 162.4945)
		(end 277.3055 147.530566)
		(width 0.202)
		(layer "B.Cu")
		(net 867)
	)
	(segment
		(start 315.844699 160.190367)
		(end 315.96627 160.068796)
		(width 0.202)
		(layer "B.Cu")
		(net 867)
	)
	(segment
		(start 302.660566 160.3545)
		(end 300.520566 162.4945)
		(width 0.202)
		(layer "B.Cu")
		(net 867)
	)
	(segment
		(start 315.287 160.412)
		(end 315.3425 160.3565)
		(width 0.202)
		(layer "B.Cu")
		(net 867)
	)
	(segment
		(start 274.719434 139.2945)
		(end 269.124 139.2945)
		(width 0.202)
		(layer "B.Cu")
		(net 867)
	)
	(segment
		(start 314.3095 160.3545)
		(end 302.660566 160.3545)
		(width 0.202)
		(layer "B.Cu")
		(net 867)
	)
	(segment
		(start 277.3055 141.880566)
		(end 274.719434 139.2945)
		(width 0.202)
		(layer "B.Cu")
		(net 867)
	)
	(segment
		(start 277.3055 147.530566)
		(end 277.3055 141.880566)
		(width 0.202)
		(layer "B.Cu")
		(net 867)
	)
	(segment
		(start 315.137 160.41)
		(end 314.365 160.41)
		(width 0.202)
		(layer "B.Cu")
		(net 867)
	)
	(segment
		(start 314.365 160.41)
		(end 314.3095 160.3545)
		(width 0.202)
		(layer "B.Cu")
		(net 867)
	)
	(segment
		(start 318.0195 159.9045)
		(end 318.225 160.11)
		(width 0.202)
		(layer "B.Cu")
		(net 867)
	)
	(segment
		(start 315.3425 160.3565)
		(end 315.443618 160.3565)
		(width 0.202)
		(layer "B.Cu")
		(net 867)
	)
	(arc
		(start 315.844699 160.190367)
		(mid 315.660681 160.313324)
		(end 315.443618 160.3565)
		(width 0.202)
		(layer "B.Cu")
		(net 867)
	)
	(arc
		(start 316.362916 159.9045)
		(mid 316.148253 159.947199)
		(end 315.96627 160.068796)
		(width 0.202)
		(layer "B.Cu")
		(net 867)
	)
	(segment
		(start 264.219434 140.5055)
		(end 268.876 140.5055)
		(width 0.202)
		(layer "F.Cu")
		(net 868)
	)
	(segment
		(start 203.025 151.135)
		(end 203.025 150.41)
		(width 0.202)
		(layer "F.Cu")
		(net 868)
	)
	(segment
		(start 203.025 150.41)
		(end 203.0805 150.3545)
		(width 0.202)
		(layer "F.Cu")
		(net 868)
	)
	(segment
		(start 263.619434 141.1055)
		(end 264.219434 140.5055)
		(width 0.202)
		(layer "F.Cu")
		(net 868)
	)
	(segment
		(start 203.0805 148.144434)
		(end 210.119434 141.1055)
		(width 0.202)
		(layer "F.Cu")
		(net 868)
	)
	(segment
		(start 210.119434 141.1055)
		(end 263.619434 141.1055)
		(width 0.202)
		(layer "F.Cu")
		(net 868)
	)
	(segment
		(start 268.876 140.5055)
		(end 269 140.3815)
		(width 0.202)
		(layer "F.Cu")
		(net 868)
	)
	(segment
		(start 203.0805 150.3545)
		(end 203.0805 148.144434)
		(width 0.202)
		(layer "F.Cu")
		(net 868)
	)
	(via
		(at 269 140.3815)
		(size 0.45)
		(drill 0.1)
		(layers "F.Cu" "B.Cu")
		(teardrops
			(best_length_ratio 0.4)
			(max_length 1)
			(best_width_ratio 0.9)
			(max_width 2)
			(curved_edges yes)
			(filter_ratio 0.9)
			(enabled yes)
			(allow_two_segments yes)
			(prefer_zone_connections yes)
		)
		(net 868)
	)
	(segment
		(start 301.519434 163.4555)
		(end 290.780566 163.4555)
		(width 0.202)
		(layer "B.Cu")
		(net 868)
	)
	(segment
		(start 316.358187 161.9155)
		(end 318.0195 161.9155)
		(width 0.202)
		(layer "B.Cu")
		(net 868)
	)
	(segment
		(start 314.365 161.408)
		(end 314.3095 161.4635)
		(width 0.202)
		(layer "B.Cu")
		(net 868)
	)
	(segment
		(start 315.287 161.408)
		(end 315.3425 161.4635)
		(width 0.202)
		(layer "B.Cu")
		(net 868)
	)
	(segment
		(start 314.3095 161.4635)
		(end 303.511434 161.4635)
		(width 0.202)
		(layer "B.Cu")
		(net 868)
	)
	(segment
		(start 275.8945 142.619434)
		(end 273.780566 140.5055)
		(width 0.202)
		(layer "B.Cu")
		(net 868)
	)
	(segment
		(start 303.511434 161.4635)
		(end 301.519434 163.4555)
		(width 0.202)
		(layer "B.Cu")
		(net 868)
	)
	(segment
		(start 269.124 140.5055)
		(end 269 140.3815)
		(width 0.202)
		(layer "B.Cu")
		(net 868)
	)
	(segment
		(start 290.780566 163.4555)
		(end 275.8945 148.569434)
		(width 0.202)
		(layer "B.Cu")
		(net 868)
	)
	(segment
		(start 275.8945 148.569434)
		(end 275.8945 142.619434)
		(width 0.202)
		(layer "B.Cu")
		(net 868)
	)
	(segment
		(start 315.83562 161.620554)
		(end 315.969614 161.754548)
		(width 0.202)
		(layer "B.Cu")
		(net 868)
	)
	(segment
		(start 315.3425 161.4635)
		(end 315.456458 161.4635)
		(width 0.202)
		(layer "B.Cu")
		(net 868)
	)
	(segment
		(start 273.780566 140.5055)
		(end 269.124 140.5055)
		(width 0.202)
		(layer "B.Cu")
		(net 868)
	)
	(segment
		(start 318.0195 161.9155)
		(end 318.225 161.71)
		(width 0.202)
		(layer "B.Cu")
		(net 868)
	)
	(segment
		(start 315.137 161.408)
		(end 314.365 161.408)
		(width 0.202)
		(layer "B.Cu")
		(net 868)
	)
	(arc
		(start 315.83562 161.620554)
		(mid 315.661659 161.504317)
		(end 315.456458 161.4635)
		(width 0.202)
		(layer "B.Cu")
		(net 868)
	)
	(arc
		(start 316.358187 161.9155)
		(mid 316.147893 161.87367)
		(end 315.969614 161.754548)
		(width 0.202)
		(layer "B.Cu")
		(net 868)
	)
	(segment
		(start 203.525 151.135)
		(end 203.525 150.41)
		(width 0.202)
		(layer "F.Cu")
		(net 869)
	)
	(segment
		(start 203.4695 148.305566)
		(end 210.280566 141.4945)
		(width 0.202)
		(layer "F.Cu")
		(net 869)
	)
	(segment
		(start 210.280566 141.4945)
		(end 233.29082 141.4945)
		(width 0.202)
		(layer "F.Cu")
		(net 869)
	)
	(segment
		(start 234.06315 141.4945)
		(end 234.27082 141.4945)
		(width 0.202)
		(layer "F.Cu")
		(net 869)
	)
	(segment
		(start 203.4695 150.3545)
		(end 203.4695 148.305566)
		(width 0.202)
		(layer "F.Cu")
		(net 869)
	)
	(segment
		(start 203.525 150.41)
		(end 203.4695 150.3545)
		(width 0.202)
		(layer "F.Cu")
		(net 869)
	)
	(segment
		(start 263.780566 141.4945)
		(end 264.380566 140.8945)
		(width 0.202)
		(layer "F.Cu")
		(net 869)
	)
	(segment
		(start 235.043192 141.4945)
		(end 235.25082 141.4945)
		(width 0.202)
		(layer "F.Cu")
		(net 869)
	)
	(segment
		(start 264.380566 140.8945)
		(end 268.876 140.8945)
		(width 0.202)
		(layer "F.Cu")
		(net 869)
	)
	(segment
		(start 235.25082 141.4945)
		(end 236.552612 141.4945)
		(width 0.202)
		(layer "F.Cu")
		(net 869)
	)
	(segment
		(start 234.553192 141.776872)
		(end 234.76082 141.776872)
		(width 0.202)
		(layer "F.Cu")
		(net 869)
	)
	(segment
		(start 233.57315 141.77683)
		(end 233.78082 141.77683)
		(width 0.202)
		(layer "F.Cu")
		(net 869)
	)
	(segment
		(start 236.552612 141.4945)
		(end 263.780566 141.4945)
		(width 0.202)
		(layer "F.Cu")
		(net 869)
	)
	(segment
		(start 268.876 140.8945)
		(end 269 141.0185)
		(width 0.202)
		(layer "F.Cu")
		(net 869)
	)
	(via
		(at 269 141.0185)
		(size 0.45)
		(drill 0.1)
		(layers "F.Cu" "B.Cu")
		(teardrops
			(best_length_ratio 0.4)
			(max_length 1)
			(best_width_ratio 0.9)
			(max_width 2)
			(curved_edges yes)
			(filter_ratio 0.9)
			(enabled yes)
			(allow_two_segments yes)
			(prefer_zone_connections yes)
		)
		(net 869)
	)
	(arc
		(start 233.921985 141.635665)
		(mid 233.963331 141.535846)
		(end 234.06315 141.4945)
		(width 0.202)
		(layer "F.Cu")
		(net 869)
	)
	(arc
		(start 234.412006 141.635686)
		(mid 234.453358 141.73552)
		(end 234.553192 141.776872)
		(width 0.202)
		(layer "F.Cu")
		(net 869)
	)
	(arc
		(start 233.431985 141.635665)
		(mid 233.473331 141.735484)
		(end 233.57315 141.77683)
		(width 0.202)
		(layer "F.Cu")
		(net 869)
	)
	(arc
		(start 233.78082 141.77683)
		(mid 233.880639 141.735484)
		(end 233.921985 141.635665)
		(width 0.202)
		(layer "F.Cu")
		(net 869)
	)
	(arc
		(start 234.76082 141.776872)
		(mid 234.860654 141.73552)
		(end 234.902006 141.635686)
		(width 0.202)
		(layer "F.Cu")
		(net 869)
	)
	(arc
		(start 234.27082 141.4945)
		(mid 234.370654 141.535852)
		(end 234.412006 141.635686)
		(width 0.202)
		(layer "F.Cu")
		(net 869)
	)
	(arc
		(start 233.29082 141.4945)
		(mid 233.390639 141.535846)
		(end 233.431985 141.635665)
		(width 0.202)
		(layer "F.Cu")
		(net 869)
	)
	(arc
		(start 234.902006 141.635686)
		(mid 234.943358 141.535852)
		(end 235.043192 141.4945)
		(width 0.202)
		(layer "F.Cu")
		(net 869)
	)
	(segment
		(start 269.124 140.8945)
		(end 269 141.0185)
		(width 0.202)
		(layer "B.Cu")
		(net 869)
	)
	(segment
		(start 315.620821 161.955886)
		(end 315.646907 161.981972)
		(width 0.202)
		(layer "B.Cu")
		(net 869)
	)
	(segment
		(start 275.5055 148.730566)
		(end 275.5055 142.780566)
		(width 0.202)
		(layer "B.Cu")
		(net 869)
	)
	(segment
		(start 301.680566 163.8445)
		(end 290.619434 163.8445)
		(width 0.202)
		(layer "B.Cu")
		(net 869)
	)
	(segment
		(start 315.608035 161.943101)
		(end 315.620821 161.955886)
		(width 0.202)
		(layer "B.Cu")
		(net 869)
	)
	(segment
		(start 314.3095 161.8525)
		(end 303.672566 161.8525)
		(width 0.202)
		(layer "B.Cu")
		(net 869)
	)
	(segment
		(start 273.619434 140.8945)
		(end 269.124 140.8945)
		(width 0.202)
		(layer "B.Cu")
		(net 869)
	)
	(segment
		(start 315.576013 161.911079)
		(end 315.608035 161.943101)
		(width 0.202)
		(layer "B.Cu")
		(net 869)
	)
	(segment
		(start 315.287 161.908)
		(end 315.3425 161.8525)
		(width 0.202)
		(layer "B.Cu")
		(net 869)
	)
	(segment
		(start 315.3425 161.8525)
		(end 315.434591 161.8525)
		(width 0.202)
		(layer "B.Cu")
		(net 869)
	)
	(segment
		(start 290.619434 163.8445)
		(end 275.5055 148.730566)
		(width 0.202)
		(layer "B.Cu")
		(net 869)
	)
	(segment
		(start 318.0195 162.3045)
		(end 318.225 162.51)
		(width 0.202)
		(layer "B.Cu")
		(net 869)
	)
	(segment
		(start 315.646907 161.981972)
		(end 315.711085 162.046152)
		(width 0.202)
		(layer "B.Cu")
		(net 869)
	)
	(segment
		(start 314.365 161.908)
		(end 314.3095 161.8525)
		(width 0.202)
		(layer "B.Cu")
		(net 869)
	)
	(segment
		(start 316.334774 162.3045)
		(end 318.0195 162.3045)
		(width 0.202)
		(layer "B.Cu")
		(net 869)
	)
	(segment
		(start 275.5055 142.780566)
		(end 273.619434 140.8945)
		(width 0.202)
		(layer "B.Cu")
		(net 869)
	)
	(segment
		(start 303.672566 161.8525)
		(end 301.680566 163.8445)
		(width 0.202)
		(layer "B.Cu")
		(net 869)
	)
	(segment
		(start 315.137 161.908)
		(end 314.365 161.908)
		(width 0.202)
		(layer "B.Cu")
		(net 869)
	)
	(arc
		(start 315.711085 162.046152)
		(mid 315.997235 162.237357)
		(end 316.334774 162.3045)
		(width 0.202)
		(layer "B.Cu")
		(net 869)
	)
	(arc
		(start 315.576013 161.911079)
		(mid 315.511128 161.867724)
		(end 315.434591 161.8525)
		(width 0.202)
		(layer "B.Cu")
		(net 869)
	)
	(segment
		(start 246.8 131.88)
		(end 245.806001 131.88)
		(width 0.125)
		(layer "F.Cu")
		(net 872)
	)
	(segment
		(start 245.025 131.098999)
		(end 245.8 131.873999)
		(width 0.125)
		(layer "F.Cu")
		(net 872)
	)
	(segment
		(start 245.025 130.56)
		(end 245.025 131.098999)
		(width 0.125)
		(layer "F.Cu")
		(net 872)
	)
	(segment
		(start 243.725 130.56)
		(end 243.725 131.287)
		(width 0.125)
		(layer "F.Cu")
		(net 873)
	)
	(segment
		(start 243.8 131.362)
		(end 243.8 131.874)
		(width 0.125)
		(layer "F.Cu")
		(net 873)
	)
	(segment
		(start 242.8 131.88)
		(end 243.794 131.88)
		(width 0.125)
		(layer "F.Cu")
		(net 873)
	)
	(segment
		(start 243.725 131.287)
		(end 243.8 131.362)
		(width 0.125)
		(layer "F.Cu")
		(net 873)
	)
	(segment
		(start 176.8 144.3)
		(end 177.1 144)
		(width 0.125)
		(layer "F.Cu")
		(net 874)
	)
	(segment
		(start 177.1 144)
		(end 177.92 144)
		(width 0.125)
		(layer "F.Cu")
		(net 874)
	)
	(via
		(at 165.6 144.4)
		(size 0.45)
		(drill 0.1)
		(layers "F.Cu" "B.Cu")
		(teardrops
			(best_length_ratio 0.4)
			(max_length 1)
			(best_width_ratio 0.9)
			(max_width 2)
			(curved_edges yes)
			(filter_ratio 0.9)
			(enabled yes)
			(allow_two_segments yes)
			(prefer_zone_connections yes)
		)
		(net 874)
	)
	(via
		(at 176.8 144.3)
		(size 0.45)
		(drill 0.1)
		(layers "F.Cu" "B.Cu")
		(teardrops
			(best_length_ratio 0.4)
			(max_length 1)
			(best_width_ratio 0.9)
			(max_width 2)
			(curved_edges yes)
			(filter_ratio 0.9)
			(enabled yes)
			(allow_two_segments yes)
			(prefer_zone_connections yes)
		)
		(net 874)
	)
	(segment
		(start 170.5 144.3)
		(end 176.8 144.3)
		(width 0.125)
		(layer "In2.Cu")
		(net 874)
	)
	(segment
		(start 164.9 146.6)
		(end 168.2 146.6)
		(width 0.125)
		(layer "In2.Cu")
		(net 874)
	)
	(segment
		(start 164.7 145.3)
		(end 164.7 146.4)
		(width 0.125)
		(layer "In2.Cu")
		(net 874)
	)
	(segment
		(start 168.2 146.6)
		(end 170.5 144.3)
		(width 0.125)
		(layer "In2.Cu")
		(net 874)
	)
	(segment
		(start 165.6 144.4)
		(end 164.7 145.3)
		(width 0.125)
		(layer "In2.Cu")
		(net 874)
	)
	(segment
		(start 164.7 146.4)
		(end 164.9 146.6)
		(width 0.125)
		(layer "In2.Cu")
		(net 874)
	)
	(segment
		(start 143.2 163.31)
		(end 142.5 162.61)
		(width 0.125)
		(layer "In5.Cu")
		(net 874)
	)
	(segment
		(start 160.625 152.125)
		(end 160.5 152)
		(width 0.125)
		(layer "In5.Cu")
		(net 874)
	)
	(segment
		(start 156.44 162.74)
		(end 159.895 162.74)
		(width 0.125)
		(layer "In5.Cu")
		(net 874)
	)
	(segment
		(start 165.825 152.125)
		(end 160.625 152.125)
		(width 0.125)
		(layer "In5.Cu")
		(net 874)
	)
	(segment
		(start 149.35 157.76)
		(end 150.9 159.31)
		(width 0.125)
		(layer "In5.Cu")
		(net 874)
	)
	(segment
		(start 167.625 157)
		(end 167.625 153.925)
		(width 0.125)
		(layer "In5.Cu")
		(net 874)
	)
	(segment
		(start 142.5 161.26)
		(end 142.8 160.96)
		(width 0.125)
		(layer "In5.Cu")
		(net 874)
	)
	(segment
		(start 160.5 147)
		(end 163.1 144.4)
		(width 0.125)
		(layer "In5.Cu")
		(net 874)
	)
	(segment
		(start 159.895 162.74)
		(end 160.855 163.7)
		(width 0.125)
		(layer "In5.Cu")
		(net 874)
	)
	(segment
		(start 168.3 157.675)
		(end 167.625 157)
		(width 0.125)
		(layer "In5.Cu")
		(net 874)
	)
	(segment
		(start 163.1 144.4)
		(end 165.6 144.4)
		(width 0.125)
		(layer "In5.Cu")
		(net 874)
	)
	(segment
		(start 168.3 163.6)
		(end 168.3 157.675)
		(width 0.125)
		(layer "In5.Cu")
		(net 874)
	)
	(segment
		(start 164.1 163.7)
		(end 164.8 164.4)
		(width 0.125)
		(layer "In5.Cu")
		(net 874)
	)
	(segment
		(start 150.91 159.3)
		(end 153 159.3)
		(width 0.125)
		(layer "In5.Cu")
		(net 874)
	)
	(segment
		(start 153 159.3)
		(end 156.44 162.74)
		(width 0.125)
		(layer "In5.Cu")
		(net 874)
	)
	(segment
		(start 160.855 163.7)
		(end 164.1 163.7)
		(width 0.125)
		(layer "In5.Cu")
		(net 874)
	)
	(segment
		(start 164.8 164.4)
		(end 167.5 164.4)
		(width 0.125)
		(layer "In5.Cu")
		(net 874)
	)
	(segment
		(start 167.5 164.4)
		(end 168.3 163.6)
		(width 0.125)
		(layer "In5.Cu")
		(net 874)
	)
	(segment
		(start 143.573633 160.96)
		(end 143.95 160.583633)
		(width 0.125)
		(layer "In5.Cu")
		(net 874)
	)
	(segment
		(start 143.95 160.583633)
		(end 143.95 159.16)
		(width 0.125)
		(layer "In5.Cu")
		(net 874)
	)
	(segment
		(start 150.9 159.31)
		(end 150.91 159.3)
		(width 0.125)
		(layer "In5.Cu")
		(net 874)
	)
	(segment
		(start 160.5 152)
		(end 160.5 147)
		(width 0.125)
		(layer "In5.Cu")
		(net 874)
	)
	(segment
		(start 142.5 162.61)
		(end 142.5 161.26)
		(width 0.125)
		(layer "In5.Cu")
		(net 874)
	)
	(segment
		(start 145.35 157.76)
		(end 149.35 157.76)
		(width 0.125)
		(layer "In5.Cu")
		(net 874)
	)
	(segment
		(start 142.8 160.96)
		(end 143.573633 160.96)
		(width 0.125)
		(layer "In5.Cu")
		(net 874)
	)
	(segment
		(start 167.625 153.925)
		(end 165.825 152.125)
		(width 0.125)
		(layer "In5.Cu")
		(net 874)
	)
	(segment
		(start 143.95 159.16)
		(end 145.35 157.76)
		(width 0.125)
		(layer "In5.Cu")
		(net 874)
	)
	(segment
		(start 177.92 148)
		(end 175.6 148)
		(width 0.125)
		(layer "F.Cu")
		(net 875)
	)
	(via
		(at 167.9 148.3)
		(size 0.45)
		(drill 0.1)
		(layers "F.Cu" "B.Cu")
		(teardrops
			(best_length_ratio 0.4)
			(max_length 1)
			(best_width_ratio 0.9)
			(max_width 2)
			(curved_edges yes)
			(filter_ratio 0.9)
			(enabled yes)
			(allow_two_segments yes)
			(prefer_zone_connections yes)
		)
		(net 875)
	)
	(via
		(at 175.6 148)
		(size 0.45)
		(drill 0.1)
		(layers "F.Cu" "B.Cu")
		(teardrops
			(best_length_ratio 0.4)
			(max_length 1)
			(best_width_ratio 0.9)
			(max_width 2)
			(curved_edges yes)
			(filter_ratio 0.9)
			(enabled yes)
			(allow_two_segments yes)
			(prefer_zone_connections yes)
		)
		(net 875)
	)
	(segment
		(start 167.9 148.3)
		(end 175.3 148.3)
		(width 0.125)
		(layer "In2.Cu")
		(net 875)
	)
	(segment
		(start 175.3 148.3)
		(end 175.6 148)
		(width 0.125)
		(layer "In2.Cu")
		(net 875)
	)
	(segment
		(start 149.171367 169.36)
		(end 145.171367 165.36)
		(width 0.125)
		(layer "In5.Cu")
		(net 875)
	)
	(segment
		(start 172.4 165)
		(end 171.6 165.8)
		(width 0.125)
		(layer "In5.Cu")
		(net 875)
	)
	(segment
		(start 168.925 152.635)
		(end 168.925 156.3)
		(width 0.125)
		(layer "In5.Cu")
		(net 875)
	)
	(segment
		(start 141.81 163.118111)
		(end 141.81 162.51)
		(width 0.125)
		(layer "In5.Cu")
		(net 875)
	)
	(segment
		(start 159.5 171.3)
		(end 157.56 169.36)
		(width 0.125)
		(layer "In5.Cu")
		(net 875)
	)
	(segment
		(start 157.56 169.36)
		(end 149.171367 169.36)
		(width 0.125)
		(layer "In5.Cu")
		(net 875)
	)
	(segment
		(start 170.1 161.6)
		(end 172.4 163.9)
		(width 0.125)
		(layer "In5.Cu")
		(net 875)
	)
	(segment
		(start 171.6 165.8)
		(end 171.6 166.4)
		(width 0.125)
		(layer "In5.Cu")
		(net 875)
	)
	(segment
		(start 170.4 167.6)
		(end 169.1 167.6)
		(width 0.125)
		(layer "In5.Cu")
		(net 875)
	)
	(segment
		(start 165.4 171.3)
		(end 159.5 171.3)
		(width 0.125)
		(layer "In5.Cu")
		(net 875)
	)
	(segment
		(start 167.9 148.3)
		(end 167.9 149.27)
		(width 0.125)
		(layer "In5.Cu")
		(net 875)
	)
	(segment
		(start 167.9 149.27)
		(end 168.33 149.7)
		(width 0.125)
		(layer "In5.Cu")
		(net 875)
	)
	(segment
		(start 142.801889 164.11)
		(end 141.81 163.118111)
		(width 0.125)
		(layer "In5.Cu")
		(net 875)
	)
	(segment
		(start 145.171367 165.36)
		(end 144.629316 165.36)
		(width 0.125)
		(layer "In5.Cu")
		(net 875)
	)
	(segment
		(start 170.1 157.475)
		(end 170.1 161.6)
		(width 0.125)
		(layer "In5.Cu")
		(net 875)
	)
	(segment
		(start 169.1 167.6)
		(end 165.4 171.3)
		(width 0.125)
		(layer "In5.Cu")
		(net 875)
	)
	(segment
		(start 172.4 163.9)
		(end 172.4 165)
		(width 0.125)
		(layer "In5.Cu")
		(net 875)
	)
	(segment
		(start 171.6 166.4)
		(end 170.4 167.6)
		(width 0.125)
		(layer "In5.Cu")
		(net 875)
	)
	(segment
		(start 143.379316 164.11)
		(end 142.801889 164.11)
		(width 0.125)
		(layer "In5.Cu")
		(net 875)
	)
	(segment
		(start 144.629316 165.36)
		(end 143.379316 164.11)
		(width 0.125)
		(layer "In5.Cu")
		(net 875)
	)
	(segment
		(start 168.33 149.7)
		(end 168.33 152.04)
		(width 0.125)
		(layer "In5.Cu")
		(net 875)
	)
	(segment
		(start 168.925 156.3)
		(end 170.1 157.475)
		(width 0.125)
		(layer "In5.Cu")
		(net 875)
	)
	(segment
		(start 168.33 152.04)
		(end 168.925 152.635)
		(width 0.125)
		(layer "In5.Cu")
		(net 875)
	)
	(segment
		(start 143.2 165.86)
		(end 143.2 164.91)
		(width 0.125)
		(layer "B.Cu")
		(net 876)
	)
	(segment
		(start 142.6 167.41)
		(end 142.6 166.46)
		(width 0.125)
		(layer "B.Cu")
		(net 876)
	)
	(segment
		(start 142.05 167.96)
		(end 142.6 167.41)
		(width 0.125)
		(layer "B.Cu")
		(net 876)
	)
	(segment
		(start 141.8 167.21)
		(end 141.8 167.71)
		(width 0.125)
		(layer "B.Cu")
		(net 876)
	)
	(segment
		(start 142.6 166.46)
		(end 143.2 165.86)
		(width 0.125)
		(layer "B.Cu")
		(net 876)
	)
	(segment
		(start 141.8 167.71)
		(end 142.05 167.96)
		(width 0.125)
		(layer "B.Cu")
		(net 876)
	)
	(segment
		(start 142.05 168.68)
		(end 142.05 167.96)
		(width 0.125)
		(layer "B.Cu")
		(net 876)
	)
	(via
		(at 132.13 147.63)
		(size 0.45)
		(drill 0.1)
		(layers "F.Cu" "B.Cu")
		(remove_unused_layers yes)
		(keep_end_layers yes)
		(zone_layer_connections)
		(teardrops
			(best_length_ratio 0.4)
			(max_length 1)
			(best_width_ratio 0.9)
			(max_width 2)
			(curved_edges yes)
			(filter_ratio 0.9)
			(enabled yes)
			(allow_two_segments yes)
			(prefer_zone_connections yes)
		)
		(net 877)
	)
	(segment
		(start 137.29 154.21)
		(end 137.29 154.033891)
		(width 0.16)
		(layer "B.Cu")
		(net 877)
	)
	(segment
		(start 134.388527 152.059692)
		(end 135.399693 151.048529)
		(width 0.16)
		(layer "B.Cu")
		(net 877)
	)
	(segment
		(start 131.985 147.775)
		(end 132.13 147.63)
		(width 0.16)
		(layer "B.Cu")
		(net 877)
	)
	(segment
		(start 136.559351 152.950649)
		(end 136.55935 152.950649)
		(width 0.16)
		(layer "B.Cu")
		(net 877)
	)
	(segment
		(start 137.29 157.024191)
		(end 137.29 157.013903)
		(width 0.16)
		(layer "B.Cu")
		(net 877)
	)
	(segment
		(start 133.631924 151.303089)
		(end 133.766275 151.168739)
		(width 0.16)
		(layer "B.Cu")
		(net 877)
	)
	(segment
		(start 137.59 157.924191)
		(end 137.704017 157.924191)
		(width 0.16)
		(layer "B.Cu")
		(net 877)
	)
	(segment
		(start 137.704017 157.324191)
		(end 137.59 157.324191)
		(width 0.16)
		(layer "B.Cu")
		(net 877)
	)
	(segment
		(start 133.766276 150.157574)
		(end 133.766274 150.157573)
		(width 0.16)
		(layer "B.Cu")
		(net 877)
	)
	(segment
		(start 131.985 147.962084)
		(end 131.985 147.775)
		(width 0.16)
		(layer "B.Cu")
		(net 877)
	)
	(segment
		(start 138.88 159.71)
		(end 138.606447 159.983553)
		(width 0.16)
		(layer "B.Cu")
		(net 877)
	)
	(segment
		(start 137.040679 153.431977)
		(end 136.559351 152.950649)
		(width 0.16)
		(layer "B.Cu")
		(net 877)
	)
	(segment
		(start 136.55935 152.476887)
		(end 136.55935 152.476888)
		(width 0.16)
		(layer "B.Cu")
		(net 877)
	)
	(segment
		(start 137.29 157.013903)
		(end 137.29 156.71)
		(width 0.16)
		(layer "B.Cu")
		(net 877)
	)
	(segment
		(start 136.6937 151.331372)
		(end 136.410857 151.048529)
		(width 0.16)
		(layer "B.Cu")
		(net 877)
	)
	(segment
		(start 137.704017 158.524191)
		(end 137.59 158.524191)
		(width 0.16)
		(layer "B.Cu")
		(net 877)
	)
	(segment
		(start 135.435 155.025)
		(end 136.475 155.025)
		(width 0.16)
		(layer "B.Cu")
		(net 877)
	)
	(segment
		(start 136.475 155.895)
		(end 135.435 155.895)
		(width 0.16)
		(layer "B.Cu")
		(net 877)
	)
	(segment
		(start 136.693701 151.331372)
		(end 136.6937 151.331372)
		(width 0.16)
		(layer "B.Cu")
		(net 877)
	)
	(segment
		(start 137.59 159.124191)
		(end 137.704017 159.124191)
		(width 0.16)
		(layer "B.Cu")
		(net 877)
	)
	(segment
		(start 133.914766 152.059691)
		(end 133.914767 152.059692)
		(width 0.16)
		(layer "B.Cu")
		(net 877)
	)
	(segment
		(start 137.642254 159.983552)
		(end 137.436446 159.777744)
		(width 0.16)
		(layer "B.Cu")
		(net 877)
	)
	(segment
		(start 133.766274 150.157573)
		(end 132.277893 148.669191)
		(width 0.16)
		(layer "B.Cu")
		(net 877)
	)
	(segment
		(start 136.55935 152.476888)
		(end 136.6937 152.342537)
		(width 0.16)
		(layer "B.Cu")
		(net 877)
	)
	(segment
		(start 133.914767 152.059692)
		(end 133.631924 151.776849)
		(width 0.16)
		(layer "B.Cu")
		(net 877)
	)
	(segment
		(start 138.252894 160.129999)
		(end 137.995808 160.129999)
		(width 0.16)
		(layer "B.Cu")
		(net 877)
	)
	(arc
		(start 138.606447 159.983553)
		(mid 138.444235 160.091939)
		(end 138.252894 160.129999)
		(width 0.16)
		(layer "B.Cu")
		(net 877)
	)
	(arc
		(start 137.704017 157.924191)
		(mid 137.916149 157.836323)
		(end 138.004017 157.624191)
		(width 0.16)
		(layer "B.Cu")
		(net 877)
	)
	(arc
		(start 137.704017 159.124191)
		(mid 137.916149 159.036323)
		(end 138.004017 158.824191)
		(width 0.16)
		(layer "B.Cu")
		(net 877)
	)
	(arc
		(start 137.436446 159.777744)
		(mid 137.32806 159.615532)
		(end 137.29 159.424191)
		(width 0.16)
		(layer "B.Cu")
		(net 877)
	)
	(arc
		(start 136.55935 152.950649)
		(mid 136.461231 152.713768)
		(end 136.55935 152.476887)
		(width 0.16)
		(layer "B.Cu")
		(net 877)
	)
	(arc
		(start 135.435 155.895)
		(mid 135.127409 155.767591)
		(end 135 155.46)
		(width 0.16)
		(layer "B.Cu")
		(net 877)
	)
	(arc
		(start 132.277893 148.669191)
		(mid 132.06112 148.344767)
		(end 131.985 147.962084)
		(width 0.16)
		(layer "B.Cu")
		(net 877)
	)
	(arc
		(start 137.29 154.033891)
		(mid 137.225204 153.708137)
		(end 137.040679 153.431977)
		(width 0.16)
		(layer "B.Cu")
		(net 877)
	)
	(arc
		(start 138.004017 158.824191)
		(mid 137.916149 158.612059)
		(end 137.704017 158.524191)
		(width 0.16)
		(layer "B.Cu")
		(net 877)
	)
	(arc
		(start 135 155.46)
		(mid 135.127409 155.152409)
		(end 135.435 155.025)
		(width 0.16)
		(layer "B.Cu")
		(net 877)
	)
	(arc
		(start 137.29 156.71)
		(mid 137.051292 156.133708)
		(end 136.475 155.895)
		(width 0.16)
		(layer "B.Cu")
		(net 877)
	)
	(arc
		(start 133.766275 151.168739)
		(mid 133.975695 150.663157)
		(end 133.766276 150.157574)
		(width 0.16)
		(layer "B.Cu")
		(net 877)
	)
	(arc
		(start 134.388527 152.059692)
		(mid 134.151646 152.157811)
		(end 133.914766 152.059691)
		(width 0.16)
		(layer "B.Cu")
		(net 877)
	)
	(arc
		(start 137.59 157.324191)
		(mid 137.377868 157.236323)
		(end 137.29 157.024191)
		(width 0.16)
		(layer "B.Cu")
		(net 877)
	)
	(arc
		(start 137.29 158.224191)
		(mid 137.377868 158.012059)
		(end 137.59 157.924191)
		(width 0.16)
		(layer "B.Cu")
		(net 877)
	)
	(arc
		(start 136.410857 151.048529)
		(mid 135.905275 150.83911)
		(end 135.399693 151.048529)
		(width 0.16)
		(layer "B.Cu")
		(net 877)
	)
	(arc
		(start 137.59 158.524191)
		(mid 137.377868 158.436323)
		(end 137.29 158.224191)
		(width 0.16)
		(layer "B.Cu")
		(net 877)
	)
	(arc
		(start 133.631924 151.776849)
		(mid 133.533806 151.53997)
		(end 133.631924 151.303089)
		(width 0.16)
		(layer "B.Cu")
		(net 877)
	)
	(arc
		(start 136.475 155.025)
		(mid 137.051292 154.786292)
		(end 137.29 154.21)
		(width 0.16)
		(layer "B.Cu")
		(net 877)
	)
	(arc
		(start 138.004017 157.624191)
		(mid 137.916149 157.412059)
		(end 137.704017 157.324191)
		(width 0.16)
		(layer "B.Cu")
		(net 877)
	)
	(arc
		(start 136.6937 152.342537)
		(mid 136.90312 151.836955)
		(end 136.693701 151.331372)
		(width 0.16)
		(layer "B.Cu")
		(net 877)
	)
	(arc
		(start 137.995808 160.129999)
		(mid 137.804466 160.091939)
		(end 137.642254 159.983552)
		(width 0.16)
		(layer "B.Cu")
		(net 877)
	)
	(arc
		(start 137.29 159.424191)
		(mid 137.377868 159.212059)
		(end 137.59 159.124191)
		(width 0.16)
		(layer "B.Cu")
		(net 877)
	)
	(via
		(at 131.46 147.63)
		(size 0.45)
		(drill 0.1)
		(layers "F.Cu" "B.Cu")
		(remove_unused_layers yes)
		(keep_end_layers yes)
		(zone_layer_connections)
		(teardrops
			(best_length_ratio 0.4)
			(max_length 1)
			(best_width_ratio 0.9)
			(max_width 2)
			(curved_edges yes)
			(filter_ratio 0.9)
			(enabled yes)
			(allow_two_segments yes)
			(prefer_zone_connections yes)
		)
		(net 878)
	)
	(segment
		(start 136.290649 152.208186)
		(end 136.424999 152.073835)
		(width 0.16)
		(layer "B.Cu")
		(net 878)
	)
	(segment
		(start 136.475 156.275)
		(end 135.435 156.275)
		(width 0.16)
		(layer "B.Cu")
		(net 878)
	)
	(segment
		(start 136.290649 153.219351)
		(end 136.290649 153.21935)
		(width 0.16)
		(layer "B.Cu")
		(net 878)
	)
	(segment
		(start 134.657231 152.328396)
		(end 135.668396 151.317231)
		(width 0.16)
		(layer "B.Cu")
		(net 878)
	)
	(segment
		(start 133.363222 151.034387)
		(end 133.497573 150.900037)
		(width 0.16)
		(layer "B.Cu")
		(net 878)
	)
	(segment
		(start 140.26 160.51)
		(end 137.98128 160.51)
		(width 0.16)
		(layer "B.Cu")
		(net 878)
	)
	(segment
		(start 136.91 159.439804)
		(end 136.91 156.71)
		(width 0.16)
		(layer "B.Cu")
		(net 878)
	)
	(segment
		(start 136.763553 153.692255)
		(end 136.290649 153.219351)
		(width 0.16)
		(layer "B.Cu")
		(net 878)
	)
	(segment
		(start 131.605 147.957351)
		(end 131.605 147.775)
		(width 0.16)
		(layer "B.Cu")
		(net 878)
	)
	(segment
		(start 136.91 154.21)
		(end 136.91 154.045809)
		(width 0.16)
		(layer "B.Cu")
		(net 878)
	)
	(segment
		(start 133.646065 152.328394)
		(end 133.363222 152.045551)
		(width 0.16)
		(layer "B.Cu")
		(net 878)
	)
	(segment
		(start 135.435 154.645)
		(end 136.475 154.645)
		(width 0.16)
		(layer "B.Cu")
		(net 878)
	)
	(segment
		(start 133.497572 150.426275)
		(end 132.012542 148.941244)
		(width 0.16)
		(layer "B.Cu")
		(net 878)
	)
	(segment
		(start 131.605 147.775)
		(end 131.46 147.63)
		(width 0.16)
		(layer "B.Cu")
		(net 878)
	)
	(segment
		(start 133.497574 150.426276)
		(end 133.497572 150.426275)
		(width 0.16)
		(layer "B.Cu")
		(net 878)
	)
	(segment
		(start 133.646064 152.328393)
		(end 133.646065 152.328394)
		(width 0.16)
		(layer "B.Cu")
		(net 878)
	)
	(segment
		(start 136.424999 151.600074)
		(end 136.142156 151.317231)
		(width 0.16)
		(layer "B.Cu")
		(net 878)
	)
	(segment
		(start 136.425 151.600074)
		(end 136.424999 151.600074)
		(width 0.16)
		(layer "B.Cu")
		(net 878)
	)
	(segment
		(start 137.383823 160.262525)
		(end 137.156707 160.035409)
		(width 0.16)
		(layer "B.Cu")
		(net 878)
	)
	(arc
		(start 136.424999 152.073835)
		(mid 136.523119 151.836955)
		(end 136.425 151.600074)
		(width 0.16)
		(layer "B.Cu")
		(net 878)
	)
	(arc
		(start 136.290649 153.21935)
		(mid 136.08123 152.713768)
		(end 136.290649 152.208186)
		(width 0.16)
		(layer "B.Cu")
		(net 878)
	)
	(arc
		(start 134.657231 152.328396)
		(mid 134.151646 152.537813)
		(end 133.646064 152.328393)
		(width 0.16)
		(layer "B.Cu")
		(net 878)
	)
	(arc
		(start 136.475 154.645)
		(mid 136.782591 154.517591)
		(end 136.91 154.21)
		(width 0.16)
		(layer "B.Cu")
		(net 878)
	)
	(arc
		(start 136.91 156.71)
		(mid 136.782591 156.402409)
		(end 136.475 156.275)
		(width 0.16)
		(layer "B.Cu")
		(net 878)
	)
	(arc
		(start 135.435 156.275)
		(mid 134.858708 156.036292)
		(end 134.62 155.46)
		(width 0.16)
		(layer "B.Cu")
		(net 878)
	)
	(arc
		(start 136.91 154.045809)
		(mid 136.87194 153.854467)
		(end 136.763553 153.692255)
		(width 0.16)
		(layer "B.Cu")
		(net 878)
	)
	(arc
		(start 133.497573 150.900037)
		(mid 133.595693 150.663157)
		(end 133.497574 150.426276)
		(width 0.16)
		(layer "B.Cu")
		(net 878)
	)
	(arc
		(start 137.98128 160.51)
		(mid 137.657939 160.445683)
		(end 137.383823 160.262525)
		(width 0.16)
		(layer "B.Cu")
		(net 878)
	)
	(arc
		(start 132.012542 148.941244)
		(mid 131.710917 148.48983)
		(end 131.605 147.957351)
		(width 0.16)
		(layer "B.Cu")
		(net 878)
	)
	(arc
		(start 134.62 155.46)
		(mid 134.858708 154.883708)
		(end 135.435 154.645)
		(width 0.16)
		(layer "B.Cu")
		(net 878)
	)
	(arc
		(start 133.363222 152.045551)
		(mid 133.153804 151.53997)
		(end 133.363222 151.034387)
		(width 0.16)
		(layer "B.Cu")
		(net 878)
	)
	(arc
		(start 136.142156 151.317231)
		(mid 135.905276 151.219112)
		(end 135.668396 151.317231)
		(width 0.16)
		(layer "B.Cu")
		(net 878)
	)
	(arc
		(start 137.156707 160.035409)
		(mid 136.974117 159.762143)
		(end 136.91 159.439804)
		(width 0.16)
		(layer "B.Cu")
		(net 878)
	)
	(via
		(at 129.13 147.63)
		(size 0.45)
		(drill 0.1)
		(layers "F.Cu" "B.Cu")
		(remove_unused_layers yes)
		(keep_end_layers yes)
		(zone_layer_connections)
		(teardrops
			(best_length_ratio 0.4)
			(max_length 1)
			(best_width_ratio 0.9)
			(max_width 2)
			(curved_edges yes)
			(filter_ratio 0.9)
			(enabled yes)
			(allow_two_segments yes)
			(prefer_zone_connections yes)
		)
		(net 879)
	)
	(segment
		(start 134.388831 163.680129)
		(end 134.33626 163.627558)
		(width 0.16)
		(layer "B.Cu")
		(net 879)
	)
	(segment
		(start 136.457498 164.752719)
		(end 136.457498 164.762499)
		(width 0.16)
		(layer "B.Cu")
		(net 879)
	)
	(segment
		(start 134.760524 163.680129)
		(end 134.760523 163.680129)
		(width 0.16)
		(layer "B.Cu")
		(net 879)
	)
	(segment
		(start 138.132499 164.762499)
		(end 138.132498 164.752719)
		(width 0.16)
		(layer "B.Cu")
		(net 879)
	)
	(segment
		(start 137.797498 164.752719)
		(end 137.797498 164.762499)
		(width 0.16)
		(layer "B.Cu")
		(net 879)
	)
	(segment
		(start 136.29 164.929999)
		(end 136.280628 164.929999)
		(width 0.16)
		(layer "B.Cu")
		(net 879)
	)
	(segment
		(start 134.760524 163.680128)
		(end 134.760524 163.680129)
		(width 0.16)
		(layer "B.Cu")
		(net 879)
	)
	(segment
		(start 137.127498 164.752695)
		(end 137.127498 164.762499)
		(width 0.16)
		(layer "B.Cu")
		(net 879)
	)
	(segment
		(start 136.792499 164.7625)
		(end 136.792499 164.762499)
		(width 0.16)
		(layer "B.Cu")
		(net 879)
	)
	(segment
		(start 138.132499 164.7625)
		(end 138.132499 164.762499)
		(width 0.16)
		(layer "B.Cu")
		(net 879)
	)
	(segment
		(start 128.985 147.775)
		(end 129.13 147.63)
		(width 0.16)
		(layer "B.Cu")
		(net 879)
	)
	(segment
		(start 138.460001 164.929999)
		(end 138.3 164.929999)
		(width 0.16)
		(layer "B.Cu")
		(net 879)
	)
	(segment
		(start 136.792499 164.762499)
		(end 136.792498 164.752719)
		(width 0.16)
		(layer "B.Cu")
		(net 879)
	)
	(segment
		(start 135.184789 164.104394)
		(end 135.184789 164.104393)
		(width 0.16)
		(layer "B.Cu")
		(net 879)
	)
	(segment
		(start 137.462499 164.7625)
		(end 137.462499 164.762499)
		(width 0.16)
		(layer "B.Cu")
		(net 879)
	)
	(segment
		(start 137.629998 164.929999)
		(end 137.63 164.929999)
		(width 0.16)
		(layer "B.Cu")
		(net 879)
	)
	(segment
		(start 136.289998 164.929999)
		(end 136.29 164.929999)
		(width 0.16)
		(layer "B.Cu")
		(net 879)
	)
	(segment
		(start 138.88 164.51)
		(end 138.460001 164.929999)
		(width 0.16)
		(layer "B.Cu")
		(net 879)
	)
	(segment
		(start 128.985 156.332163)
		(end 128.985 147.775)
		(width 0.16)
		(layer "B.Cu")
		(net 879)
	)
	(segment
		(start 135.184788 164.104394)
		(end 135.184789 164.104394)
		(width 0.16)
		(layer "B.Cu")
		(net 879)
	)
	(segment
		(start 136.959998 164.929999)
		(end 136.96 164.929999)
		(width 0.16)
		(layer "B.Cu")
		(net 879)
	)
	(segment
		(start 134.33626 163.627558)
		(end 130.359711 159.651009)
		(width 0.16)
		(layer "B.Cu")
		(net 879)
	)
	(segment
		(start 135.184789 163.732701)
		(end 135.132217 163.680129)
		(width 0.16)
		(layer "B.Cu")
		(net 879)
	)
	(segment
		(start 137.462499 164.762499)
		(end 137.462498 164.752695)
		(width 0.16)
		(layer "B.Cu")
		(net 879)
	)
	(arc
		(start 137.127498 164.762499)
		(mid 137.078438 164.880939)
		(end 136.959998 164.929999)
		(width 0.16)
		(layer "B.Cu")
		(net 879)
	)
	(arc
		(start 137.797498 164.762499)
		(mid 137.748438 164.880939)
		(end 137.629998 164.929999)
		(width 0.16)
		(layer "B.Cu")
		(net 879)
	)
	(arc
		(start 138.132498 164.752719)
		(mid 138.083438 164.634279)
		(end 137.964998 164.585219)
		(width 0.16)
		(layer "B.Cu")
		(net 879)
	)
	(arc
		(start 135.184789 164.476087)
		(mid 135.107808 164.290241)
		(end 135.184788 164.104394)
		(width 0.16)
		(layer "B.Cu")
		(net 879)
	)
	(arc
		(start 136.624998 164.585219)
		(mid 136.506558 164.634279)
		(end 136.457498 164.752719)
		(width 0.16)
		(layer "B.Cu")
		(net 879)
	)
	(arc
		(start 136.280628 164.929999)
		(mid 135.687564 164.812031)
		(end 135.184789 164.476087)
		(width 0.16)
		(layer "B.Cu")
		(net 879)
	)
	(arc
		(start 137.63 164.929999)
		(mid 137.511559 164.88094)
		(end 137.462499 164.7625)
		(width 0.16)
		(layer "B.Cu")
		(net 879)
	)
	(arc
		(start 135.132217 163.680129)
		(mid 134.946371 163.603148)
		(end 134.760524 163.680128)
		(width 0.16)
		(layer "B.Cu")
		(net 879)
	)
	(arc
		(start 136.792498 164.752719)
		(mid 136.743438 164.634279)
		(end 136.624998 164.585219)
		(width 0.16)
		(layer "B.Cu")
		(net 879)
	)
	(arc
		(start 135.184789 164.104393)
		(mid 135.261769 163.918547)
		(end 135.184789 163.732701)
		(width 0.16)
		(layer "B.Cu")
		(net 879)
	)
	(arc
		(start 137.964998 164.585219)
		(mid 137.846558 164.634279)
		(end 137.797498 164.752719)
		(width 0.16)
		(layer "B.Cu")
		(net 879)
	)
	(arc
		(start 138.3 164.929999)
		(mid 138.181559 164.88094)
		(end 138.132499 164.7625)
		(width 0.16)
		(layer "B.Cu")
		(net 879)
	)
	(arc
		(start 130.359711 159.651009)
		(mid 129.342276 158.12831)
		(end 128.985 156.332163)
		(width 0.16)
		(layer "B.Cu")
		(net 879)
	)
	(arc
		(start 134.760523 163.680129)
		(mid 134.574677 163.757109)
		(end 134.388831 163.680129)
		(width 0.16)
		(layer "B.Cu")
		(net 879)
	)
	(arc
		(start 136.457498 164.762499)
		(mid 136.408438 164.880939)
		(end 136.289998 164.929999)
		(width 0.16)
		(layer "B.Cu")
		(net 879)
	)
	(arc
		(start 137.294998 164.585195)
		(mid 137.176558 164.634255)
		(end 137.127498 164.752695)
		(width 0.16)
		(layer "B.Cu")
		(net 879)
	)
	(arc
		(start 136.96 164.929999)
		(mid 136.841559 164.88094)
		(end 136.792499 164.7625)
		(width 0.16)
		(layer "B.Cu")
		(net 879)
	)
	(arc
		(start 137.462498 164.752695)
		(mid 137.413438 164.634255)
		(end 137.294998 164.585195)
		(width 0.16)
		(layer "B.Cu")
		(net 879)
	)
	(via
		(at 128.46 147.63)
		(size 0.45)
		(drill 0.1)
		(layers "F.Cu" "B.Cu")
		(remove_unused_layers yes)
		(keep_end_layers yes)
		(zone_layer_connections)
		(teardrops
			(best_length_ratio 0.4)
			(max_length 1)
			(best_width_ratio 0.9)
			(max_width 2)
			(curved_edges yes)
			(filter_ratio 0.9)
			(enabled yes)
			(allow_two_segments yes)
			(prefer_zone_connections yes)
		)
		(net 880)
	)
	(segment
		(start 128.605 156.362634)
		(end 128.605 147.775)
		(width 0.16)
		(layer "B.Cu")
		(net 880)
	)
	(segment
		(start 140.26 165.31)
		(end 136.280163 165.31)
		(width 0.16)
		(layer "B.Cu")
		(net 880)
	)
	(segment
		(start 128.605 147.775)
		(end 128.46 147.63)
		(width 0.16)
		(layer "B.Cu")
		(net 880)
	)
	(segment
		(start 134.916416 164.745118)
		(end 130.069466 159.898168)
		(width 0.16)
		(layer "B.Cu")
		(net 880)
	)
	(arc
		(start 134.916416 164.745118)
		(mid 135.542108 165.163192)
		(end 136.280163 165.31)
		(width 0.16)
		(layer "B.Cu")
		(net 880)
	)
	(arc
		(start 130.069466 159.898168)
		(mid 128.985602 158.276051)
		(end 128.605 156.362634)
		(width 0.16)
		(layer "B.Cu")
		(net 880)
	)
	(segment
		(start 311.264999 102.85)
		(end 311.264999 103.350999)
		(width 0.125)
		(layer "F.Cu")
		(net 889)
	)
	(via
		(at 312.075499 136.94)
		(size 0.45)
		(drill 0.1)
		(layers "F.Cu" "B.Cu")
		(remove_unused_layers yes)
		(keep_end_layers yes)
		(zone_layer_connections)
		(teardrops
			(best_length_ratio 0.4)
			(max_length 1)
			(best_width_ratio 0.9)
			(max_width 2)
			(curved_edges yes)
			(filter_ratio 0.9)
			(enabled yes)
			(allow_two_segments yes)
			(prefer_zone_connections yes)
		)
		(net 889)
	)
	(via
		(at 311.264999 102.85)
		(size 0.45)
		(drill 0.1)
		(layers "F.Cu" "B.Cu")
		(remove_unused_layers yes)
		(keep_end_layers yes)
		(zone_layer_connections)
		(teardrops
			(best_length_ratio 0.4)
			(max_length 1)
			(best_width_ratio 0.9)
			(max_width 2)
			(curved_edges yes)
			(filter_ratio 0.9)
			(enabled yes)
			(allow_two_segments yes)
			(prefer_zone_connections yes)
		)
		(net 889)
	)
	(segment
		(start 313.65 135.365499)
		(end 312.075499 136.94)
		(width 0.125)
		(layer "B.Cu")
		(net 889)
	)
	(segment
		(start 313.024999 105.67)
		(end 313.65 106.295001)
		(width 0.125)
		(layer "B.Cu")
		(net 889)
	)
	(segment
		(start 313.024999 104.05)
		(end 311.824999 102.85)
		(width 0.125)
		(layer "B.Cu")
		(net 889)
	)
	(segment
		(start 313.024999 105.67)
		(end 313.024999 104.05)
		(width 0.125)
		(layer "B.Cu")
		(net 889)
	)
	(segment
		(start 313.65 106.295001)
		(end 313.65 135.365499)
		(width 0.125)
		(layer "B.Cu")
		(net 889)
	)
	(segment
		(start 311.824999 102.85)
		(end 311.264999 102.85)
		(width 0.125)
		(layer "B.Cu")
		(net 889)
	)
	(segment
		(start 179.41 88.76)
		(end 178 88.76)
		(width 0.125)
		(layer "B.Cu")
		(net 891)
	)
	(segment
		(start 283.36 76.4)
		(end 283.36 77.58)
		(width 0.125)
		(layer "F.Cu")
		(net 892)
	)
	(segment
		(start 142.5 164.8)
		(end 141.81 164.11)
		(width 0.125)
		(layer "F.Cu")
		(net 893)
	)
	(segment
		(start 142 166.61)
		(end 142.5 166.11)
		(width 0.125)
		(layer "F.Cu")
		(net 893)
	)
	(segment
		(start 142.5 166.11)
		(end 142.5 164.8)
		(width 0.125)
		(layer "F.Cu")
		(net 893)
	)
	(segment
		(start 138.05 167.565)
		(end 139.895 167.565)
		(width 0.125)
		(layer "F.Cu")
		(net 893)
	)
	(segment
		(start 140.85 166.61)
		(end 142 166.61)
		(width 0.125)
		(layer "F.Cu")
		(net 893)
	)
	(segment
		(start 139.895 167.565)
		(end 140.85 166.61)
		(width 0.125)
		(layer "F.Cu")
		(net 893)
	)
	(via
		(at 138.05 167.565)
		(size 0.45)
		(drill 0.1)
		(layers "F.Cu" "B.Cu")
		(remove_unused_layers yes)
		(keep_end_layers yes)
		(zone_layer_connections)
		(teardrops
			(best_length_ratio 0.4)
			(max_length 1)
			(best_width_ratio 0.9)
			(max_width 2)
			(curved_edges yes)
			(filter_ratio 0.9)
			(enabled yes)
			(allow_two_segments yes)
			(prefer_zone_connections yes)
		)
		(net 893)
	)
	(segment
		(start 138.05 168.68)
		(end 138.05 167.565)
		(width 0.125)
		(layer "B.Cu")
		(net 893)
	)
	(segment
		(start 177.919999 146)
		(end 177.92 145.999999)
		(width 0.125)
		(layer "F.Cu")
		(net 894)
	)
	(segment
		(start 176 146)
		(end 177.919999 146)
		(width 0.125)
		(layer "F.Cu")
		(net 894)
	)
	(via
		(at 167.1 147.7)
		(size 0.45)
		(drill 0.1)
		(layers "F.Cu" "B.Cu")
		(teardrops
			(best_length_ratio 0.4)
			(max_length 1)
			(best_width_ratio 0.9)
			(max_width 2)
			(curved_edges yes)
			(filter_ratio 0.9)
			(enabled yes)
			(allow_two_segments yes)
			(prefer_zone_connections yes)
		)
		(net 894)
	)
	(via
		(at 176 146)
		(size 0.45)
		(drill 0.1)
		(layers "F.Cu" "B.Cu")
		(teardrops
			(best_length_ratio 0.4)
			(max_length 1)
			(best_width_ratio 0.9)
			(max_width 2)
			(curved_edges yes)
			(filter_ratio 0.9)
			(enabled yes)
			(allow_two_segments yes)
			(prefer_zone_connections yes)
		)
		(net 894)
	)
	(segment
		(start 141.5 166.46)
		(end 142.15 166.46)
		(width 0.125)
		(layer "B.Cu")
		(net 894)
	)
	(segment
		(start 142.5 166.11)
		(end 142.5 162.41)
		(width 0.125)
		(layer "B.Cu")
		(net 894)
	)
	(segment
		(start 142.5 162.41)
		(end 143.2 161.71)
		(width 0.125)
		(layer "B.Cu")
		(net 894)
	)
	(segment
		(start 142.15 166.46)
		(end 142.5 166.11)
		(width 0.125)
		(layer "B.Cu")
		(net 894)
	)
	(segment
		(start 141.05 168.68)
		(end 141.05 166.91)
		(width 0.125)
		(layer "B.Cu")
		(net 894)
	)
	(segment
		(start 141.05 166.91)
		(end 141.5 166.46)
		(width 0.125)
		(layer "B.Cu")
		(net 894)
	)
	(segment
		(start 167.1 147.7)
		(end 167.6 147.2)
		(width 0.125)
		(layer "In2.Cu")
		(net 894)
	)
	(segment
		(start 167.6 147.2)
		(end 174.8 147.2)
		(width 0.125)
		(layer "In2.Cu")
		(net 894)
	)
	(segment
		(start 174.8 147.2)
		(end 176 146)
		(width 0.125)
		(layer "In2.Cu")
		(net 894)
	)
	(segment
		(start 165.8 149)
		(end 167.1 147.7)
		(width 0.125)
		(layer "In5.Cu")
		(net 894)
	)
	(segment
		(start 146.4075 164.51)
		(end 146.8075 164.91)
		(width 0.125)
		(layer "In5.Cu")
		(net 894)
	)
	(segment
		(start 146.8075 164.91)
		(end 147.95 164.91)
		(width 0.125)
		(layer "In5.Cu")
		(net 894)
	)
	(segment
		(start 168.675 156.475)
		(end 168.675 152.875)
		(width 0.125)
		(layer "In5.Cu")
		(net 894)
	)
	(segment
		(start 145.85 164.51)
		(end 146.4075 164.51)
		(width 0.125)
		(layer "In5.Cu")
		(net 894)
	)
	(segment
		(start 150.128633 165.06)
		(end 153.96 165.06)
		(width 0.125)
		(layer "In5.Cu")
		(net 894)
	)
	(segment
		(start 148.75 165.71)
		(end 149.478633 165.71)
		(width 0.125)
		(layer "In5.Cu")
		(net 894)
	)
	(segment
		(start 162.2 149.8)
		(end 163 149)
		(width 0.125)
		(layer "In5.Cu")
		(net 894)
	)
	(segment
		(start 162.2 150.8)
		(end 162.2 149.8)
		(width 0.125)
		(layer "In5.Cu")
		(net 894)
	)
	(segment
		(start 169.7 157.5)
		(end 168.675 156.475)
		(width 0.125)
		(layer "In5.Cu")
		(net 894)
	)
	(segment
		(start 168.675 152.875)
		(end 166.8 151)
		(width 0.125)
		(layer "In5.Cu")
		(net 894)
	)
	(segment
		(start 172.1 164.7)
		(end 172.1 164.1)
		(width 0.125)
		(layer "In5.Cu")
		(net 894)
	)
	(segment
		(start 168.3 166.8)
		(end 170 166.8)
		(width 0.125)
		(layer "In5.Cu")
		(net 894)
	)
	(segment
		(start 163 149)
		(end 165.8 149)
		(width 0.125)
		(layer "In5.Cu")
		(net 894)
	)
	(segment
		(start 143.2 161.71)
		(end 143.2 162.31)
		(width 0.125)
		(layer "In5.Cu")
		(net 894)
	)
	(segment
		(start 170 166.8)
		(end 172.1 164.7)
		(width 0.125)
		(layer "In5.Cu")
		(net 894)
	)
	(segment
		(start 166.8 151)
		(end 162.4 151)
		(width 0.125)
		(layer "In5.Cu")
		(net 894)
	)
	(segment
		(start 143.2 162.31)
		(end 144.6 163.71)
		(width 0.125)
		(layer "In5.Cu")
		(net 894)
	)
	(segment
		(start 164.1 171)
		(end 168.3 166.8)
		(width 0.125)
		(layer "In5.Cu")
		(net 894)
	)
	(segment
		(start 169.7 161.7)
		(end 169.7 157.5)
		(width 0.125)
		(layer "In5.Cu")
		(net 894)
	)
	(segment
		(start 172.1 164.1)
		(end 169.7 161.7)
		(width 0.125)
		(layer "In5.Cu")
		(net 894)
	)
	(segment
		(start 153.96 165.06)
		(end 159.9 171)
		(width 0.125)
		(layer "In5.Cu")
		(net 894)
	)
	(segment
		(start 147.95 164.91)
		(end 148.75 165.71)
		(width 0.125)
		(layer "In5.Cu")
		(net 894)
	)
	(segment
		(start 159.9 171)
		(end 164.1 171)
		(width 0.125)
		(layer "In5.Cu")
		(net 894)
	)
	(segment
		(start 149.478633 165.71)
		(end 150.128633 165.06)
		(width 0.125)
		(layer "In5.Cu")
		(net 894)
	)
	(segment
		(start 162.4 151)
		(end 162.2 150.8)
		(width 0.125)
		(layer "In5.Cu")
		(net 894)
	)
	(segment
		(start 144.6 163.71)
		(end 145.05 163.71)
		(width 0.125)
		(layer "In5.Cu")
		(net 894)
	)
	(segment
		(start 145.05 163.71)
		(end 145.85 164.51)
		(width 0.125)
		(layer "In5.Cu")
		(net 894)
	)
	(segment
		(start 141 161.72)
		(end 141.81 160.91)
		(width 0.125)
		(layer "F.Cu")
		(net 895)
	)
	(segment
		(start 139.05 167.01)
		(end 140 166.06)
		(width 0.125)
		(layer "F.Cu")
		(net 895)
	)
	(segment
		(start 140 166.06)
		(end 140.6 166.06)
		(width 0.125)
		(layer "F.Cu")
		(net 895)
	)
	(segment
		(start 140.6 166.06)
		(end 141 165.66)
		(width 0.125)
		(layer "F.Cu")
		(net 895)
	)
	(segment
		(start 141 165.66)
		(end 141 161.72)
		(width 0.125)
		(layer "F.Cu")
		(net 895)
	)
	(via
		(at 139.05 167.01)
		(size 0.45)
		(drill 0.1)
		(layers "F.Cu" "B.Cu")
		(remove_unused_layers yes)
		(keep_end_layers yes)
		(zone_layer_connections)
		(teardrops
			(best_length_ratio 0.4)
			(max_length 1)
			(best_width_ratio 0.9)
			(max_width 2)
			(curved_edges yes)
			(filter_ratio 0.9)
			(enabled yes)
			(allow_two_segments yes)
			(prefer_zone_connections yes)
		)
		(net 895)
	)
	(segment
		(start 139.05 168.68)
		(end 139.05 167.01)
		(width 0.125)
		(layer "B.Cu")
		(net 895)
	)
	(segment
		(start 141.550684 161.71)
		(end 142.05 161.71)
		(width 0.125)
		(layer "B.Cu")
		(net 896)
	)
	(segment
		(start 139.95 167.86)
		(end 140.05 167.96)
		(width 0.125)
		(layer "B.Cu")
		(net 896)
	)
	(segment
		(start 139.95 167.21)
		(end 139.95 167.86)
		(width 0.125)
		(layer "B.Cu")
		(net 896)
	)
	(segment
		(start 140.05 168.68)
		(end 140.05 167.96)
		(width 0.125)
		(layer "B.Cu")
		(net 896)
	)
	(segment
		(start 140.55 167.46)
		(end 140.55 166.41)
		(width 0.125)
		(layer "B.Cu")
		(net 896)
	)
	(segment
		(start 141.05 162.210684)
		(end 141.550684 161.71)
		(width 0.125)
		(layer "B.Cu")
		(net 896)
	)
	(segment
		(start 140.55 166.41)
		(end 141.05 165.91)
		(width 0.125)
		(layer "B.Cu")
		(net 896)
	)
	(segment
		(start 140.05 167.96)
		(end 140.55 167.46)
		(width 0.125)
		(layer "B.Cu")
		(net 896)
	)
	(segment
		(start 143.2 160.56)
		(end 143.2 160.11)
		(width 0.125)
		(layer "B.Cu")
		(net 896)
	)
	(segment
		(start 141.05 165.91)
		(end 141.05 162.210684)
		(width 0.125)
		(layer "B.Cu")
		(net 896)
	)
	(segment
		(start 142.05 161.71)
		(end 143.2 160.56)
		(width 0.125)
		(layer "B.Cu")
		(net 896)
	)
	(segment
		(start 137.65 166.431367)
		(end 137.65 161.385)
		(width 0.125)
		(layer "F.Cu")
		(net 897)
	)
	(segment
		(start 141.41 159.71)
		(end 141.81 159.31)
		(width 0.125)
		(layer "F.Cu")
		(net 897)
	)
	(segment
		(start 137.3 167.56)
		(end 137.3 166.781367)
		(width 0.125)
		(layer "F.Cu")
		(net 897)
	)
	(segment
		(start 137.65 161.385)
		(end 138.525 160.51)
		(width 0.125)
		(layer "F.Cu")
		(net 897)
	)
	(segment
		(start 137.3 166.781367)
		(end 137.65 166.431367)
		(width 0.125)
		(layer "F.Cu")
		(net 897)
	)
	(segment
		(start 138.525 160.51)
		(end 139.05 160.51)
		(width 0.125)
		(layer "F.Cu")
		(net 897)
	)
	(segment
		(start 139.85 159.71)
		(end 141.41 159.71)
		(width 0.125)
		(layer "F.Cu")
		(net 897)
	)
	(segment
		(start 139.05 160.51)
		(end 139.85 159.71)
		(width 0.125)
		(layer "F.Cu")
		(net 897)
	)
	(via
		(at 137.3 167.56)
		(size 0.45)
		(drill 0.1)
		(layers "F.Cu" "B.Cu")
		(remove_unused_layers yes)
		(keep_end_layers yes)
		(zone_layer_connections)
		(teardrops
			(best_length_ratio 0.4)
			(max_length 1)
			(best_width_ratio 0.9)
			(max_width 2)
			(curved_edges yes)
			(filter_ratio 0.9)
			(enabled yes)
			(allow_two_segments yes)
			(prefer_zone_connections yes)
		)
		(net 897)
	)
	(segment
		(start 137.05 167.81)
		(end 137.05 168.68)
		(width 0.125)
		(layer "B.Cu")
		(net 897)
	)
	(segment
		(start 137.3 167.56)
		(end 137.05 167.81)
		(width 0.125)
		(layer "B.Cu")
		(net 897)
	)
	(segment
		(start 154.25 163.51)
		(end 154.25 161.679)
		(width 0.125)
		(layer "F.Cu")
		(net 898)
	)
	(segment
		(start 156.8 164.71)
		(end 156.2 164.11)
		(width 0.125)
		(layer "F.Cu")
		(net 898)
	)
	(segment
		(start 156.8 166.7995)
		(end 156.8 164.71)
		(width 0.125)
		(layer "F.Cu")
		(net 898)
	)
	(segment
		(start 154.85 164.11)
		(end 154.25 163.51)
		(width 0.125)
		(layer "F.Cu")
		(net 898)
	)
	(segment
		(start 154.25 161.679)
		(end 154.819 161.11)
		(width 0.125)
		(layer "F.Cu")
		(net 898)
	)
	(segment
		(start 155.779 167.36)
		(end 156.2395 167.36)
		(width 0.125)
		(layer "F.Cu")
		(net 898)
	)
	(segment
		(start 156.2395 167.36)
		(end 156.8 166.7995)
		(width 0.125)
		(layer "F.Cu")
		(net 898)
	)
	(segment
		(start 156.2 164.11)
		(end 154.85 164.11)
		(width 0.125)
		(layer "F.Cu")
		(net 898)
	)
	(segment
		(start 153.35 157.34)
		(end 153.35 164.31)
		(width 0.125)
		(layer "F.Cu")
		(net 899)
	)
	(segment
		(start 154.4 165.36)
		(end 154.819 165.36)
		(width 0.125)
		(layer "F.Cu")
		(net 899)
	)
	(segment
		(start 153.35 164.31)
		(end 154.4 165.36)
		(width 0.125)
		(layer "F.Cu")
		(net 899)
	)
	(segment
		(start 147.19 156.17)
		(end 152.18 156.17)
		(width 0.125)
		(layer "F.Cu")
		(net 899)
	)
	(segment
		(start 152.18 156.17)
		(end 153.35 157.34)
		(width 0.125)
		(layer "F.Cu")
		(net 899)
	)
	(via
		(at 178 108.66)
		(size 0.45)
		(drill 0.1)
		(layers "F.Cu" "B.Cu")
		(remove_unused_layers yes)
		(keep_end_layers yes)
		(zone_layer_connections)
		(teardrops
			(best_length_ratio 0.4)
			(max_length 1)
			(best_width_ratio 0.9)
			(max_width 2)
			(curved_edges yes)
			(filter_ratio 0.9)
			(enabled yes)
			(allow_two_segments yes)
			(prefer_zone_connections yes)
		)
		(net 926)
	)
	(segment
		(start 177.75 108.91)
		(end 177.75 109.46)
		(width 0.125)
		(layer "B.Cu")
		(net 926)
	)
	(segment
		(start 177.75 109.46)
		(end 177.9 109.61)
		(width 0.125)
		(layer "B.Cu")
		(net 926)
	)
	(segment
		(start 177.9 109.61)
		(end 178.84 109.61)
		(width 0.125)
		(layer "B.Cu")
		(net 926)
	)
	(segment
		(start 178 108.66)
		(end 177.75 108.91)
		(width 0.125)
		(layer "B.Cu")
		(net 926)
	)
	(segment
		(start 157.15 164.56)
		(end 157.15 167.41)
		(width 0.125)
		(layer "F.Cu")
		(net 929)
	)
	(segment
		(start 154.819 163.529)
		(end 155.05 163.76)
		(width 0.125)
		(layer "F.Cu")
		(net 929)
	)
	(segment
		(start 154.819 162.11)
		(end 154.819 163.11)
		(width 0.125)
		(layer "F.Cu")
		(net 929)
	)
	(segment
		(start 156.2 168.36)
		(end 155.779 168.36)
		(width 0.125)
		(layer "F.Cu")
		(net 929)
	)
	(segment
		(start 154.819 163.11)
		(end 154.819 163.529)
		(width 0.125)
		(layer "F.Cu")
		(net 929)
	)
	(segment
		(start 156.35 163.76)
		(end 157.15 164.56)
		(width 0.125)
		(layer "F.Cu")
		(net 929)
	)
	(segment
		(start 155.05 163.76)
		(end 156.35 163.76)
		(width 0.125)
		(layer "F.Cu")
		(net 929)
	)
	(segment
		(start 157.15 167.41)
		(end 156.2 168.36)
		(width 0.125)
		(layer "F.Cu")
		(net 929)
	)
	(via
		(at 139.33 156.17)
		(size 0.45)
		(drill 0.1)
		(layers "F.Cu" "B.Cu")
		(remove_unused_layers yes)
		(keep_end_layers yes)
		(zone_layer_connections "In2.Cu")
		(teardrops
			(best_length_ratio 0.4)
			(max_length 1)
			(best_width_ratio 0.9)
			(max_width 2)
			(curved_edges yes)
			(filter_ratio 0.9)
			(enabled yes)
			(allow_two_segments yes)
			(prefer_zone_connections yes)
		)
		(net 930)
	)
	(via
		(at 154.819 167.36)
		(size 0.45)
		(drill 0.1)
		(layers "F.Cu" "B.Cu")
		(remove_unused_layers yes)
		(keep_end_layers yes)
		(zone_layer_connections "In2.Cu")
		(teardrops
			(best_length_ratio 0.4)
			(max_length 1)
			(best_width_ratio 0.9)
			(max_width 2)
			(curved_edges yes)
			(filter_ratio 0.9)
			(enabled yes)
			(allow_two_segments yes)
			(prefer_zone_connections yes)
		)
		(net 930)
	)
	(segment
		(start 140.15 155.36)
		(end 139.34 156.17)
		(width 0.125)
		(layer "In2.Cu")
		(net 930)
	)
	(segment
		(start 152.4 155.36)
		(end 140.15 155.36)
		(width 0.125)
		(layer "In2.Cu")
		(net 930)
	)
	(segment
		(start 154.819 167.36)
		(end 154.819 157.779)
		(width 0.125)
		(layer "In2.Cu")
		(net 930)
	)
	(segment
		(start 154.819 157.779)
		(end 152.4 155.36)
		(width 0.125)
		(layer "In2.Cu")
		(net 930)
	)
	(segment
		(start 139.34 156.17)
		(end 139.33 156.17)
		(width 0.125)
		(layer "In2.Cu")
		(net 930)
	)
	(segment
		(start 154.65 164.46)
		(end 156.1 164.46)
		(width 0.125)
		(layer "F.Cu")
		(net 931)
	)
	(segment
		(start 156.1 164.46)
		(end 156.45 164.81)
		(width 0.125)
		(layer "F.Cu")
		(net 931)
	)
	(segment
		(start 154.819 160.11)
		(end 153.95 160.979)
		(width 0.125)
		(layer "F.Cu")
		(net 931)
	)
	(segment
		(start 156.45 164.81)
		(end 156.45 166.11)
		(width 0.125)
		(layer "F.Cu")
		(net 931)
	)
	(segment
		(start 156.45 166.11)
		(end 156.2 166.36)
		(width 0.125)
		(layer "F.Cu")
		(net 931)
	)
	(segment
		(start 153.95 163.76)
		(end 154.65 164.46)
		(width 0.125)
		(layer "F.Cu")
		(net 931)
	)
	(segment
		(start 154.819 159.11)
		(end 154.819 160.11)
		(width 0.125)
		(layer "F.Cu")
		(net 931)
	)
	(segment
		(start 156.2 166.36)
		(end 155.779 166.36)
		(width 0.125)
		(layer "F.Cu")
		(net 931)
	)
	(segment
		(start 153.95 160.979)
		(end 153.95 163.76)
		(width 0.125)
		(layer "F.Cu")
		(net 931)
	)
	(segment
		(start 152.19 169.37)
		(end 153.2 168.36)
		(width 0.125)
		(layer "F.Cu")
		(net 932)
	)
	(segment
		(start 153.2 168.36)
		(end 154.819 168.36)
		(width 0.125)
		(layer "F.Cu")
		(net 932)
	)
	(segment
		(start 148.29 168.44)
		(end 149.22 169.37)
		(width 0.125)
		(layer "F.Cu")
		(net 932)
	)
	(segment
		(start 149.22 169.37)
		(end 152.19 169.37)
		(width 0.125)
		(layer "F.Cu")
		(net 932)
	)
	(segment
		(start 147.19 168.44)
		(end 148.29 168.44)
		(width 0.125)
		(layer "F.Cu")
		(net 932)
	)
	(via
		(at 112.4 69.16)
		(size 0.45)
		(drill 0.1)
		(layers "F.Cu" "B.Cu")
		(remove_unused_layers yes)
		(keep_end_layers yes)
		(zone_layer_connections)
		(teardrops
			(best_length_ratio 0.4)
			(max_length 1)
			(best_width_ratio 0.9)
			(max_width 2)
			(curved_edges yes)
			(filter_ratio 0.9)
			(enabled yes)
			(allow_two_segments yes)
			(prefer_zone_connections yes)
		)
		(net 933)
	)
	(via
		(at 110.9 69.16)
		(size 0.45)
		(drill 0.1)
		(layers "F.Cu" "B.Cu")
		(remove_unused_layers yes)
		(keep_end_layers yes)
		(zone_layer_connections)
		(teardrops
			(best_length_ratio 0.4)
			(max_length 1)
			(best_width_ratio 0.9)
			(max_width 2)
			(curved_edges yes)
			(filter_ratio 0.9)
			(enabled yes)
			(allow_two_segments yes)
			(prefer_zone_connections yes)
		)
		(net 934)
	)
	(via
		(at 176.6 88.76)
		(size 0.45)
		(drill 0.1)
		(layers "F.Cu" "B.Cu")
		(remove_unused_layers yes)
		(keep_end_layers yes)
		(zone_layer_connections "In2.Cu")
		(teardrops
			(best_length_ratio 0.4)
			(max_length 1)
			(best_width_ratio 0.9)
			(max_width 2)
			(curved_edges yes)
			(filter_ratio 0.9)
			(enabled yes)
			(allow_two_segments yes)
			(prefer_zone_connections yes)
		)
		(net 935)
	)
	(via
		(at 177.6 94.31)
		(size 0.45)
		(drill 0.1)
		(layers "F.Cu" "B.Cu")
		(remove_unused_layers yes)
		(keep_end_layers yes)
		(zone_layer_connections "In2.Cu")
		(teardrops
			(best_length_ratio 0.4)
			(max_length 1)
			(best_width_ratio 0.9)
			(max_width 2)
			(curved_edges yes)
			(filter_ratio 0.9)
			(enabled yes)
			(allow_two_segments yes)
			(prefer_zone_connections yes)
		)
		(net 935)
	)
	(segment
		(start 177.6175 94.3275)
		(end 177.6175 94.7775)
		(width 0.125)
		(layer "B.Cu")
		(net 935)
	)
	(segment
		(start 177.95 95.11)
		(end 178.84 95.11)
		(width 0.125)
		(layer "B.Cu")
		(net 935)
	)
	(segment
		(start 177.6 94.31)
		(end 177.6175 94.3275)
		(width 0.125)
		(layer "B.Cu")
		(net 935)
	)
	(segment
		(start 177.6175 94.7775)
		(end 177.95 95.11)
		(width 0.125)
		(layer "B.Cu")
		(net 935)
	)
	(segment
		(start 176.6 93.61)
		(end 176.6 88.76)
		(width 0.125)
		(layer "In2.Cu")
		(net 935)
	)
	(segment
		(start 177.3 94.31)
		(end 176.6 93.61)
		(width 0.125)
		(layer "In2.Cu")
		(net 935)
	)
	(segment
		(start 177.6 94.31)
		(end 177.3 94.31)
		(width 0.125)
		(layer "In2.Cu")
		(net 935)
	)
	(segment
		(start 288.448 78.688)
		(end 288.448 81.583)
		(width 0.125)
		(layer "F.Cu")
		(net 936)
	)
	(segment
		(start 284.21 75.85)
		(end 284.21 76.61)
		(width 0.125)
		(layer "F.Cu")
		(net 936)
	)
	(segment
		(start 285.16 77.56)
		(end 287.32 77.56)
		(width 0.125)
		(layer "F.Cu")
		(net 936)
	)
	(segment
		(start 284.21 76.61)
		(end 285.16 77.56)
		(width 0.125)
		(layer "F.Cu")
		(net 936)
	)
	(segment
		(start 283.36 75)
		(end 284.21 75.85)
		(width 0.125)
		(layer "F.Cu")
		(net 936)
	)
	(segment
		(start 287.32 77.56)
		(end 288.448 78.688)
		(width 0.125)
		(layer "F.Cu")
		(net 936)
	)
	(via
		(at 116.45 69.16)
		(size 0.45)
		(drill 0.1)
		(layers "F.Cu" "B.Cu")
		(remove_unused_layers yes)
		(keep_end_layers yes)
		(zone_layer_connections)
		(teardrops
			(best_length_ratio 0.4)
			(max_length 1)
			(best_width_ratio 0.9)
			(max_width 2)
			(curved_edges yes)
			(filter_ratio 0.9)
			(enabled yes)
			(allow_two_segments yes)
			(prefer_zone_connections yes)
		)
		(net 937)
	)
	(via
		(at 114.95 69.16)
		(size 0.45)
		(drill 0.1)
		(layers "F.Cu" "B.Cu")
		(remove_unused_layers yes)
		(keep_end_layers yes)
		(zone_layer_connections)
		(teardrops
			(best_length_ratio 0.4)
			(max_length 1)
			(best_width_ratio 0.9)
			(max_width 2)
			(curved_edges yes)
			(filter_ratio 0.9)
			(enabled yes)
			(allow_two_segments yes)
			(prefer_zone_connections yes)
		)
		(net 938)
	)
	(segment
		(start 155.779 165.36)
		(end 155.779 164.939)
		(width 0.125)
		(layer "F.Cu")
		(net 939)
	)
	(segment
		(start 154.25 158.11)
		(end 154.819 158.11)
		(width 0.125)
		(layer "F.Cu")
		(net 939)
	)
	(segment
		(start 153.65 164.06)
		(end 153.65 158.71)
		(width 0.125)
		(layer "F.Cu")
		(net 939)
	)
	(segment
		(start 155.65 164.81)
		(end 154.4 164.81)
		(width 0.125)
		(layer "F.Cu")
		(net 939)
	)
	(segment
		(start 153.65 158.71)
		(end 154.25 158.11)
		(width 0.125)
		(layer "F.Cu")
		(net 939)
	)
	(segment
		(start 154.4 164.81)
		(end 153.65 164.06)
		(width 0.125)
		(layer "F.Cu")
		(net 939)
	)
	(segment
		(start 155.779 164.939)
		(end 155.65 164.81)
		(width 0.125)
		(layer "F.Cu")
		(net 939)
	)
	(segment
		(start 150.35 165.06)
		(end 152.7 165.06)
		(width 0.125)
		(layer "F.Cu")
		(net 940)
	)
	(segment
		(start 145.558719 167.12)
		(end 148.29 167.12)
		(width 0.125)
		(layer "F.Cu")
		(net 940)
	)
	(segment
		(start 148.29 167.12)
		(end 150.35 165.06)
		(width 0.125)
		(layer "F.Cu")
		(net 940)
	)
	(segment
		(start 139.32 168.44)
		(end 144.238719 168.44)
		(width 0.125)
		(layer "F.Cu")
		(net 940)
	)
	(segment
		(start 144.238719 168.44)
		(end 145.558719 167.12)
		(width 0.125)
		(layer "F.Cu")
		(net 940)
	)
	(segment
		(start 154 166.36)
		(end 154.819 166.36)
		(width 0.125)
		(layer "F.Cu")
		(net 940)
	)
	(segment
		(start 152.7 165.06)
		(end 154 166.36)
		(width 0.125)
		(layer "F.Cu")
		(net 940)
	)
	(segment
		(start 122.95 85.06)
		(end 122.529999 85.06)
		(width 0.125)
		(layer "F.Cu")
		(net 941)
	)
	(segment
		(start 123.950001 86.060001)
		(end 122.95 85.06)
		(width 0.125)
		(layer "F.Cu")
		(net 941)
	)
	(segment
		(start 125.945 86.060001)
		(end 123.950001 86.060001)
		(width 0.125)
		(layer "F.Cu")
		(net 941)
	)
	(segment
		(start 123 89.96)
		(end 122.53 89.96)
		(width 0.125)
		(layer "F.Cu")
		(net 942)
	)
	(segment
		(start 123.4 87.61)
		(end 123.4 89.56)
		(width 0.125)
		(layer "F.Cu")
		(net 942)
	)
	(segment
		(start 123.4 89.56)
		(end 123 89.96)
		(width 0.125)
		(layer "F.Cu")
		(net 942)
	)
	(segment
		(start 123.949999 87.060001)
		(end 123.4 87.61)
		(width 0.125)
		(layer "F.Cu")
		(net 942)
	)
	(segment
		(start 125.945 87.060001)
		(end 123.949999 87.060001)
		(width 0.125)
		(layer "F.Cu")
		(net 942)
	)
	(via
		(at 98.82 77.81)
		(size 0.45)
		(drill 0.1)
		(layers "F.Cu" "B.Cu")
		(remove_unused_layers yes)
		(keep_end_layers yes)
		(zone_layer_connections "In5.Cu")
		(teardrops
			(best_length_ratio 0.4)
			(max_length 1)
			(best_width_ratio 0.9)
			(max_width 2)
			(curved_edges yes)
			(filter_ratio 0.9)
			(enabled yes)
			(allow_two_segments yes)
			(prefer_zone_connections yes)
		)
		(net 943)
	)
	(via
		(at 125.945 84.060001)
		(size 0.45)
		(drill 0.1)
		(layers "F.Cu" "B.Cu")
		(remove_unused_layers yes)
		(keep_end_layers yes)
		(zone_layer_connections "In5.Cu")
		(teardrops
			(best_length_ratio 0.4)
			(max_length 1)
			(best_width_ratio 0.9)
			(max_width 2)
			(curved_edges yes)
			(filter_ratio 0.9)
			(enabled yes)
			(allow_two_segments yes)
			(prefer_zone_connections yes)
		)
		(net 943)
	)
	(segment
		(start 99.32 78.31)
		(end 98.82 77.81)
		(width 0.125)
		(layer "In5.Cu")
		(net 943)
	)
	(segment
		(start 105.85 77.71)
		(end 104.55 77.71)
		(width 0.125)
		(layer "In5.Cu")
		(net 943)
	)
	(segment
		(start 104.55 77.71)
		(end 103.95 78.31)
		(width 0.125)
		(layer "In5.Cu")
		(net 943)
	)
	(segment
		(start 103.95 78.31)
		(end 99.32 78.31)
		(width 0.125)
		(layer "In5.Cu")
		(net 943)
	)
	(segment
		(start 112.200001 84.060001)
		(end 105.85 77.71)
		(width 0.125)
		(layer "In5.Cu")
		(net 943)
	)
	(segment
		(start 125.945 84.060001)
		(end 112.200001 84.060001)
		(width 0.125)
		(layer "In5.Cu")
		(net 943)
	)
	(via
		(at 125.945 85.060001)
		(size 0.45)
		(drill 0.1)
		(layers "F.Cu" "B.Cu")
		(remove_unused_layers yes)
		(keep_end_layers yes)
		(zone_layer_connections "In5.Cu")
		(teardrops
			(best_length_ratio 0.4)
			(max_length 1)
			(best_width_ratio 0.9)
			(max_width 2)
			(curved_edges yes)
			(filter_ratio 0.9)
			(enabled yes)
			(allow_two_segments yes)
			(prefer_zone_connections yes)
		)
		(net 944)
	)
	(via
		(at 98.82 78.81)
		(size 0.45)
		(drill 0.1)
		(layers "F.Cu" "B.Cu")
		(remove_unused_layers yes)
		(keep_end_layers yes)
		(zone_layer_connections "In5.Cu")
		(teardrops
			(best_length_ratio 0.4)
			(max_length 1)
			(best_width_ratio 0.9)
			(max_width 2)
			(curved_edges yes)
			(filter_ratio 0.9)
			(enabled yes)
			(allow_two_segments yes)
			(prefer_zone_connections yes)
		)
		(net 944)
	)
	(segment
		(start 125.344999 84.46)
		(end 125.945 85.060001)
		(width 0.125)
		(layer "In5.Cu")
		(net 944)
	)
	(segment
		(start 107.1435 79.9535)
		(end 111.65 84.46)
		(width 0.125)
		(layer "In5.Cu")
		(net 944)
	)
	(segment
		(start 111.65 84.46)
		(end 125.344999 84.46)
		(width 0.125)
		(layer "In5.Cu")
		(net 944)
	)
	(segment
		(start 98.82 78.81)
		(end 99.9635 79.9535)
		(width 0.125)
		(layer "In5.Cu")
		(net 944)
	)
	(segment
		(start 99.9635 79.9535)
		(end 107.1435 79.9535)
		(width 0.125)
		(layer "In5.Cu")
		(net 944)
	)
	(segment
		(start 122.55 147.7)
		(end 122.55 147.32)
		(width 0.125)
		(layer "F.Cu")
		(net 945)
	)
	(segment
		(start 210.85 132.61)
		(end 210.85 133.81)
		(width 0.125)
		(layer "F.Cu")
		(net 945)
	)
	(segment
		(start 122.111 146.881)
		(end 121.4 146.881)
		(width 0.125)
		(layer "F.Cu")
		(net 945)
	)
	(segment
		(start 212.11 132.26)
		(end 211.2 132.26)
		(width 0.125)
		(layer "F.Cu")
		(net 945)
	)
	(segment
		(start 211.2 132.26)
		(end 210.85 132.61)
		(width 0.125)
		(layer "F.Cu")
		(net 945)
	)
	(segment
		(start 122.55 147.32)
		(end 122.111 146.881)
		(width 0.125)
		(layer "F.Cu")
		(net 945)
	)
	(via
		(at 125.945 88.06)
		(size 0.45)
		(drill 0.1)
		(layers "F.Cu" "B.Cu")
		(remove_unused_layers yes)
		(keep_end_layers yes)
		(zone_layer_connections)
		(teardrops
			(best_length_ratio 0.4)
			(max_length 1)
			(best_width_ratio 0.9)
			(max_width 2)
			(curved_edges yes)
			(filter_ratio 0.9)
			(enabled yes)
			(allow_two_segments yes)
			(prefer_zone_connections yes)
		)
		(net 945)
	)
	(via
		(at 122.85 160.56)
		(size 0.45)
		(drill 0.1)
		(layers "F.Cu" "B.Cu")
		(remove_unused_layers yes)
		(keep_end_layers yes)
		(zone_layer_connections "In2.Cu")
		(teardrops
			(best_length_ratio 0.4)
			(max_length 1)
			(best_width_ratio 0.9)
			(max_width 2)
			(curved_edges yes)
			(filter_ratio 0.9)
			(enabled yes)
			(allow_two_segments yes)
			(prefer_zone_connections yes)
		)
		(net 945)
	)
	(via
		(at 122.55 147.7)
		(size 0.45)
		(drill 0.1)
		(layers "F.Cu" "B.Cu")
		(remove_unused_layers yes)
		(keep_end_layers yes)
		(zone_layer_connections "In2.Cu")
		(teardrops
			(best_length_ratio 0.4)
			(max_length 1)
			(best_width_ratio 0.9)
			(max_width 2)
			(curved_edges yes)
			(filter_ratio 0.9)
			(enabled yes)
			(allow_two_segments yes)
			(prefer_zone_connections yes)
		)
		(net 945)
	)
	(via
		(at 210.85 133.81)
		(size 0.45)
		(drill 0.1)
		(layers "F.Cu" "B.Cu")
		(remove_unused_layers yes)
		(keep_end_layers yes)
		(zone_layer_connections "In2.Cu")
		(teardrops
			(best_length_ratio 0.4)
			(max_length 1)
			(best_width_ratio 0.9)
			(max_width 2)
			(curved_edges yes)
			(filter_ratio 0.9)
			(enabled yes)
			(allow_two_segments yes)
			(prefer_zone_connections yes)
		)
		(net 945)
	)
	(via
		(at 197.7 132.2)
		(size 0.45)
		(drill 0.1)
		(layers "F.Cu" "B.Cu")
		(teardrops
			(best_length_ratio 0.4)
			(max_length 1)
			(best_width_ratio 0.9)
			(max_width 2)
			(curved_edges yes)
			(filter_ratio 0.9)
			(enabled yes)
			(allow_two_segments yes)
			(prefer_zone_connections yes)
		)
		(net 945)
	)
	(segment
		(start 122.55 147.7)
		(end 122.459 147.609)
		(width 0.125)
		(layer "B.Cu")
		(net 945)
	)
	(segment
		(start 196.906066 132.98303)
		(end 196.91697 132.98303)
		(width 0.125)
		(layer "B.Cu")
		(net 945)
	)
	(segment
		(start 196.91697 132.98303)
		(end 197.7 132.2)
		(width 0.125)
		(layer "B.Cu")
		(net 945)
	)
	(segment
		(start 122.459 147.609)
		(end 121.838 147.609)
		(width 0.125)
		(layer "B.Cu")
		(net 945)
	)
	(segment
		(start 122.18 160.56)
		(end 122.85 160.56)
		(width 0.125)
		(layer "B.Cu")
		(net 945)
	)
	(segment
		(start 122.55 147.7)
		(end 122.55 147.61)
		(width 0.125)
		(layer "In2.Cu")
		(net 945)
	)
	(segment
		(start 122.55 147.61)
		(end 124.395 145.765)
		(width 0.125)
		(layer "In2.Cu")
		(net 945)
	)
	(segment
		(start 124.395 141.555)
		(end 125.325 140.625)
		(width 0.125)
		(layer "In2.Cu")
		(net 945)
	)
	(segment
		(start 198 131.9)
		(end 200.9 131.9)
		(width 0.125)
		(layer "In2.Cu")
		(net 945)
	)
	(segment
		(start 125.325 113.585)
		(end 125.325 140.625)
		(width 0.125)
		(layer "In2.Cu")
		(net 945)
	)
	(segment
		(start 122.55 147.7)
		(end 122.55 156.545)
		(width 0.125)
		(layer "In2.Cu")
		(net 945)
	)
	(segment
		(start 140.7 151.11)
		(end 152.85 151.11)
		(width 0.125)
		(layer "In2.Cu")
		(net 945)
	)
	(segment
		(start 126.05 112.86)
		(end 125.325 113.585)
		(width 0.125)
		(layer "In2.Cu")
		(net 945)
	)
	(segment
		(start 161.5 149.3)
		(end 161.5 140.5)
		(width 0.125)
		(layer "In2.Cu")
		(net 945)
	)
	(segment
		(start 134.95 156.86)
		(end 140.7 151.11)
		(width 0.125)
		(layer "In2.Cu")
		(net 945)
	)
	(segment
		(start 161.5 140.5)
		(end 169.4 132.6)
		(width 0.125)
		(layer "In2.Cu")
		(net 945)
	)
	(segment
		(start 153.21 150.75)
		(end 160.05 150.75)
		(width 0.125)
		(layer "In2.Cu")
		(net 945)
	)
	(segment
		(start 202.81 133.81)
		(end 210.85 133.81)
		(width 0.125)
		(layer "In2.Cu")
		(net 945)
	)
	(segment
		(start 197.3 132.6)
		(end 197.7 132.2)
		(width 0.125)
		(layer "In2.Cu")
		(net 945)
	)
	(segment
		(start 122.55 156.545)
		(end 122.865 156.86)
		(width 0.125)
		(layer "In2.Cu")
		(net 945)
	)
	(segment
		(start 122.85 156.875)
		(end 122.865 156.86)
		(width 0.125)
		(layer "In2.Cu")
		(net 945)
	)
	(segment
		(start 122.865 156.86)
		(end 134.95 156.86)
		(width 0.125)
		(layer "In2.Cu")
		(net 945)
	)
	(segment
		(start 160.05 150.75)
		(end 161.5 149.3)
		(width 0.125)
		(layer "In2.Cu")
		(net 945)
	)
	(segment
		(start 124.395 145.765)
		(end 124.395 141.555)
		(width 0.125)
		(layer "In2.Cu")
		(net 945)
	)
	(segment
		(start 122.85 160.56)
		(end 122.85 156.875)
		(width 0.125)
		(layer "In2.Cu")
		(net 945)
	)
	(segment
		(start 200.9 131.9)
		(end 202.81 133.81)
		(width 0.125)
		(layer "In2.Cu")
		(net 945)
	)
	(segment
		(start 169.4 132.6)
		(end 197.3 132.6)
		(width 0.125)
		(layer "In2.Cu")
		(net 945)
	)
	(segment
		(start 152.85 151.11)
		(end 153.21 150.75)
		(width 0.125)
		(layer "In2.Cu")
		(net 945)
	)
	(segment
		(start 125.945 88.06)
		(end 126.05 88.165)
		(width 0.125)
		(layer "In2.Cu")
		(net 945)
	)
	(segment
		(start 197.7 132.2)
		(end 198 131.9)
		(width 0.125)
		(layer "In2.Cu")
		(net 945)
	)
	(segment
		(start 126.05 88.165)
		(end 126.05 112.86)
		(width 0.125)
		(layer "In2.Cu")
		(net 945)
	)
	(segment
		(start 153.14 148.475)
		(end 153.33 148.285)
		(width 0.16)
		(layer "F.Cu")
		(net 946)
	)
	(segment
		(start 148.392183 151.380885)
		(end 148.439116 151.427818)
		(width 0.16)
		(layer "F.Cu")
		(net 946)
	)
	(segment
		(start 152.44 151.75)
		(end 153.683067 151.75)
		(width 0.16)
		(layer "F.Cu")
		(net 946)
	)
	(segment
		(start 151.775 150.445)
		(end 151.775 151.085)
		(width 0.16)
		(layer "F.Cu")
		(net 946)
	)
	(segment
		(start 149.57 148.311)
		(end 149.76 148.501)
		(width 0.16)
		(layer "F.Cu")
		(net 946)
	)
	(segment
		(start 149.216933 151.75)
		(end 150.54 151.75)
		(width 0.16)
		(layer "F.Cu")
		(net 946)
	)
	(segment
		(start 153.14 148.957034)
		(end 153.14 148.475)
		(width 0.16)
		(layer "F.Cu")
		(net 946)
	)
	(segment
		(start 154.83 150.603067)
		(end 154.83 150.506933)
		(width 0.16)
		(layer "F.Cu")
		(net 946)
	)
	(segment
		(start 149.76 148.501)
		(end 149.76 148.957034)
		(width 0.16)
		(layer "F.Cu")
		(net 946)
	)
	(segment
		(start 148.07 150.506933)
		(end 148.07 150.603067)
		(width 0.16)
		(layer "F.Cu")
		(net 946)
	)
	(segment
		(start 153.693067 149.37)
		(end 153.552966 149.37)
		(width 0.16)
		(layer "F.Cu")
		(net 946)
	)
	(segment
		(start 148.429115 149.692183)
		(end 148.392182 149.729116)
		(width 0.16)
		(layer "F.Cu")
		(net 946)
	)
	(segment
		(start 149.672132 149.169166)
		(end 149.559166 149.282132)
		(width 0.16)
		(layer "F.Cu")
		(net 946)
	)
	(segment
		(start 154.507818 149.729116)
		(end 154.470885 149.692183)
		(width 0.16)
		(layer "F.Cu")
		(net 946)
	)
	(segment
		(start 149.347034 149.37)
		(end 149.206933 149.37)
		(width 0.16)
		(layer "F.Cu")
		(net 946)
	)
	(segment
		(start 154.460884 151.427818)
		(end 154.507817 151.380885)
		(width 0.16)
		(layer "F.Cu")
		(net 946)
	)
	(segment
		(start 153.340834 149.282132)
		(end 153.227868 149.169166)
		(width 0.16)
		(layer "F.Cu")
		(net 946)
	)
	(segment
		(start 151.205 151.085)
		(end 151.205 150.445)
		(width 0.16)
		(layer "F.Cu")
		(net 946)
	)
	(arc
		(start 148.07 150.603067)
		(mid 148.153733 151.024019)
		(end 148.392183 151.380885)
		(width 0.16)
		(layer "F.Cu")
		(net 946)
	)
	(arc
		(start 148.392182 149.729116)
		(mid 148.153732 150.085982)
		(end 148.07 150.506933)
		(width 0.16)
		(layer "F.Cu")
		(net 946)
	)
	(arc
		(start 149.206933 149.37)
		(mid 148.785981 149.453733)
		(end 148.429115 149.692183)
		(width 0.16)
		(layer "F.Cu")
		(net 946)
	)
	(arc
		(start 151.205 150.445)
		(mid 151.288475 150.243475)
		(end 151.49 150.16)
		(width 0.16)
		(layer "F.Cu")
		(net 946)
	)
	(arc
		(start 153.683067 151.75)
		(mid 154.104018 151.666268)
		(end 154.460884 151.427818)
		(width 0.16)
		(layer "F.Cu")
		(net 946)
	)
	(arc
		(start 149.559166 149.282132)
		(mid 149.461839 149.347164)
		(end 149.347034 149.37)
		(width 0.16)
		(layer "F.Cu")
		(net 946)
	)
	(arc
		(start 151.775 151.085)
		(mid 151.969774 151.555226)
		(end 152.44 151.75)
		(width 0.16)
		(layer "F.Cu")
		(net 946)
	)
	(arc
		(start 150.54 151.75)
		(mid 151.010226 151.555226)
		(end 151.205 151.085)
		(width 0.16)
		(layer "F.Cu")
		(net 946)
	)
	(arc
		(start 148.439116 151.427818)
		(mid 148.795982 151.666268)
		(end 149.216933 151.75)
		(width 0.16)
		(layer "F.Cu")
		(net 946)
	)
	(arc
		(start 154.507817 151.380885)
		(mid 154.746267 151.024019)
		(end 154.83 150.603067)
		(width 0.16)
		(layer "F.Cu")
		(net 946)
	)
	(arc
		(start 153.227868 149.169166)
		(mid 153.162836 149.071839)
		(end 153.14 148.957034)
		(width 0.16)
		(layer "F.Cu")
		(net 946)
	)
	(arc
		(start 153.552966 149.37)
		(mid 153.438161 149.347164)
		(end 153.340834 149.282132)
		(width 0.16)
		(layer "F.Cu")
		(net 946)
	)
	(arc
		(start 149.76 148.957034)
		(mid 149.737164 149.071839)
		(end 149.672132 149.169166)
		(width 0.16)
		(layer "F.Cu")
		(net 946)
	)
	(arc
		(start 154.470885 149.692183)
		(mid 154.114019 149.453733)
		(end 153.693067 149.37)
		(width 0.16)
		(layer "F.Cu")
		(net 946)
	)
	(arc
		(start 151.49 150.16)
		(mid 151.691525 150.243475)
		(end 151.775 150.445)
		(width 0.16)
		(layer "F.Cu")
		(net 946)
	)
	(arc
		(start 154.83 150.506933)
		(mid 154.746268 150.085982)
		(end 154.507818 149.729116)
		(width 0.16)
		(layer "F.Cu")
		(net 946)
	)
	(segment
		(start 128.98 143.17)
		(end 129.29 142.86)
		(width 0.16)
		(layer "F.Cu")
		(net 947)
	)
	(segment
		(start 129.17 146.96)
		(end 128.98 146.77)
		(width 0.16)
		(layer "F.Cu")
		(net 947)
	)
	(segment
		(start 128.98 146.77)
		(end 128.98 143.17)
		(width 0.16)
		(layer "F.Cu")
		(net 947)
	)
	(segment
		(start 156.14 148.477)
		(end 156.14 150.790275)
		(width 0.16)
		(layer "F.Cu")
		(net 948)
	)
	(segment
		(start 146.76 148.475)
		(end 146.57 148.285)
		(width 0.16)
		(layer "F.Cu")
		(net 948)
	)
	(segment
		(start 156.332 148.285)
		(end 156.14 148.477)
		(width 0.16)
		(layer "F.Cu")
		(net 948)
	)
	(segment
		(start 153.880275 153.05)
		(end 149.009725 153.05)
		(width 0.16)
		(layer "F.Cu")
		(net 948)
	)
	(segment
		(start 146.76 150.800275)
		(end 146.76 148.475)
		(width 0.16)
		(layer "F.Cu")
		(net 948)
	)
	(segment
		(start 147.595511 152.464213)
		(end 147.345786 152.214488)
		(width 0.16)
		(layer "F.Cu")
		(net 948)
	)
	(segment
		(start 155.554213 152.204489)
		(end 155.294488 152.464214)
		(width 0.16)
		(layer "F.Cu")
		(net 948)
	)
	(arc
		(start 147.345786 152.214488)
		(mid 146.912241 151.565642)
		(end 146.76 150.800275)
		(width 0.16)
		(layer "F.Cu")
		(net 948)
	)
	(arc
		(start 156.14 150.790275)
		(mid 155.987759 151.555642)
		(end 155.554213 152.204489)
		(width 0.16)
		(layer "F.Cu")
		(net 948)
	)
	(arc
		(start 155.294488 152.464214)
		(mid 154.645642 152.897759)
		(end 153.880275 153.05)
		(width 0.16)
		(layer "F.Cu")
		(net 948)
	)
	(arc
		(start 149.009725 153.05)
		(mid 148.244358 152.897759)
		(end 147.595511 152.464213)
		(width 0.16)
		(layer "F.Cu")
		(net 948)
	)
	(segment
		(start 134.98 148.475)
		(end 135.17 148.285)
		(width 0.16)
		(layer "F.Cu")
		(net 949)
	)
	(segment
		(start 130.269115 149.692183)
		(end 130.232182 149.729116)
		(width 0.16)
		(layer "F.Cu")
		(net 949)
	)
	(segment
		(start 131.41 148.311)
		(end 131.6 148.501)
		(width 0.16)
		(layer "F.Cu")
		(net 949)
	)
	(segment
		(start 134.98 148.957034)
		(end 134.98 148.475)
		(width 0.16)
		(layer "F.Cu")
		(net 949)
	)
	(segment
		(start 131.056933 151.75)
		(end 132.38 151.75)
		(width 0.16)
		(layer "F.Cu")
		(net 949)
	)
	(segment
		(start 133.045 151.085)
		(end 133.045 150.445)
		(width 0.16)
		(layer "F.Cu")
		(net 949)
	)
	(segment
		(start 131.187034 149.37)
		(end 131.046933 149.37)
		(width 0.16)
		(layer "F.Cu")
		(net 949)
	)
	(segment
		(start 134.28 151.75)
		(end 135.523067 151.75)
		(width 0.16)
		(layer "F.Cu")
		(net 949)
	)
	(segment
		(start 136.347818 149.729116)
		(end 136.310885 149.692183)
		(width 0.16)
		(layer "F.Cu")
		(net 949)
	)
	(segment
		(start 136.300884 151.427818)
		(end 136.347817 151.380885)
		(width 0.16)
		(layer "F.Cu")
		(net 949)
	)
	(segment
		(start 131.6 148.501)
		(end 131.6 148.957034)
		(width 0.16)
		(layer "F.Cu")
		(net 949)
	)
	(segment
		(start 133.615 150.445)
		(end 133.615 151.085)
		(width 0.16)
		(layer "F.Cu")
		(net 949)
	)
	(segment
		(start 135.180834 149.282132)
		(end 135.067868 149.169166)
		(width 0.16)
		(layer "F.Cu")
		(net 949)
	)
	(segment
		(start 136.67 150.603067)
		(end 136.67 150.506933)
		(width 0.16)
		(layer "F.Cu")
		(net 949)
	)
	(segment
		(start 131.512132 149.169166)
		(end 131.399166 149.282132)
		(width 0.16)
		(layer "F.Cu")
		(net 949)
	)
	(segment
		(start 129.91 150.506933)
		(end 129.91 150.603067)
		(width 0.16)
		(layer "F.Cu")
		(net 949)
	)
	(segment
		(start 130.232183 151.380885)
		(end 130.279116 151.427818)
		(width 0.16)
		(layer "F.Cu")
		(net 949)
	)
	(segment
		(start 135.533067 149.37)
		(end 135.392966 149.37)
		(width 0.16)
		(layer "F.Cu")
		(net 949)
	)
	(arc
		(start 131.399166 149.282132)
		(mid 131.301839 149.347164)
		(end 131.187034 149.37)
		(width 0.16)
		(layer "F.Cu")
		(net 949)
	)
	(arc
		(start 133.045 150.445)
		(mid 133.128475 150.243475)
		(end 133.33 150.16)
		(width 0.16)
		(layer "F.Cu")
		(net 949)
	)
	(arc
		(start 136.310885 149.692183)
		(mid 135.954019 149.453733)
		(end 135.533067 149.37)
		(width 0.16)
		(layer "F.Cu")
		(net 949)
	)
	(arc
		(start 135.523067 151.75)
		(mid 135.944018 151.666268)
		(end 136.300884 151.427818)
		(width 0.16)
		(layer "F.Cu")
		(net 949)
	)
	(arc
		(start 136.347817 151.380885)
		(mid 136.586267 151.024019)
		(end 136.67 150.603067)
		(width 0.16)
		(layer "F.Cu")
		(net 949)
	)
	(arc
		(start 133.33 150.16)
		(mid 133.531525 150.243475)
		(end 133.615 150.445)
		(width 0.16)
		(layer "F.Cu")
		(net 949)
	)
	(arc
		(start 132.38 151.75)
		(mid 132.850226 151.555226)
		(end 133.045 151.085)
		(width 0.16)
		(layer "F.Cu")
		(net 949)
	)
	(arc
		(start 135.067868 149.169166)
		(mid 135.002836 149.071839)
		(end 134.98 148.957034)
		(width 0.16)
		(layer "F.Cu")
		(net 949)
	)
	(arc
		(start 133.615 151.085)
		(mid 133.809774 151.555226)
		(end 134.28 151.75)
		(width 0.16)
		(layer "F.Cu")
		(net 949)
	)
	(arc
		(start 130.232182 149.729116)
		(mid 129.993732 150.085982)
		(end 129.91 150.506933)
		(width 0.16)
		(layer "F.Cu")
		(net 949)
	)
	(arc
		(start 131.6 148.957034)
		(mid 131.577164 149.071839)
		(end 131.512132 149.169166)
		(width 0.16)
		(layer "F.Cu")
		(net 949)
	)
	(arc
		(start 131.046933 149.37)
		(mid 130.625981 149.453733)
		(end 130.269115 149.692183)
		(width 0.16)
		(layer "F.Cu")
		(net 949)
	)
	(arc
		(start 129.91 150.603067)
		(mid 129.993733 151.024019)
		(end 130.232183 151.380885)
		(width 0.16)
		(layer "F.Cu")
		(net 949)
	)
	(arc
		(start 130.279116 151.427818)
		(mid 130.635982 151.666268)
		(end 131.056933 151.75)
		(width 0.16)
		(layer "F.Cu")
		(net 949)
	)
	(arc
		(start 136.67 150.506933)
		(mid 136.586268 150.085982)
		(end 136.347818 149.729116)
		(width 0.16)
		(layer "F.Cu")
		(net 949)
	)
	(arc
		(start 135.392966 149.37)
		(mid 135.278161 149.347164)
		(end 135.180834 149.282132)
		(width 0.16)
		(layer "F.Cu")
		(net 949)
	)
	(segment
		(start 131.6 143.17)
		(end 131.29 142.86)
		(width 0.16)
		(layer "F.Cu")
		(net 950)
	)
	(segment
		(start 131.6 146.77)
		(end 131.6 143.17)
		(width 0.16)
		(layer "F.Cu")
		(net 950)
	)
	(segment
		(start 131.41 146.96)
		(end 131.6 146.77)
		(width 0.16)
		(layer "F.Cu")
		(net 950)
	)
	(segment
		(start 128.6 150.800275)
		(end 128.6 148.475)
		(width 0.16)
		(layer "F.Cu")
		(net 951)
	)
	(segment
		(start 128.6 148.475)
		(end 128.41 148.285)
		(width 0.16)
		(layer "F.Cu")
		(net 951)
	)
	(segment
		(start 129.435511 152.464213)
		(end 129.185786 152.214488)
		(width 0.16)
		(layer "F.Cu")
		(net 951)
	)
	(segment
		(start 135.720275 153.05)
		(end 130.849725 153.05)
		(width 0.16)
		(layer "F.Cu")
		(net 951)
	)
	(segment
		(start 137.98 148.477)
		(end 137.98 150.790275)
		(width 0.16)
		(layer "F.Cu")
		(net 951)
	)
	(segment
		(start 137.394213 152.204489)
		(end 137.134488 152.464214)
		(width 0.16)
		(layer "F.Cu")
		(net 951)
	)
	(segment
		(start 138.172 148.285)
		(end 137.98 148.477)
		(width 0.16)
		(layer "F.Cu")
		(net 951)
	)
	(arc
		(start 129.185786 152.214488)
		(mid 128.752241 151.565642)
		(end 128.6 150.800275)
		(width 0.16)
		(layer "F.Cu")
		(net 951)
	)
	(arc
		(start 130.849725 153.05)
		(mid 130.084358 152.897759)
		(end 129.435511 152.464213)
		(width 0.16)
		(layer "F.Cu")
		(net 951)
	)
	(arc
		(start 137.134488 152.464214)
		(mid 136.485642 152.897759)
		(end 135.720275 153.05)
		(width 0.16)
		(layer "F.Cu")
		(net 951)
	)
	(arc
		(start 137.98 150.790275)
		(mid 137.827759 151.555642)
		(end 137.394213 152.204489)
		(width 0.16)
		(layer "F.Cu")
		(net 951)
	)
	(segment
		(start 128.41 146.96)
		(end 128.6 146.77)
		(width 0.16)
		(layer "F.Cu")
		(net 952)
	)
	(segment
		(start 128.6 146.77)
		(end 128.6 143.17)
		(width 0.16)
		(layer "F.Cu")
		(net 952)
	)
	(segment
		(start 128.6 143.17)
		(end 128.29 142.86)
		(width 0.16)
		(layer "F.Cu")
		(net 952)
	)
	(segment
		(start 132.17 146.96)
		(end 131.98 146.77)
		(width 0.16)
		(layer "F.Cu")
		(net 953)
	)
	(segment
		(start 131.98 143.17)
		(end 132.29 142.86)
		(width 0.16)
		(layer "F.Cu")
		(net 953)
	)
	(segment
		(start 131.98 146.77)
		(end 131.98 143.17)
		(width 0.16)
		(layer "F.Cu")
		(net 953)
	)
	(segment
		(start 147.14 149.13)
		(end 147.14 148.475)
		(width 0.16)
		(layer "F.Cu")
		(net 954)
	)
	(segment
		(start 147.3975 149.3725)
		(end 147.3825 149.3725)
		(width 0.16)
		(layer "F.Cu")
		(net 954)
	)
	(segment
		(start 155.76 148.473)
		(end 155.76 149.06)
		(width 0.16)
		(layer "F.Cu")
		(net 954)
	)
	(segment
		(start 147.3825 149.8575)
		(end 147.3975 149.8575)
		(width 0.16)
		(layer "F.Cu")
		(net 954)
	)
	(segment
		(start 147.752915 152.084213)
		(end 147.725786 152.057084)
		(width 0.16)
		(layer "F.Cu")
		(net 954)
	)
	(segment
		(start 153.722871 152.67)
		(end 149.167129 152.67)
		(width 0.16)
		(layer "F.Cu")
		(net 954)
	)
	(segment
		(start 155.76 150.06)
		(end 155.76 150.632871)
		(width 0.16)
		(layer "F.Cu")
		(net 954)
	)
	(segment
		(start 147.14 148.475)
		(end 147.33 148.285)
		(width 0.16)
		(layer "F.Cu")
		(net 954)
	)
	(segment
		(start 155.572 148.285)
		(end 155.76 148.473)
		(width 0.16)
		(layer "F.Cu")
		(net 954)
	)
	(segment
		(start 155.51 149.31)
		(end 155.457644 149.31)
		(width 0.16)
		(layer "F.Cu")
		(net 954)
	)
	(segment
		(start 147.14 150.642871)
		(end 147.14 150.1)
		(width 0.16)
		(layer "F.Cu")
		(net 954)
	)
	(segment
		(start 155.457644 149.81)
		(end 155.51 149.81)
		(width 0.16)
		(layer "F.Cu")
		(net 954)
	)
	(segment
		(start 155.174213 152.047085)
		(end 155.137084 152.084214)
		(width 0.16)
		(layer "F.Cu")
		(net 954)
	)
	(arc
		(start 155.137084 152.084214)
		(mid 154.488238 152.517759)
		(end 153.722871 152.67)
		(width 0.16)
		(layer "F.Cu")
		(net 954)
	)
	(arc
		(start 155.457644 149.31)
		(mid 155.280867 149.383223)
		(end 155.207644 149.56)
		(width 0.16)
		(layer "F.Cu")
		(net 954)
	)
	(arc
		(start 147.64 149.615)
		(mid 147.568973 149.443527)
		(end 147.3975 149.3725)
		(width 0.16)
		(layer "F.Cu")
		(net 954)
	)
	(arc
		(start 155.76 150.632871)
		(mid 155.607759 151.398238)
		(end 155.174213 152.047085)
		(width 0.16)
		(layer "F.Cu")
		(net 954)
	)
	(arc
		(start 155.76 149.06)
		(mid 155.686777 149.236777)
		(end 155.51 149.31)
		(width 0.16)
		(layer "F.Cu")
		(net 954)
	)
	(arc
		(start 147.3975 149.8575)
		(mid 147.568973 149.786473)
		(end 147.64 149.615)
		(width 0.16)
		(layer "F.Cu")
		(net 954)
	)
	(arc
		(start 147.3825 149.3725)
		(mid 147.211027 149.301473)
		(end 147.14 149.13)
		(width 0.16)
		(layer "F.Cu")
		(net 954)
	)
	(arc
		(start 147.725786 152.057084)
		(mid 147.292241 151.408238)
		(end 147.14 150.642871)
		(width 0.16)
		(layer "F.Cu")
		(net 954)
	)
	(arc
		(start 149.167129 152.67)
		(mid 148.401762 152.517759)
		(end 147.752915 152.084213)
		(width 0.16)
		(layer "F.Cu")
		(net 954)
	)
	(arc
		(start 155.51 149.81)
		(mid 155.686777 149.883223)
		(end 155.76 150.06)
		(width 0.16)
		(layer "F.Cu")
		(net 954)
	)
	(arc
		(start 155.207644 149.56)
		(mid 155.280867 149.736777)
		(end 155.457644 149.81)
		(width 0.16)
		(layer "F.Cu")
		(net 954)
	)
	(arc
		(start 147.14 150.1)
		(mid 147.211027 149.928527)
		(end 147.3825 149.8575)
		(width 0.16)
		(layer "F.Cu")
		(net 954)
	)
	(segment
		(start 137.297644 149.81)
		(end 137.35 149.81)
		(width 0.16)
		(layer "F.Cu")
		(net 955)
	)
	(segment
		(start 135.562871 152.67)
		(end 131.007129 152.67)
		(width 0.16)
		(layer "F.Cu")
		(net 955)
	)
	(segment
		(start 137.412 148.285)
		(end 137.6 148.473)
		(width 0.16)
		(layer "F.Cu")
		(net 955)
	)
	(segment
		(start 129.2375 149.3725)
		(end 129.2225 149.3725)
		(width 0.16)
		(layer "F.Cu")
		(net 955)
	)
	(segment
		(start 137.6 148.473)
		(end 137.6 149.06)
		(width 0.16)
		(layer "F.Cu")
		(net 955)
	)
	(segment
		(start 128.98 148.475)
		(end 129.17 148.285)
		(width 0.16)
		(layer "F.Cu")
		(net 955)
	)
	(segment
		(start 137.014213 152.047085)
		(end 136.977084 152.084214)
		(width 0.16)
		(layer "F.Cu")
		(net 955)
	)
	(segment
		(start 128.98 150.642871)
		(end 128.98 150.1)
		(width 0.16)
		(layer "F.Cu")
		(net 955)
	)
	(segment
		(start 129.592915 152.084213)
		(end 129.565786 152.057084)
		(width 0.16)
		(layer "F.Cu")
		(net 955)
	)
	(segment
		(start 137.6 150.06)
		(end 137.6 150.632871)
		(width 0.16)
		(layer "F.Cu")
		(net 955)
	)
	(segment
		(start 137.35 149.31)
		(end 137.297644 149.31)
		(width 0.16)
		(layer "F.Cu")
		(net 955)
	)
	(segment
		(start 129.2225 149.8575)
		(end 129.2375 149.8575)
		(width 0.16)
		(layer "F.Cu")
		(net 955)
	)
	(segment
		(start 128.98 149.13)
		(end 128.98 148.475)
		(width 0.16)
		(layer "F.Cu")
		(net 955)
	)
	(arc
		(start 129.48 149.615)
		(mid 129.408973 149.443527)
		(end 129.2375 149.3725)
		(width 0.16)
		(layer "F.Cu")
		(net 955)
	)
	(arc
		(start 129.2375 149.8575)
		(mid 129.408973 149.786473)
		(end 129.48 149.615)
		(width 0.16)
		(layer "F.Cu")
		(net 955)
	)
	(arc
		(start 131.007129 152.67)
		(mid 130.241762 152.517759)
		(end 129.592915 152.084213)
		(width 0.16)
		(layer "F.Cu")
		(net 955)
	)
	(arc
		(start 129.2225 149.3725)
		(mid 129.051027 149.301473)
		(end 128.98 149.13)
		(width 0.16)
		(layer "F.Cu")
		(net 955)
	)
	(arc
		(start 137.297644 149.31)
		(mid 137.120867 149.383223)
		(end 137.047644 149.56)
		(width 0.16)
		(layer "F.Cu")
		(net 955)
	)
	(arc
		(start 137.6 149.06)
		(mid 137.526777 149.236777)
		(end 137.35 149.31)
		(width 0.16)
		(layer "F.Cu")
		(net 955)
	)
	(arc
		(start 137.6 150.632871)
		(mid 137.447759 151.398238)
		(end 137.014213 152.047085)
		(width 0.16)
		(layer "F.Cu")
		(net 955)
	)
	(arc
		(start 129.565786 152.057084)
		(mid 129.132241 151.408238)
		(end 128.98 150.642871)
		(width 0.16)
		(layer "F.Cu")
		(net 955)
	)
	(arc
		(start 136.977084 152.084214)
		(mid 136.328238 152.517759)
		(end 135.562871 152.67)
		(width 0.16)
		(layer "F.Cu")
		(net 955)
	)
	(arc
		(start 137.047644 149.56)
		(mid 137.120867 149.736777)
		(end 137.297644 149.81)
		(width 0.16)
		(layer "F.Cu")
		(net 955)
	)
	(arc
		(start 137.35 149.81)
		(mid 137.526777 149.883223)
		(end 137.6 150.06)
		(width 0.16)
		(layer "F.Cu")
		(net 955)
	)
	(arc
		(start 128.98 150.1)
		(mid 129.051027 149.928527)
		(end 129.2225 149.8575)
		(width 0.16)
		(layer "F.Cu")
		(net 955)
	)
	(segment
		(start 193.370532 138.550788)
		(end 193.834572 139.014828)
		(width 0.202)
		(layer "B.Cu")
		(net 956)
	)
	(segment
		(start 193.834572 139.093317)
		(end 195.657669 140.916414)
		(width 0.202)
		(layer "B.Cu")
		(net 956)
	)
	(segment
		(start 195.657669 140.916414)
		(end 195.657669 140.916415)
		(width 0.202)
		(layer "B.Cu")
		(net 956)
	)
	(segment
		(start 196.358058 141.184762)
		(end 196.375735 141.202439)
		(width 0.202)
		(layer "B.Cu")
		(net 956)
	)
	(segment
		(start 193.834572 139.014828)
		(end 193.834572 139.093317)
		(width 0.202)
		(layer "B.Cu")
		(net 956)
	)
	(segment
		(start 195.657669 140.916415)
		(end 195.926015 141.184762)
		(width 0.202)
		(layer "B.Cu")
		(net 956)
	)
	(segment
		(start 195.926015 141.184762)
		(end 196.358058 141.184762)
		(width 0.202)
		(layer "B.Cu")
		(net 956)
	)
	(segment
		(start 197.496499 136.941412)
		(end 197.496499 137.373456)
		(width 0.202)
		(layer "B.Cu")
		(net 957)
	)
	(segment
		(start 196.662999 136.186401)
		(end 196.741488 136.186401)
		(width 0.202)
		(layer "B.Cu")
		(net 957)
	)
	(segment
		(start 196.198959 135.722361)
		(end 196.662999 136.186401)
		(width 0.202)
		(layer "B.Cu")
		(net 957)
	)
	(segment
		(start 197.496499 137.373456)
		(end 197.514177 137.391134)
		(width 0.202)
		(layer "B.Cu")
		(net 957)
	)
	(segment
		(start 196.741488 136.186401)
		(end 197.496499 136.941412)
		(width 0.202)
		(layer "B.Cu")
		(net 957)
	)
	(segment
		(start 195.138299 136.783021)
		(end 195.602339 137.247061)
		(width 0.202)
		(layer "B.Cu")
		(net 958)
	)
	(segment
		(start 197.772271 139.770548)
		(end 197.789949 139.788226)
		(width 0.202)
		(layer "B.Cu")
		(net 958)
	)
	(segment
		(start 197.503925 139.07016)
		(end 197.772271 139.338506)
		(width 0.202)
		(layer "B.Cu")
		(net 958)
	)
	(segment
		(start 195.680827 137.247061)
		(end 197.503925 139.070158)
		(width 0.202)
		(layer "B.Cu")
		(net 958)
	)
	(segment
		(start 197.503925 139.070158)
		(end 197.503925 139.07016)
		(width 0.202)
		(layer "B.Cu")
		(net 958)
	)
	(segment
		(start 197.772271 139.338506)
		(end 197.772271 139.770548)
		(width 0.202)
		(layer "B.Cu")
		(net 958)
	)
	(segment
		(start 195.602339 137.247061)
		(end 195.680827 137.247061)
		(width 0.202)
		(layer "B.Cu")
		(net 958)
	)
	(segment
		(start 195.353966 139.487705)
		(end 195.371644 139.505383)
		(width 0.202)
		(layer "B.Cu")
		(net 959)
	)
	(segment
		(start 195.170472 138.865099)
		(end 195.353966 139.048592)
		(width 0.202)
		(layer "B.Cu")
		(net 959)
	)
	(segment
		(start 195.170472 138.858026)
		(end 195.170472 138.865099)
		(width 0.202)
		(layer "B.Cu")
		(net 959)
	)
	(segment
		(start 195.353966 139.048592)
		(end 195.353966 139.487705)
		(width 0.202)
		(layer "B.Cu")
		(net 959)
	)
	(segment
		(start 194.077639 137.843681)
		(end 194.541678 138.307721)
		(width 0.202)
		(layer "B.Cu")
		(net 959)
	)
	(segment
		(start 194.541678 138.307721)
		(end 194.620167 138.307721)
		(width 0.202)
		(layer "B.Cu")
		(net 959)
	)
	(segment
		(start 194.620167 138.307721)
		(end 195.170472 138.858026)
		(width 0.202)
		(layer "B.Cu")
		(net 959)
	)
	(segment
		(start 193.016979 138.904342)
		(end 193.481018 139.368381)
		(width 0.202)
		(layer "B.Cu")
		(net 960)
	)
	(segment
		(start 195.650951 141.891868)
		(end 195.668628 141.909546)
		(width 0.202)
		(layer "B.Cu")
		(net 960)
	)
	(segment
		(start 195.382604 141.19148)
		(end 195.650951 141.459826)
		(width 0.202)
		(layer "B.Cu")
		(net 960)
	)
	(segment
		(start 193.559507 139.368381)
		(end 195.382604 141.191479)
		(width 0.202)
		(layer "B.Cu")
		(net 960)
	)
	(segment
		(start 195.650951 141.459826)
		(end 195.650951 141.891868)
		(width 0.202)
		(layer "B.Cu")
		(net 960)
	)
	(segment
		(start 193.481018 139.368381)
		(end 193.559507 139.368381)
		(width 0.202)
		(layer "B.Cu")
		(net 960)
	)
	(segment
		(start 195.382604 141.191479)
		(end 195.382604 141.19148)
		(width 0.202)
		(layer "B.Cu")
		(net 960)
	)
	(segment
		(start 114.5545 154.890362)
		(end 114.5545 157.502139)
		(width 0.202)
		(layer "B.Cu")
		(net 961)
	)
	(segment
		(start 116.901 149.3605)
		(end 116.8455 149.416)
		(width 0.202)
		(layer "B.Cu")
		(net 961)
	)
	(segment
		(start 116.259713 152.495353)
		(end 115.042259 153.712807)
		(width 0.202)
		(layer "B.Cu")
		(net 961)
	)
	(segment
		(start 111.503854 160.552785)
		(end 110.610786 160.552785)
		(width 0.202)
		(layer "B.Cu")
		(net 961)
	)
	(segment
		(start 113.968713 158.916353)
		(end 112.918067 159.966999)
		(width 0.202)
		(layer "B.Cu")
		(net 961)
	)
	(segment
		(start 116.8455 149.416)
		(end 116.8455 151.081139)
		(width 0.202)
		(layer "B.Cu")
		(net 961)
	)
	(segment
		(start 110.610786 160.552785)
		(end 110.316 160.847571)
		(width 0.202)
		(layer "B.Cu")
		(net 961)
	)
	(arc
		(start 115.042259 153.712807)
		(mid 114.681264 154.253074)
		(end 114.5545 154.890362)
		(width 0.202)
		(layer "B.Cu")
		(net 961)
	)
	(arc
		(start 114.5545 157.502139)
		(mid 114.402259 158.267506)
		(end 113.968713 158.916353)
		(width 0.202)
		(layer "B.Cu")
		(net 961)
	)
	(arc
		(start 111.503854 160.552785)
		(mid 112.269221 160.400544)
		(end 112.918067 159.966999)
		(width 0.202)
		(layer "B.Cu")
		(net 961)
	)
	(arc
		(start 116.8455 151.081139)
		(mid 116.693259 151.846506)
		(end 116.259713 152.495353)
		(width 0.202)
		(layer "B.Cu")
		(net 961)
	)
	(segment
		(start 108.667786 165.060785)
		(end 109.845854 165.060785)
		(width 0.202)
		(layer "B.Cu")
		(net 962)
	)
	(segment
		(start 118.3435 149.416)
		(end 118.399 149.3605)
		(width 0.202)
		(layer "B.Cu")
		(net 962)
	)
	(segment
		(start 111.260068 164.474998)
		(end 117.757713 157.977353)
		(width 0.202)
		(layer "B.Cu")
		(net 962)
	)
	(segment
		(start 118.3435 156.563139)
		(end 118.3435 149.416)
		(width 0.202)
		(layer "B.Cu")
		(net 962)
	)
	(segment
		(start 108.373 165.355571)
		(end 108.667786 165.060785)
		(width 0.202)
		(layer "B.Cu")
		(net 962)
	)
	(arc
		(start 111.260068 164.474998)
		(mid 110.611221 164.908544)
		(end 109.845854 165.060785)
		(width 0.202)
		(layer "B.Cu")
		(net 962)
	)
	(arc
		(start 117.757713 157.977353)
		(mid 118.191259 157.328506)
		(end 118.3435 156.563139)
		(width 0.202)
		(layer "B.Cu")
		(net 962)
	)
	(segment
		(start 119.8445 157.852139)
		(end 119.8445 149.416)
		(width 0.202)
		(layer "B.Cu")
		(net 963)
	)
	(segment
		(start 112.558068 165.966998)
		(end 119.258713 159.266353)
		(width 0.202)
		(layer "B.Cu")
		(net 963)
	)
	(segment
		(start 119.8445 149.416)
		(end 119.9 149.3605)
		(width 0.202)
		(layer "B.Cu")
		(net 963)
	)
	(segment
		(start 110.585786 166.552785)
		(end 111.143854 166.552785)
		(width 0.202)
		(layer "B.Cu")
		(net 963)
	)
	(segment
		(start 110.291 166.847571)
		(end 110.585786 166.552785)
		(width 0.202)
		(layer "B.Cu")
		(net 963)
	)
	(arc
		(start 111.143854 166.552785)
		(mid 111.909221 166.400544)
		(end 112.558068 165.966998)
		(width 0.202)
		(layer "B.Cu")
		(net 963)
	)
	(arc
		(start 119.258713 159.266353)
		(mid 119.692259 158.617506)
		(end 119.8445 157.852139)
		(width 0.202)
		(layer "B.Cu")
		(net 963)
	)
	(segment
		(start 113.595997 158.738938)
		(end 113.681262 158.653672)
		(width 0.202)
		(layer "B.Cu")
		(net 964)
	)
	(segment
		(start 113.171733 158.783418)
		(end 113.171734 158.783419)
		(width 0.202)
		(layer "B.Cu")
		(net 964)
	)
	(segment
		(start 116.4565 149.416)
		(end 116.401 149.3605)
		(width 0.202)
		(layer "B.Cu")
		(net 964)
	)
	(segment
		(start 113.551518 158.783419)
		(end 113.595997 158.738938)
		(width 0.202)
		(layer "B.Cu")
		(net 964)
	)
	(segment
		(start 110.610786 160.163786)
		(end 111.483553 160.163786)
		(width 0.202)
		(layer "B.Cu")
		(net 964)
	)
	(segment
		(start 114.751286 153.453648)
		(end 115.981281 152.223653)
		(width 0.202)
		(layer "B.Cu")
		(net 964)
	)
	(segment
		(start 112.747467 158.827899)
		(end 112.791949 158.783418)
		(width 0.202)
		(layer "B.Cu")
		(net 964)
	)
	(segment
		(start 116.4565 151.076372)
		(end 116.4565 149.416)
		(width 0.202)
		(layer "B.Cu")
		(net 964)
	)
	(segment
		(start 110.316 159.869)
		(end 110.610786 160.163786)
		(width 0.202)
		(layer "B.Cu")
		(net 964)
	)
	(segment
		(start 112.657351 159.677583)
		(end 112.747467 159.587467)
		(width 0.202)
		(layer "B.Cu")
		(net 964)
	)
	(segment
		(start 114.1655 157.484618)
		(end 114.1655 154.867861)
		(width 0.202)
		(layer "B.Cu")
		(net 964)
	)
	(arc
		(start 111.483553 160.163786)
		(mid 112.118808 160.037426)
		(end 112.657351 159.677583)
		(width 0.202)
		(layer "B.Cu")
		(net 964)
	)
	(arc
		(start 114.1655 154.867861)
		(mid 114.317741 154.102494)
		(end 114.751286 153.453648)
		(width 0.202)
		(layer "B.Cu")
		(net 964)
	)
	(arc
		(start 113.171734 158.783419)
		(mid 113.361626 158.862075)
		(end 113.551518 158.783419)
		(width 0.202)
		(layer "B.Cu")
		(net 964)
	)
	(arc
		(start 113.681262 158.653672)
		(mid 114.039651 158.117305)
		(end 114.1655 157.484618)
		(width 0.202)
		(layer "B.Cu")
		(net 964)
	)
	(arc
		(start 112.747467 159.207683)
		(mid 112.668811 159.017791)
		(end 112.747467 158.827899)
		(width 0.202)
		(layer "B.Cu")
		(net 964)
	)
	(arc
		(start 115.981281 152.223653)
		(mid 116.332995 151.697276)
		(end 116.4565 151.076372)
		(width 0.202)
		(layer "B.Cu")
		(net 964)
	)
	(arc
		(start 112.747467 159.587467)
		(mid 112.826123 159.397575)
		(end 112.747467 159.207683)
		(width 0.202)
		(layer "B.Cu")
		(net 964)
	)
	(arc
		(start 112.791949 158.783418)
		(mid 112.981841 158.704762)
		(end 113.171733 158.783418)
		(width 0.202)
		(layer "B.Cu")
		(net 964)
	)
	(segment
		(start 111.576732 163.227772)
		(end 111.576733 163.227773)
		(width 0.202)
		(layer "B.Cu")
		(net 965)
	)
	(segment
		(start 117.9545 149.416)
		(end 117.899 149.3605)
		(width 0.202)
		(layer "B.Cu")
		(net 965)
	)
	(segment
		(start 110.999352 164.185583)
		(end 111.152467 164.032467)
		(width 0.202)
		(layer "B.Cu")
		(net 965)
	)
	(segment
		(start 111.957165 163.227773)
		(end 112.000997 163.183938)
		(width 0.202)
		(layer "B.Cu")
		(net 965)
	)
	(segment
		(start 108.373 164.377)
		(end 108.667786 164.671786)
		(width 0.202)
		(layer "B.Cu")
		(net 965)
	)
	(segment
		(start 108.667786 164.671786)
		(end 109.825554 164.671786)
		(width 0.202)
		(layer "B.Cu")
		(net 965)
	)
	(segment
		(start 111.152468 163.271603)
		(end 111.1963 163.227772)
		(width 0.202)
		(layer "B.Cu")
		(net 965)
	)
	(segment
		(start 117.9545 156.553625)
		(end 117.9545 149.416)
		(width 0.202)
		(layer "B.Cu")
		(net 965)
	)
	(segment
		(start 111.152467 163.652037)
		(end 111.152468 163.652035)
		(width 0.202)
		(layer "B.Cu")
		(net 965)
	)
	(segment
		(start 112.000997 163.183938)
		(end 117.475924 157.70901)
		(width 0.202)
		(layer "B.Cu")
		(net 965)
	)
	(arc
		(start 117.475924 157.70901)
		(mid 117.830122 157.178915)
		(end 117.9545 156.553625)
		(width 0.202)
		(layer "B.Cu")
		(net 965)
	)
	(arc
		(start 111.576733 163.227773)
		(mid 111.766949 163.306563)
		(end 111.957165 163.227773)
		(width 0.202)
		(layer "B.Cu")
		(net 965)
	)
	(arc
		(start 109.825554 164.671786)
		(mid 110.460809 164.545426)
		(end 110.999352 164.185583)
		(width 0.202)
		(layer "B.Cu")
		(net 965)
	)
	(arc
		(start 111.152468 163.652035)
		(mid 111.073678 163.461819)
		(end 111.152468 163.271603)
		(width 0.202)
		(layer "B.Cu")
		(net 965)
	)
	(arc
		(start 111.1963 163.227772)
		(mid 111.386516 163.148982)
		(end 111.576732 163.227772)
		(width 0.202)
		(layer "B.Cu")
		(net 965)
	)
	(arc
		(start 111.152467 164.032467)
		(mid 111.231258 163.842251)
		(end 111.152467 163.652037)
		(width 0.202)
		(layer "B.Cu")
		(net 965)
	)
	(segment
		(start 112.297354 165.677583)
		(end 112.502469 165.472468)
		(width 0.202)
		(layer "B.Cu")
		(net 966)
	)
	(segment
		(start 112.502467 165.092634)
		(end 112.502468 165.092633)
		(width 0.202)
		(layer "B.Cu")
		(net 966)
	)
	(segment
		(start 110.291 165.869)
		(end 110.585786 166.163786)
		(width 0.202)
		(layer "B.Cu")
		(net 966)
	)
	(segment
		(start 110.585786 166.163786)
		(end 111.123556 166.163786)
		(width 0.202)
		(layer "B.Cu")
		(net 966)
	)
	(segment
		(start 112.926732 164.668367)
		(end 112.926733 164.668368)
		(width 0.202)
		(layer "B.Cu")
		(net 966)
	)
	(segment
		(start 112.502468 164.712797)
		(end 112.502467 164.712799)
		(width 0.202)
		(layer "B.Cu")
		(net 966)
	)
	(segment
		(start 119.4555 157.851044)
		(end 119.4555 149.416)
		(width 0.202)
		(layer "B.Cu")
		(net 966)
	)
	(segment
		(start 113.618112 164.356822)
		(end 118.982877 158.992057)
		(width 0.202)
		(layer "B.Cu")
		(net 966)
	)
	(segment
		(start 113.306569 164.66837)
		(end 113.350997 164.62394)
		(width 0.202)
		(layer "B.Cu")
		(net 966)
	)
	(segment
		(start 119.4555 149.416)
		(end 119.4 149.3605)
		(width 0.202)
		(layer "B.Cu")
		(net 966)
	)
	(segment
		(start 112.502467 164.712799)
		(end 112.546897 164.66837)
		(width 0.202)
		(layer "B.Cu")
		(net 966)
	)
	(segment
		(start 112.926733 164.668368)
		(end 112.926734 164.668369)
		(width 0.202)
		(layer "B.Cu")
		(net 966)
	)
	(segment
		(start 113.350997 164.62394)
		(end 113.618112 164.356822)
		(width 0.202)
		(layer "B.Cu")
		(net 966)
	)
	(arc
		(start 118.982877 158.992057)
		(mid 119.332669 158.468556)
		(end 119.4555 157.851044)
		(width 0.202)
		(layer "B.Cu")
		(net 966)
	)
	(arc
		(start 112.502468 165.092633)
		(mid 112.423802 164.902716)
		(end 112.502468 164.712797)
		(width 0.202)
		(layer "B.Cu")
		(net 966)
	)
	(arc
		(start 112.502469 165.472468)
		(mid 112.581134 165.28255)
		(end 112.502467 165.092634)
		(width 0.202)
		(layer "B.Cu")
		(net 966)
	)
	(arc
		(start 111.123556 166.163786)
		(mid 111.758811 166.037426)
		(end 112.297354 165.677583)
		(width 0.202)
		(layer "B.Cu")
		(net 966)
	)
	(arc
		(start 112.926734 164.668369)
		(mid 113.116651 164.747036)
		(end 113.306569 164.66837)
		(width 0.202)
		(layer "B.Cu")
		(net 966)
	)
	(arc
		(start 112.546897 164.66837)
		(mid 112.736814 164.589703)
		(end 112.926732 164.668367)
		(width 0.202)
		(layer "B.Cu")
		(net 966)
	)
	(segment
		(start 149.949619 149.429083)
		(end 149.819082 149.55962)
		(width 0.16)
		(layer "F.Cu")
		(net 967)
	)
	(segment
		(start 152.76 148.969463)
		(end 152.76 148.475)
		(width 0.16)
		(layer "F.Cu")
		(net 967)
	)
	(segment
		(start 150.33 148.311)
		(end 150.14 148.501)
		(width 0.16)
		(layer "F.Cu")
		(net 967)
	)
	(segment
		(start 148.45 150.519362)
		(end 148.45 150.590638)
		(width 0.16)
		(layer "F.Cu")
		(net 967)
	)
	(segment
		(start 152.76 148.475)
		(end 152.57 148.285)
		(width 0.16)
		(layer "F.Cu")
		(net 967)
	)
	(segment
		(start 152.155 150.445)
		(end 152.155 151.085)
		(width 0.16)
		(layer "F.Cu")
		(net 967)
	)
	(segment
		(start 153.680638 149.75)
		(end 153.540537 149.75)
		(width 0.16)
		(layer "F.Cu")
		(net 967)
	)
	(segment
		(start 149.229362 151.37)
		(end 149.33 151.37)
		(width 0.16)
		(layer "F.Cu")
		(net 967)
	)
	(segment
		(start 148.689032 149.96967)
		(end 148.66967 149.989032)
		(width 0.16)
		(layer "F.Cu")
		(net 967)
	)
	(segment
		(start 150.14 148.501)
		(end 150.14 148.969463)
		(width 0.16)
		(layer "F.Cu")
		(net 967)
	)
	(segment
		(start 149.58 151.12)
		(end 149.58 151.11572)
		(width 0.16)
		(layer "F.Cu")
		(net 967)
	)
	(segment
		(start 152.44 151.37)
		(end 152.570638 151.37)
		(width 0.16)
		(layer "F.Cu")
		(net 967)
	)
	(segment
		(start 148.66967 151.120968)
		(end 148.699032 151.15033)
		(width 0.16)
		(layer "F.Cu")
		(net 967)
	)
	(segment
		(start 149.815726 150.87)
		(end 149.945752 150.87)
		(width 0.16)
		(layer "F.Cu")
		(net 967)
	)
	(segment
		(start 153.080918 149.55962)
		(end 152.950381 149.429083)
		(width 0.16)
		(layer "F.Cu")
		(net 967)
	)
	(segment
		(start 153.420638 151.102616)
		(end 153.420638 151.12)
		(width 0.16)
		(layer "F.Cu")
		(net 967)
	)
	(segment
		(start 150.825 151.085)
		(end 150.825 150.445)
		(width 0.16)
		(layer "F.Cu")
		(net 967)
	)
	(segment
		(start 149.359463 149.75)
		(end 149.219362 149.75)
		(width 0.16)
		(layer "F.Cu")
		(net 967)
	)
	(segment
		(start 149.58 151.11572)
		(end 149.579999 151.105746)
		(width 0.16)
		(layer "F.Cu")
		(net 967)
	)
	(segment
		(start 153.053188 150.87)
		(end 153.188022 150.87)
		(width 0.16)
		(layer "F.Cu")
		(net 967)
	)
	(segment
		(start 150.18 151.108948)
		(end 150.18 151.12)
		(width 0.16)
		(layer "F.Cu")
		(net 967)
	)
	(segment
		(start 154.23033 149.989032)
		(end 154.210968 149.96967)
		(width 0.16)
		(layer "F.Cu")
		(net 967)
	)
	(segment
		(start 154.45 150.590638)
		(end 154.45 150.519362)
		(width 0.16)
		(layer "F.Cu")
		(net 967)
	)
	(segment
		(start 150.179999 151.104196)
		(end 150.18 151.108948)
		(width 0.16)
		(layer "F.Cu")
		(net 967)
	)
	(segment
		(start 154.200968 151.15033)
		(end 154.23033 151.120968)
		(width 0.16)
		(layer "F.Cu")
		(net 967)
	)
	(segment
		(start 152.820638 151.109871)
		(end 152.820639 151.102516)
		(width 0.16)
		(layer "F.Cu")
		(net 967)
	)
	(segment
		(start 152.820638 151.12)
		(end 152.820638 151.109871)
		(width 0.16)
		(layer "F.Cu")
		(net 967)
	)
	(segment
		(start 150.43 151.37)
		(end 150.54 151.37)
		(width 0.16)
		(layer "F.Cu")
		(net 967)
	)
	(arc
		(start 152.820639 151.102516)
		(mid 152.888763 150.9381)
		(end 153.053188 150.87)
		(width 0.16)
		(layer "F.Cu")
		(net 967)
	)
	(arc
		(start 153.188022 150.87)
		(mid 153.352506 150.938132)
		(end 153.420638 151.102616)
		(width 0.16)
		(layer "F.Cu")
		(net 967)
	)
	(arc
		(start 148.45 150.590638)
		(mid 148.50709 150.877651)
		(end 148.66967 151.120968)
		(width 0.16)
		(layer "F.Cu")
		(net 967)
	)
	(arc
		(start 149.819082 149.55962)
		(mid 149.608207 149.700522)
		(end 149.359463 149.75)
		(width 0.16)
		(layer "F.Cu")
		(net 967)
	)
	(arc
		(start 153.670638 151.37)
		(mid 153.957651 151.31291)
		(end 154.200968 151.15033)
		(width 0.16)
		(layer "F.Cu")
		(net 967)
	)
	(arc
		(start 150.14 148.969463)
		(mid 150.090522 149.218208)
		(end 149.949619 149.429083)
		(width 0.16)
		(layer "F.Cu")
		(net 967)
	)
	(arc
		(start 152.570638 151.37)
		(mid 152.747415 151.296777)
		(end 152.820638 151.12)
		(width 0.16)
		(layer "F.Cu")
		(net 967)
	)
	(arc
		(start 148.66967 149.989032)
		(mid 148.50709 150.232349)
		(end 148.45 150.519362)
		(width 0.16)
		(layer "F.Cu")
		(net 967)
	)
	(arc
		(start 154.23033 151.120968)
		(mid 154.39291 150.877651)
		(end 154.45 150.590638)
		(width 0.16)
		(layer "F.Cu")
		(net 967)
	)
	(arc
		(start 150.18 151.12)
		(mid 150.253223 151.296777)
		(end 150.43 151.37)
		(width 0.16)
		(layer "F.Cu")
		(net 967)
	)
	(arc
		(start 150.54 151.37)
		(mid 150.741525 151.286525)
		(end 150.825 151.085)
		(width 0.16)
		(layer "F.Cu")
		(net 967)
	)
	(arc
		(start 152.950381 149.429083)
		(mid 152.809478 149.218208)
		(end 152.76 148.969463)
		(width 0.16)
		(layer "F.Cu")
		(net 967)
	)
	(arc
		(start 154.210968 149.96967)
		(mid 153.967651 149.80709)
		(end 153.680638 149.75)
		(width 0.16)
		(layer "F.Cu")
		(net 967)
	)
	(arc
		(start 153.540537 149.75)
		(mid 153.291793 149.700522)
		(end 153.080918 149.55962)
		(width 0.16)
		(layer "F.Cu")
		(net 967)
	)
	(arc
		(start 148.699032 151.15033)
		(mid 148.942349 151.31291)
		(end 149.229362 151.37)
		(width 0.16)
		(layer "F.Cu")
		(net 967)
	)
	(arc
		(start 149.579999 151.105746)
		(mid 149.649035 150.93905)
		(end 149.815726 150.87)
		(width 0.16)
		(layer "F.Cu")
		(net 967)
	)
	(arc
		(start 151.49 149.78)
		(mid 151.960226 149.974774)
		(end 152.155 150.445)
		(width 0.16)
		(layer "F.Cu")
		(net 967)
	)
	(arc
		(start 153.420638 151.12)
		(mid 153.493861 151.296777)
		(end 153.670638 151.37)
		(width 0.16)
		(layer "F.Cu")
		(net 967)
	)
	(arc
		(start 149.33 151.37)
		(mid 149.506777 151.296777)
		(end 149.58 151.12)
		(width 0.16)
		(layer "F.Cu")
		(net 967)
	)
	(arc
		(start 150.825 150.445)
		(mid 151.019774 149.974774)
		(end 151.49 149.78)
		(width 0.16)
		(layer "F.Cu")
		(net 967)
	)
	(arc
		(start 149.219362 149.75)
		(mid 148.932349 149.80709)
		(end 148.689032 149.96967)
		(width 0.16)
		(layer "F.Cu")
		(net 967)
	)
	(arc
		(start 154.45 150.519362)
		(mid 154.39291 150.232349)
		(end 154.23033 149.989032)
		(width 0.16)
		(layer "F.Cu")
		(net 967)
	)
	(arc
		(start 149.945752 150.87)
		(mid 150.111372 150.938591)
		(end 150.179999 151.104196)
		(width 0.16)
		(layer "F.Cu")
		(net 967)
	)
	(arc
		(start 152.155 151.085)
		(mid 152.238475 151.286525)
		(end 152.44 151.37)
		(width 0.16)
		(layer "F.Cu")
		(net 967)
	)
	(segment
		(start 131.42 151.11572)
		(end 131.419999 151.105746)
		(width 0.16)
		(layer "F.Cu")
		(net 968)
	)
	(segment
		(start 130.29 150.519362)
		(end 130.29 150.590638)
		(width 0.16)
		(layer "F.Cu")
		(net 968)
	)
	(segment
		(start 134.28 151.37)
		(end 134.410638 151.37)
		(width 0.16)
		(layer "F.Cu")
		(net 968)
	)
	(segment
		(start 132.019999 151.104196)
		(end 132.02 151.108948)
		(width 0.16)
		(layer "F.Cu")
		(net 968)
	)
	(segment
		(start 133.995 150.445)
		(end 133.995 151.085)
		(width 0.16)
		(layer "F.Cu")
		(net 968)
	)
	(segment
		(start 136.29 150.590638)
		(end 136.29 150.519362)
		(width 0.16)
		(layer "F.Cu")
		(net 968)
	)
	(segment
		(start 132.27 151.37)
		(end 132.38 151.37)
		(width 0.16)
		(layer "F.Cu")
		(net 968)
	)
	(segment
		(start 131.42 151.12)
		(end 131.42 151.11572)
		(width 0.16)
		(layer "F.Cu")
		(net 968)
	)
	(segment
		(start 134.660638 151.109871)
		(end 134.660639 151.102516)
		(width 0.16)
		(layer "F.Cu")
		(net 968)
	)
	(segment
		(start 131.069362 151.37)
		(end 131.17 151.37)
		(width 0.16)
		(layer "F.Cu")
		(net 968)
	)
	(segment
		(start 132.665 151.085)
		(end 132.665 150.445)
		(width 0.16)
		(layer "F.Cu")
		(net 968)
	)
	(segment
		(start 131.199463 149.75)
		(end 131.059362 149.75)
		(width 0.16)
		(layer "F.Cu")
		(net 968)
	)
	(segment
		(start 132.17 148.311)
		(end 131.98 148.501)
		(width 0.16)
		(layer "F.Cu")
		(net 968)
	)
	(segment
		(start 136.07033 149.989032)
		(end 136.050968 149.96967)
		(width 0.16)
		(layer "F.Cu")
		(net 968)
	)
	(segment
		(start 131.655726 150.87)
		(end 131.785752 150.87)
		(width 0.16)
		(layer "F.Cu")
		(net 968)
	)
	(segment
		(start 134.6 148.475)
		(end 134.41 148.285)
		(width 0.16)
		(layer "F.Cu")
		(net 968)
	)
	(segment
		(start 135.260638 151.102616)
		(end 135.260638 151.12)
		(width 0.16)
		(layer "F.Cu")
		(net 968)
	)
	(segment
		(start 131.98 148.501)
		(end 131.98 148.969463)
		(width 0.16)
		(layer "F.Cu")
		(net 968)
	)
	(segment
		(start 134.6 148.969463)
		(end 134.6 148.475)
		(width 0.16)
		(layer "F.Cu")
		(net 968)
	)
	(segment
		(start 131.789619 149.429083)
		(end 131.659082 149.55962)
		(width 0.16)
		(layer "F.Cu")
		(net 968)
	)
	(segment
		(start 132.02 151.108948)
		(end 132.02 151.12)
		(width 0.16)
		(layer "F.Cu")
		(net 968)
	)
	(segment
		(start 136.040968 151.15033)
		(end 136.07033 151.120968)
		(width 0.16)
		(layer "F.Cu")
		(net 968)
	)
	(segment
		(start 134.660638 151.12)
		(end 134.660638 151.109871)
		(width 0.16)
		(layer "F.Cu")
		(net 968)
	)
	(segment
		(start 130.50967 151.120968)
		(end 130.539032 151.15033)
		(width 0.16)
		(layer "F.Cu")
		(net 968)
	)
	(segment
		(start 135.520638 149.75)
		(end 135.380537 149.75)
		(width 0.16)
		(layer "F.Cu")
		(net 968)
	)
	(segment
		(start 130.529032 149.96967)
		(end 130.50967 149.989032)
		(width 0.16)
		(layer "F.Cu")
		(net 968)
	)
	(segment
		(start 134.893188 150.87)
		(end 135.028022 150.87)
		(width 0.16)
		(layer "F.Cu")
		(net 968)
	)
	(segment
		(start 134.920918 149.55962)
		(end 134.790381 149.429083)
		(width 0.16)
		(layer "F.Cu")
		(net 968)
	)
	(arc
		(start 136.29 150.519362)
		(mid 136.23291 150.232349)
		(end 136.07033 149.989032)
		(width 0.16)
		(layer "F.Cu")
		(net 968)
	)
	(arc
		(start 136.050968 149.96967)
		(mid 135.807651 149.80709)
		(end 135.520638 149.75)
		(width 0.16)
		(layer "F.Cu")
		(net 968)
	)
	(arc
		(start 135.028022 150.87)
		(mid 135.192506 150.938132)
		(end 135.260638 151.102616)
		(width 0.16)
		(layer "F.Cu")
		(net 968)
	)
	(arc
		(start 130.539032 151.15033)
		(mid 130.782349 151.31291)
		(end 131.069362 151.37)
		(width 0.16)
		(layer "F.Cu")
		(net 968)
	)
	(arc
		(start 134.660639 151.102516)
		(mid 134.728763 150.9381)
		(end 134.893188 150.87)
		(width 0.16)
		(layer "F.Cu")
		(net 968)
	)
	(arc
		(start 130.50967 149.989032)
		(mid 130.34709 150.232349)
		(end 130.29 150.519362)
		(width 0.16)
		(layer "F.Cu")
		(net 968)
	)
	(arc
		(start 134.790381 149.429083)
		(mid 134.649478 149.218208)
		(end 134.6 148.969463)
		(width 0.16)
		(layer "F.Cu")
		(net 968)
	)
	(arc
		(start 131.659082 149.55962)
		(mid 131.448207 149.700522)
		(end 131.199463 149.75)
		(width 0.16)
		(layer "F.Cu")
		(net 968)
	)
	(arc
		(start 134.410638 151.37)
		(mid 134.587415 151.296777)
		(end 134.660638 151.12)
		(width 0.16)
		(layer "F.Cu")
		(net 968)
	)
	(arc
		(start 131.98 148.969463)
		(mid 131.930522 149.218208)
		(end 131.789619 149.429083)
		(width 0.16)
		(layer "F.Cu")
		(net 968)
	)
	(arc
		(start 131.419999 151.105746)
		(mid 131.489035 150.93905)
		(end 131.655726 150.87)
		(width 0.16)
		(layer "F.Cu")
		(net 968)
	)
	(arc
		(start 131.17 151.37)
		(mid 131.346777 151.296777)
		(end 131.42 151.12)
		(width 0.16)
		(layer "F.Cu")
		(net 968)
	)
	(arc
		(start 133.33 149.78)
		(mid 133.800226 149.974774)
		(end 133.995 150.445)
		(width 0.16)
		(layer "F.Cu")
		(net 968)
	)
	(arc
		(start 130.29 150.590638)
		(mid 130.34709 150.877651)
		(end 130.50967 151.120968)
		(width 0.16)
		(layer "F.Cu")
		(net 968)
	)
	(arc
		(start 133.995 151.085)
		(mid 134.078475 151.286525)
		(end 134.28 151.37)
		(width 0.16)
		(layer "F.Cu")
		(net 968)
	)
	(arc
		(start 135.380537 149.75)
		(mid 135.131793 149.700522)
		(end 134.920918 149.55962)
		(width 0.16)
		(layer "F.Cu")
		(net 968)
	)
	(arc
		(start 136.07033 151.120968)
		(mid 136.23291 150.877651)
		(end 136.29 150.590638)
		(width 0.16)
		(layer "F.Cu")
		(net 968)
	)
	(arc
		(start 135.510638 151.37)
		(mid 135.797651 151.31291)
		(end 136.040968 151.15033)
		(width 0.16)
		(layer "F.Cu")
		(net 968)
	)
	(arc
		(start 131.785752 150.87)
		(mid 131.951372 150.938591)
		(end 132.019999 151.104196)
		(width 0.16)
		(layer "F.Cu")
		(net 968)
	)
	(arc
		(start 135.260638 151.12)
		(mid 135.333861 151.296777)
		(end 135.510638 151.37)
		(width 0.16)
		(layer "F.Cu")
		(net 968)
	)
	(arc
		(start 132.665 150.445)
		(mid 132.859774 149.974774)
		(end 133.33 149.78)
		(width 0.16)
		(layer "F.Cu")
		(net 968)
	)
	(arc
		(start 132.38 151.37)
		(mid 132.581525 151.286525)
		(end 132.665 151.085)
		(width 0.16)
		(layer "F.Cu")
		(net 968)
	)
	(arc
		(start 131.059362 149.75)
		(mid 130.772349 149.80709)
		(end 130.529032 149.96967)
		(width 0.16)
		(layer "F.Cu")
		(net 968)
	)
	(arc
		(start 132.02 151.12)
		(mid 132.093223 151.296777)
		(end 132.27 151.37)
		(width 0.16)
		(layer "F.Cu")
		(net 968)
	)
	(via
		(at 177.86 96.11)
		(size 0.45)
		(drill 0.1)
		(layers "F.Cu" "B.Cu")
		(remove_unused_layers yes)
		(keep_end_layers yes)
		(zone_layer_connections "In3.Cu")
		(teardrops
			(best_length_ratio 0.4)
			(max_length 1)
			(best_width_ratio 0.9)
			(max_width 2)
			(curved_edges yes)
			(filter_ratio 0.9)
			(enabled yes)
			(allow_two_segments yes)
			(prefer_zone_connections yes)
		)
		(net 969)
	)
	(via
		(at 177.86 97.11)
		(size 0.45)
		(drill 0.1)
		(layers "F.Cu" "B.Cu")
		(remove_unused_layers yes)
		(keep_end_layers yes)
		(zone_layer_connections "In3.Cu")
		(teardrops
			(best_length_ratio 0.4)
			(max_length 1)
			(best_width_ratio 0.9)
			(max_width 2)
			(curved_edges yes)
			(filter_ratio 0.9)
			(enabled yes)
			(allow_two_segments yes)
			(prefer_zone_connections yes)
		)
		(net 969)
	)
	(via
		(at 177.859999 110.11)
		(size 0.45)
		(drill 0.1)
		(layers "F.Cu" "B.Cu")
		(remove_unused_layers yes)
		(keep_end_layers yes)
		(zone_layer_connections "In3.Cu")
		(teardrops
			(best_length_ratio 0.4)
			(max_length 1)
			(best_width_ratio 0.9)
			(max_width 2)
			(curved_edges yes)
			(filter_ratio 0.9)
			(enabled yes)
			(allow_two_segments yes)
			(prefer_zone_connections yes)
		)
		(net 969)
	)
	(via
		(at 179.11 91.9)
		(size 0.45)
		(drill 0.1)
		(layers "F.Cu" "B.Cu")
		(remove_unused_layers yes)
		(keep_end_layers yes)
		(zone_layer_connections "In3.Cu")
		(teardrops
			(best_length_ratio 0.4)
			(max_length 1)
			(best_width_ratio 0.9)
			(max_width 2)
			(curved_edges yes)
			(filter_ratio 0.9)
			(enabled yes)
			(allow_two_segments yes)
			(prefer_zone_connections yes)
		)
		(net 969)
	)
	(via
		(at 177.859999 111.11)
		(size 0.45)
		(drill 0.1)
		(layers "F.Cu" "B.Cu")
		(remove_unused_layers yes)
		(keep_end_layers yes)
		(zone_layer_connections "In3.Cu")
		(teardrops
			(best_length_ratio 0.4)
			(max_length 1)
			(best_width_ratio 0.9)
			(max_width 2)
			(curved_edges yes)
			(filter_ratio 0.9)
			(enabled yes)
			(allow_two_segments yes)
			(prefer_zone_connections yes)
		)
		(net 969)
	)
	(via
		(at 177.86 93.11)
		(size 0.45)
		(drill 0.1)
		(layers "F.Cu" "B.Cu")
		(remove_unused_layers yes)
		(keep_end_layers yes)
		(zone_layer_connections "In3.Cu")
		(teardrops
			(best_length_ratio 0.4)
			(max_length 1)
			(best_width_ratio 0.9)
			(max_width 2)
			(curved_edges yes)
			(filter_ratio 0.9)
			(enabled yes)
			(allow_two_segments yes)
			(prefer_zone_connections yes)
		)
		(net 969)
	)
	(via
		(at 177.859999 110.61)
		(size 0.45)
		(drill 0.1)
		(layers "F.Cu" "B.Cu")
		(remove_unused_layers yes)
		(keep_end_layers yes)
		(zone_layer_connections "In3.Cu")
		(teardrops
			(best_length_ratio 0.4)
			(max_length 1)
			(best_width_ratio 0.9)
			(max_width 2)
			(curved_edges yes)
			(filter_ratio 0.9)
			(enabled yes)
			(allow_two_segments yes)
			(prefer_zone_connections yes)
		)
		(net 969)
	)
	(via
		(at 177.86 95.61)
		(size 0.45)
		(drill 0.1)
		(layers "F.Cu" "B.Cu")
		(remove_unused_layers yes)
		(keep_end_layers yes)
		(zone_layer_connections "In3.Cu")
		(teardrops
			(best_length_ratio 0.4)
			(max_length 1)
			(best_width_ratio 0.9)
			(max_width 2)
			(curved_edges yes)
			(filter_ratio 0.9)
			(enabled yes)
			(allow_two_segments yes)
			(prefer_zone_connections yes)
		)
		(net 969)
	)
	(via
		(at 177.86 93.61)
		(size 0.45)
		(drill 0.1)
		(layers "F.Cu" "B.Cu")
		(remove_unused_layers yes)
		(keep_end_layers yes)
		(zone_layer_connections "In3.Cu")
		(teardrops
			(best_length_ratio 0.4)
			(max_length 1)
			(best_width_ratio 0.9)
			(max_width 2)
			(curved_edges yes)
			(filter_ratio 0.9)
			(enabled yes)
			(allow_two_segments yes)
			(prefer_zone_connections yes)
		)
		(net 969)
	)
	(via
		(at 179.03 92.48)
		(size 0.45)
		(drill 0.1)
		(layers "F.Cu" "B.Cu")
		(remove_unused_layers yes)
		(keep_end_layers yes)
		(zone_layer_connections "In3.Cu")
		(teardrops
			(best_length_ratio 0.4)
			(max_length 1)
			(best_width_ratio 0.9)
			(max_width 2)
			(curved_edges yes)
			(filter_ratio 0.9)
			(enabled yes)
			(allow_two_segments yes)
			(prefer_zone_connections yes)
		)
		(net 969)
	)
	(via
		(at 177.86 96.61)
		(size 0.45)
		(drill 0.1)
		(layers "F.Cu" "B.Cu")
		(remove_unused_layers yes)
		(keep_end_layers yes)
		(zone_layer_connections "In3.Cu")
		(teardrops
			(best_length_ratio 0.4)
			(max_length 1)
			(best_width_ratio 0.9)
			(max_width 2)
			(curved_edges yes)
			(filter_ratio 0.9)
			(enabled yes)
			(allow_two_segments yes)
			(prefer_zone_connections yes)
		)
		(net 969)
	)
	(via
		(at 178.53 91.9)
		(size 0.45)
		(drill 0.1)
		(layers "F.Cu" "B.Cu")
		(remove_unused_layers yes)
		(keep_end_layers yes)
		(zone_layer_connections "In3.Cu")
		(teardrops
			(best_length_ratio 0.4)
			(max_length 1)
			(best_width_ratio 0.9)
			(max_width 2)
			(curved_edges yes)
			(filter_ratio 0.9)
			(enabled yes)
			(allow_two_segments yes)
			(prefer_zone_connections yes)
		)
		(net 969)
	)
	(via
		(at 178.45 92.48)
		(size 0.45)
		(drill 0.1)
		(layers "F.Cu" "B.Cu")
		(remove_unused_layers yes)
		(keep_end_layers yes)
		(zone_layer_connections "In3.Cu")
		(teardrops
			(best_length_ratio 0.4)
			(max_length 1)
			(best_width_ratio 0.9)
			(max_width 2)
			(curved_edges yes)
			(filter_ratio 0.9)
			(enabled yes)
			(allow_two_segments yes)
			(prefer_zone_connections yes)
		)
		(net 969)
	)
	(segment
		(start 177.86 93.11)
		(end 178.84 93.11)
		(width 0.3)
		(layer "B.Cu")
		(net 969)
	)
	(segment
		(start 177.86 96.61)
		(end 178.84 96.61)
		(width 0.3)
		(layer "B.Cu")
		(net 969)
	)
	(segment
		(start 177.86 96.11)
		(end 178.84 96.11)
		(width 0.3)
		(layer "B.Cu")
		(net 969)
	)
	(segment
		(start 177.86 97.11)
		(end 178.84 97.11)
		(width 0.3)
		(layer "B.Cu")
		(net 969)
	)
	(segment
		(start 178.84 111.11)
		(end 177.859999 111.11)
		(width 0.3)
		(layer "B.Cu")
		(net 969)
	)
	(segment
		(start 178.84 110.61)
		(end 177.859999 110.61)
		(width 0.3)
		(layer "B.Cu")
		(net 969)
	)
	(segment
		(start 177.86 93.61)
		(end 178.84 93.61)
		(width 0.3)
		(layer "B.Cu")
		(net 969)
	)
	(segment
		(start 178.84 95.61)
		(end 177.86 95.61)
		(width 0.3)
		(layer "B.Cu")
		(net 969)
	)
	(segment
		(start 178.84 110.11)
		(end 177.859999 110.11)
		(width 0.3)
		(layer "B.Cu")
		(net 969)
	)
	(segment
		(start 288.948 80.578)
		(end 288.948 81.583)
		(width 0.3)
		(layer "F.Cu")
		(net 970)
	)
	(segment
		(start 303.448 80.578)
		(end 303.448 81.583)
		(width 0.3)
		(layer "F.Cu")
		(net 970)
	)
	(segment
		(start 290.448 80.578)
		(end 290.448 81.583)
		(width 0.3)
		(layer "F.Cu")
		(net 970)
	)
	(segment
		(start 286.447 80.578)
		(end 286.447 81.583)
		(width 0.3)
		(layer "F.Cu")
		(net 970)
	)
	(segment
		(start 289.948 80.578)
		(end 289.948 81.583)
		(width 0.3)
		(layer "F.Cu")
		(net 970)
	)
	(segment
		(start 303.947 80.578)
		(end 303.947 81.583)
		(width 0.3)
		(layer "F.Cu")
		(net 970)
	)
	(segment
		(start 289.448 80.578)
		(end 289.448 81.583)
		(width 0.3)
		(layer "F.Cu")
		(net 970)
	)
	(segment
		(start 304.447 80.578)
		(end 304.447 81.583)
		(width 0.3)
		(layer "F.Cu")
		(net 970)
	)
	(segment
		(start 286.947 80.578)
		(end 286.947 81.583)
		(width 0.3)
		(layer "F.Cu")
		(net 970)
	)
	(via
		(at 303.947 80.578)
		(size 0.45)
		(drill 0.1)
		(layers "F.Cu" "B.Cu")
		(remove_unused_layers yes)
		(keep_end_layers yes)
		(zone_layer_connections)
		(teardrops
			(best_length_ratio 0.4)
			(max_length 1)
			(best_width_ratio 0.9)
			(max_width 2)
			(curved_edges yes)
			(filter_ratio 0.9)
			(enabled yes)
			(allow_two_segments yes)
			(prefer_zone_connections yes)
		)
		(net 970)
	)
	(via
		(at 289.948 80.578)
		(size 0.45)
		(drill 0.1)
		(layers "F.Cu" "B.Cu")
		(remove_unused_layers yes)
		(keep_end_layers yes)
		(zone_layer_connections)
		(teardrops
			(best_length_ratio 0.4)
			(max_length 1)
			(best_width_ratio 0.9)
			(max_width 2)
			(curved_edges yes)
			(filter_ratio 0.9)
			(enabled yes)
			(allow_two_segments yes)
			(prefer_zone_connections yes)
		)
		(net 970)
	)
	(via
		(at 303.448 80.578)
		(size 0.45)
		(drill 0.1)
		(layers "F.Cu" "B.Cu")
		(remove_unused_layers yes)
		(keep_end_layers yes)
		(zone_layer_connections)
		(teardrops
			(best_length_ratio 0.4)
			(max_length 1)
			(best_width_ratio 0.9)
			(max_width 2)
			(curved_edges yes)
			(filter_ratio 0.9)
			(enabled yes)
			(allow_two_segments yes)
			(prefer_zone_connections yes)
		)
		(net 970)
	)
	(via
		(at 290.448 80.578)
		(size 0.45)
		(drill 0.1)
		(layers "F.Cu" "B.Cu")
		(remove_unused_layers yes)
		(keep_end_layers yes)
		(zone_layer_connections)
		(teardrops
			(best_length_ratio 0.4)
			(max_length 1)
			(best_width_ratio 0.9)
			(max_width 2)
			(curved_edges yes)
			(filter_ratio 0.9)
			(enabled yes)
			(allow_two_segments yes)
			(prefer_zone_connections yes)
		)
		(net 970)
	)
	(via
		(at 289.448 80.578)
		(size 0.45)
		(drill 0.1)
		(layers "F.Cu" "B.Cu")
		(remove_unused_layers yes)
		(keep_end_layers yes)
		(zone_layer_connections)
		(teardrops
			(best_length_ratio 0.4)
			(max_length 1)
			(best_width_ratio 0.9)
			(max_width 2)
			(curved_edges yes)
			(filter_ratio 0.9)
			(enabled yes)
			(allow_two_segments yes)
			(prefer_zone_connections yes)
		)
		(net 970)
	)
	(via
		(at 288.948 80.578)
		(size 0.45)
		(drill 0.1)
		(layers "F.Cu" "B.Cu")
		(remove_unused_layers yes)
		(keep_end_layers yes)
		(zone_layer_connections)
		(teardrops
			(best_length_ratio 0.4)
			(max_length 1)
			(best_width_ratio 0.9)
			(max_width 2)
			(curved_edges yes)
			(filter_ratio 0.9)
			(enabled yes)
			(allow_two_segments yes)
			(prefer_zone_connections yes)
		)
		(net 970)
	)
	(via
		(at 286.447 80.578)
		(size 0.45)
		(drill 0.1)
		(layers "F.Cu" "B.Cu")
		(remove_unused_layers yes)
		(keep_end_layers yes)
		(zone_layer_connections)
		(teardrops
			(best_length_ratio 0.4)
			(max_length 1)
			(best_width_ratio 0.9)
			(max_width 2)
			(curved_edges yes)
			(filter_ratio 0.9)
			(enabled yes)
			(allow_two_segments yes)
			(prefer_zone_connections yes)
		)
		(net 970)
	)
	(via
		(at 304.447 80.578)
		(size 0.45)
		(drill 0.1)
		(layers "F.Cu" "B.Cu")
		(remove_unused_layers yes)
		(keep_end_layers yes)
		(zone_layer_connections)
		(teardrops
			(best_length_ratio 0.4)
			(max_length 1)
			(best_width_ratio 0.9)
			(max_width 2)
			(curved_edges yes)
			(filter_ratio 0.9)
			(enabled yes)
			(allow_two_segments yes)
			(prefer_zone_connections yes)
		)
		(net 970)
	)
	(via
		(at 286.947 80.578)
		(size 0.45)
		(drill 0.1)
		(layers "F.Cu" "B.Cu")
		(remove_unused_layers yes)
		(keep_end_layers yes)
		(zone_layer_connections)
		(teardrops
			(best_length_ratio 0.4)
			(max_length 1)
			(best_width_ratio 0.9)
			(max_width 2)
			(curved_edges yes)
			(filter_ratio 0.9)
			(enabled yes)
			(allow_two_segments yes)
			(prefer_zone_connections yes)
		)
		(net 970)
	)
	(segment
		(start 189.35 134.95)
		(end 189.35 131.071572)
		(width 0.125)
		(layer "F.Cu")
		(net 973)
	)
	(segment
		(start 192.003482 129.832304)
		(end 191.296375 129.125198)
		(width 0.125)
		(layer "F.Cu")
		(net 973)
	)
	(segment
		(start 189.35 131.071572)
		(end 191.296375 129.125197)
		(width 0.125)
		(layer "F.Cu")
		(net 973)
	)
	(segment
		(start 188.5 135.8)
		(end 189.35 134.95)
		(width 0.125)
		(layer "F.Cu")
		(net 973)
	)
	(via
		(at 188.5 135.8)
		(size 0.45)
		(drill 0.1)
		(layers "F.Cu" "B.Cu")
		(teardrops
			(best_length_ratio 0.4)
			(max_length 1)
			(best_width_ratio 0.9)
			(max_width 2)
			(curved_edges yes)
			(filter_ratio 0.9)
			(enabled yes)
			(allow_two_segments yes)
			(prefer_zone_connections yes)
		)
		(net 973)
	)
	(segment
		(start 188.5 135.8)
		(end 188.5 135.801576)
		(width 0.125)
		(layer "B.Cu")
		(net 973)
	)
	(segment
		(start 188.5 135.801576)
		(end 189.923387 137.224963)
		(width 0.125)
		(layer "B.Cu")
		(net 973)
	)
	(via
		(at 192.027029 141.237794)
		(size 0.45)
		(drill 0.1)
		(layers "F.Cu" "B.Cu")
		(remove_unused_layers yes)
		(keep_end_layers yes)
		(zone_layer_connections)
		(teardrops
			(best_length_ratio 0.4)
			(max_length 1)
			(best_width_ratio 0.9)
			(max_width 2)
			(curved_edges yes)
			(filter_ratio 0.9)
			(enabled yes)
			(allow_two_segments yes)
			(prefer_zone_connections yes)
		)
		(net 974)
	)
	(segment
		(start 192.027029 140.778175)
		(end 192.292194 140.51301)
		(width 0.125)
		(layer "B.Cu")
		(net 974)
	)
	(segment
		(start 192.292194 140.300878)
		(end 191.956319 139.965002)
		(width 0.125)
		(layer "B.Cu")
		(net 974)
	)
	(segment
		(start 192.027029 141.237794)
		(end 192.027029 140.778175)
		(width 0.125)
		(layer "B.Cu")
		(net 974)
	)
	(segment
		(start 192.292194 140.51301)
		(end 192.292194 140.300878)
		(width 0.125)
		(layer "B.Cu")
		(net 974)
	)
	(via
		(at 192.69 140.68)
		(size 0.45)
		(drill 0.1)
		(layers "F.Cu" "B.Cu")
		(remove_unused_layers yes)
		(keep_end_layers yes)
		(zone_layer_connections)
		(teardrops
			(best_length_ratio 0.4)
			(max_length 1)
			(best_width_ratio 0.9)
			(max_width 2)
			(curved_edges yes)
			(filter_ratio 0.9)
			(enabled yes)
			(allow_two_segments yes)
			(prefer_zone_connections yes)
		)
		(net 975)
	)
	(segment
		(start 192.69 139.991576)
		(end 192.309872 139.611448)
		(width 0.125)
		(layer "B.Cu")
		(net 975)
	)
	(segment
		(start 192.69 140.68)
		(end 192.69 139.991576)
		(width 0.125)
		(layer "B.Cu")
		(net 975)
	)
	(segment
		(start 188.5 136.6)
		(end 190.2 134.9)
		(width 0.125)
		(layer "F.Cu")
		(net 976)
	)
	(segment
		(start 190.2 134.9)
		(end 190.2 133.05)
		(width 0.125)
		(layer "F.Cu")
		(net 976)
	)
	(segment
		(start 188.5 137.05)
		(end 188.5 136.6)
		(width 0.125)
		(layer "F.Cu")
		(net 976)
	)
	(segment
		(start 192.710589 130.539411)
		(end 193.417696 131.246518)
		(width 0.125)
		(layer "F.Cu")
		(net 976)
	)
	(segment
		(start 190.2 133.05)
		(end 192.710589 130.539411)
		(width 0.125)
		(layer "F.Cu")
		(net 976)
	)
	(via
		(at 188.5 137.05)
		(size 0.45)
		(drill 0.1)
		(layers "F.Cu" "B.Cu")
		(teardrops
			(best_length_ratio 0.4)
			(max_length 1)
			(best_width_ratio 0.9)
			(max_width 2)
			(curved_edges yes)
			(filter_ratio 0.9)
			(enabled yes)
			(allow_two_segments yes)
			(prefer_zone_connections yes)
		)
		(net 976)
	)
	(segment
		(start 189.041317 137.05)
		(end 188.5 137.05)
		(width 0.125)
		(layer "B.Cu")
		(net 976)
	)
	(segment
		(start 189.569834 137.578517)
		(end 189.041317 137.05)
		(width 0.125)
		(layer "B.Cu")
		(net 976)
	)
	(segment
		(start 189.878132 140.08026)
		(end 189.842776 140.044905)
		(width 0.125)
		(layer "F.Cu")
		(net 977)
	)
	(segment
		(start 189.453868 139.373153)
		(end 189.453868 139.655996)
		(width 0.125)
		(layer "F.Cu")
		(net 977)
	)
	(segment
		(start 189.453868 139.655996)
		(end 189.842776 140.044905)
		(width 0.125)
		(layer "F.Cu")
		(net 977)
	)
	(segment
		(start 189.715497 139.111524)
		(end 189.453868 139.373153)
		(width 0.125)
		(layer "F.Cu")
		(net 977)
	)
	(segment
		(start 190.422604 139.818631)
		(end 190.160974 140.08026)
		(width 0.125)
		(layer "F.Cu")
		(net 977)
	)
	(segment
		(start 190.160974 140.08026)
		(end 189.878132 140.08026)
		(width 0.125)
		(layer "F.Cu")
		(net 977)
	)
	(via
		(at 189.842776 140.044905)
		(size 0.45)
		(drill 0.1)
		(layers "F.Cu" "B.Cu")
		(remove_unused_layers yes)
		(keep_end_layers yes)
		(zone_layer_connections)
		(teardrops
			(best_length_ratio 0.4)
			(max_length 1)
			(best_width_ratio 0.9)
			(max_width 2)
			(curved_edges yes)
			(filter_ratio 0.9)
			(enabled yes)
			(allow_two_segments yes)
			(prefer_zone_connections yes)
		)
		(net 977)
	)
	(segment
		(start 189.842776 140.044905)
		(end 190.629079 139.258602)
		(width 0.125)
		(layer "B.Cu")
		(net 977)
	)
	(segment
		(start 190.832726 140.822722)
		(end 190.620594 140.822722)
		(width 0.125)
		(layer "F.Cu")
		(net 978)
	)
	(segment
		(start 189.772066 140.61059)
		(end 188.640695 139.479219)
		(width 0.125)
		(layer "F.Cu")
		(net 978)
	)
	(segment
		(start 188.640695 139.479219)
		(end 188.640695 138.772113)
		(width 0.125)
		(layer "F.Cu")
		(net 978)
	)
	(segment
		(start 190.408462 140.61059)
		(end 189.772066 140.61059)
		(width 0.125)
		(layer "F.Cu")
		(net 978)
	)
	(segment
		(start 190.620594 140.822722)
		(end 190.408462 140.61059)
		(width 0.125)
		(layer "F.Cu")
		(net 978)
	)
	(segment
		(start 188.640695 138.772113)
		(end 189.00839 138.404417)
		(width 0.125)
		(layer "F.Cu")
		(net 978)
	)
	(segment
		(start 191.129711 140.525737)
		(end 190.832726 140.822722)
		(width 0.125)
		(layer "F.Cu")
		(net 978)
	)
	(via
		(at 190.408462 140.61059)
		(size 0.45)
		(drill 0.1)
		(layers "F.Cu" "B.Cu")
		(remove_unused_layers yes)
		(keep_end_layers yes)
		(zone_layer_connections)
		(teardrops
			(best_length_ratio 0.4)
			(max_length 1)
			(best_width_ratio 0.9)
			(max_width 2)
			(curved_edges yes)
			(filter_ratio 0.9)
			(enabled yes)
			(allow_two_segments yes)
			(prefer_zone_connections yes)
		)
		(net 978)
	)
	(segment
		(start 190.408462 140.61059)
		(end 190.408462 140.184912)
		(width 0.125)
		(layer "B.Cu")
		(net 978)
	)
	(segment
		(start 190.408462 140.184912)
		(end 190.982633 139.610741)
		(width 0.125)
		(layer "B.Cu")
		(net 978)
	)
	(segment
		(start 201.70861 76.672163)
		(end 201.70861 75.502163)
		(width 0.2)
		(layer "F.Cu")
		(net 979)
	)
	(segment
		(start 199.70861 76.672163)
		(end 199.70861 75.502163)
		(width 0.2)
		(layer "F.Cu")
		(net 980)
	)
	(segment
		(start 197.70861 76.672163)
		(end 197.70861 75.502163)
		(width 0.2)
		(layer "F.Cu")
		(net 981)
	)
	(segment
		(start 190.70861 76.672163)
		(end 190.70861 75.502163)
		(width 0.2)
		(layer "F.Cu")
		(net 982)
	)
	(segment
		(start 186.70861 76.672163)
		(end 186.70861 75.502163)
		(width 0.2)
		(layer "F.Cu")
		(net 983)
	)
	(segment
		(start 193.70861 76.672163)
		(end 193.70861 75.502163)
		(width 0.2)
		(layer "F.Cu")
		(net 984)
	)
	(segment
		(start 188.70861 76.672163)
		(end 188.70861 75.502163)
		(width 0.2)
		(layer "F.Cu")
		(net 985)
	)
	(segment
		(start 195.70861 76.672163)
		(end 195.70861 75.502163)
		(width 0.2)
		(layer "F.Cu")
		(net 986)
	)
	(segment
		(start 201.499 83.324447)
		(end 201.52239 83.347837)
		(width 0.2)
		(layer "F.Cu")
		(net 987)
	)
	(segment
		(start 201.499 81.85)
		(end 201.499 83.324447)
		(width 0.2)
		(layer "F.Cu")
		(net 987)
	)
	(segment
		(start 201.70861 78.18361)
		(end 202.4495 78.9245)
		(width 0.2)
		(layer "F.Cu")
		(net 988)
	)
	(segment
		(start 201.70861 77.632163)
		(end 201.70861 78.18361)
		(width 0.2)
		(layer "F.Cu")
		(net 988)
	)
	(segment
		(start 202.4495 78.9245)
		(end 202.4495 79.65)
		(width 0.2)
		(layer "F.Cu")
		(net 988)
	)
	(segment
		(start 198.049 81.85)
		(end 198.049 82.009)
		(width 0.2)
		(layer "F.Cu")
		(net 989)
	)
	(segment
		(start 198.05 82.01)
		(end 198.05 83.38)
		(width 0.2)
		(layer "F.Cu")
		(net 989)
	)
	(segment
		(start 198.049 82.009)
		(end 198.05 82.01)
		(width 0.2)
		(layer "F.Cu")
		(net 989)
	)
	(segment
		(start 199.70861 78.14139)
		(end 198.9995 78.8505)
		(width 0.2)
		(layer "F.Cu")
		(net 990)
	)
	(segment
		(start 198.9995 78.8505)
		(end 198.9995 79.65)
		(width 0.2)
		(layer "F.Cu")
		(net 990)
	)
	(segment
		(start 199.70861 77.632163)
		(end 199.70861 78.14139)
		(width 0.2)
		(layer "F.Cu")
		(net 990)
	)
	(segment
		(start 206.58 112.81)
		(end 206.58 100.32)
		(width 0.125)
		(layer "F.Cu")
		(net 999)
	)
	(segment
		(start 206.58 100.32)
		(end 178.17 71.91)
		(width 0.125)
		(layer "F.Cu")
		(net 999)
	)
	(segment
		(start 235.22 124.82)
		(end 223.97 113.57)
		(width 0.125)
		(layer "F.Cu")
		(net 999)
	)
	(segment
		(start 247.350002 127.83)
		(end 247.350001 127.830001)
		(width 0.125)
		(layer "F.Cu")
		(net 999)
	)
	(segment
		(start 247.350001 126.330001)
		(end 245.84 124.82)
		(width 0.125)
		(layer "F.Cu")
		(net 999)
	)
	(segment
		(start 247.350001 127.830001)
		(end 247.350001 126.330001)
		(width 0.125)
		(layer "F.Cu")
		(net 999)
	)
	(segment
		(start 178.17 71.91)
		(end 178.17 70.61)
		(width 0.125)
		(layer "F.Cu")
		(net 999)
	)
	(segment
		(start 248.35 127.83)
		(end 247.350002 127.83)
		(width 0.125)
		(layer "F.Cu")
		(net 999)
	)
	(segment
		(start 223.97 113.57)
		(end 207.34 113.57)
		(width 0.125)
		(layer "F.Cu")
		(net 999)
	)
	(segment
		(start 245.84 124.82)
		(end 235.22 124.82)
		(width 0.125)
		(layer "F.Cu")
		(net 999)
	)
	(segment
		(start 207.34 113.57)
		(end 206.58 112.81)
		(width 0.125)
		(layer "F.Cu")
		(net 999)
	)
	(zone
		(net 550)
		(net_name "Net-(R15-Pad2)")
		(layer "F.Cu")
		(name "$teardrop_padvia$")
		(hatch none 0.1)
		(priority 30429)
		(attr
			(teardrop
				(type padvia)
			)
		)
		(connect_pads yes
			(clearance 0)
		)
		(min_thickness 0.0254)
		(filled_areas_thickness no)
		(fill yes
			(thermal_gap 0.5)
			(thermal_bridge_width 0.5)
			(island_removal_mode 1)
			(island_area_min 10)
		)
		(polygon
			(pts
				(xy 135.42 105.635) (xy 135.370167 105.62574) (xy 135.346156 105.609372) (xy 135.326648 105.580919)
				(xy 135.312274 105.51) (xy 134.844 105.735) (xy 135.312274 105.96) (xy 135.318547 105.91239) (xy 135.332162 105.878567)
				(xy 135.372122 105.843408) (xy 135.42 105.835)
			)
		)
	)
	(zone
		(net 1)
		(net_name "GND")
		(layer "F.Cu")
		(name "$teardrop_padvia$")
		(hatch none 0.1)
		(priority 31335)
		(attr
			(teardrop
				(type padvia)
			)
		)
		(connect_pads yes
			(clearance 0)
		)
		(min_thickness 0.0254)
		(filled_areas_thickness no)
		(fill yes
			(thermal_gap 0.5)
			(thermal_bridge_width 0.5)
			(island_removal_mode 1)
			(island_area_min 10)
		)
		(polygon
			(pts
				(xy 215.125 162.017082) (xy 215.129736 161.970484) (xy 215.142885 161.935208) (xy 215.187876 161.887433)
				(xy 215.226677 161.863271) (xy 215.270388 161.835998) (xy 215.312833 161.79925) (xy 215.15 161.649)
				(xy 214.929323 161.669078) (xy 214.930273 161.855177) (xy 214.925 162.017082)
			)
		)
	)
	(zone
		(net 242)
		(net_name "/Com Express 7 Interfaces/PCIe_{B2Bx4}.TX3+")
		(layer "F.Cu")
		(name "$teardrop_padvia$")
		(hatch none 0.1)
		(priority 31389)
		(attr
			(teardrop
				(type padvia)
			)
		)
		(connect_pads yes
			(clearance 0)
		)
		(min_thickness 0.0254)
		(filled_areas_thickness no)
		(fill yes
			(thermal_gap 0.5)
			(thermal_bridge_width 0.5)
			(island_removal_mode 1)
			(island_area_min 10)
		)
		(polygon
			(pts
				(xy 186.6815 167.367496) (xy 186.676105 167.205964) (xy 186.672555 167.121553) (xy 186.677177 167.019859)
				(xy 186.4565 166.999) (xy 186.293268 167.148852) (xy 186.361936 167.202992) (xy 186.378392 167.212884)
				(xy 186.417064 167.237384) (xy 186.449279 167.26689) (xy 186.471327 167.308046) (xy 186.4795 167.367496)
			)
		)
	)
	(zone
		(net 1)
		(net_name "GND")
		(layer "F.Cu")
		(name "$teardrop_padvia$")
		(hatch none 0.1)
		(priority 30794)
		(attr
			(teardrop
				(type padvia)
			)
		)
		(connect_pads yes
			(clearance 0)
		)
		(min_thickness 0.0254)
		(filled_areas_thickness no)
		(fill yes
			(thermal_gap 0.5)
			(thermal_bridge_width 0.5)
			(island_removal_mode 1)
			(island_area_min 10)
		)
		(polygon
			(pts
				(xy 300.048 74.639323) (xy 300.041069 74.796893) (xy 300.012549 74.910421) (xy 299.9955 74.952221)
				(xy 300.198 75.041) (xy 300.4005 74.952221) (xy 300.366117 74.856179) (xy 300.3509 74.754304) (xy 300.348 74.639323)
			)
		)
	)
	(zone
		(net 735)
		(net_name "Net-(U43A-LS_OK_{IN_A})")
		(layer "F.Cu")
		(name "$teardrop_padvia$")
		(hatch none 0.1)
		(priority 30110)
		(attr
			(teardrop
				(type padvia)
			)
		)
		(connect_pads yes
			(clearance 0)
		)
		(min_thickness 0.0254)
		(filled_areas_thickness no)
		(fill yes
			(thermal_gap 0.5)
			(thermal_bridge_width 0.5)
			(island_removal_mode 1)
			(island_area_min 10)
		)
		(polygon
			(pts
				(xy 155.7625 129.377794) (xy 155.767315 129.295733) (xy 155.781019 129.230388) (xy 155.827576 129.13712)
				(xy 155.895787 129.058657) (xy 155.951942 128.997158) (xy 156.011801 128.918339) (xy 155.7 128.709)
				(xy 155.388199 128.918339) (xy 155.485219 129.038517) (xy 155.504214 129.058658) (xy 155.557366 129.117541)
				(xy 155.599591 129.181624) (xy 155.627449 129.264008) (xy 155.6375 129.377794)
			)
		)
	)
	(zone
		(net 637)
		(net_name "Net-(U41-~{RESET})")
		(layer "F.Cu")
		(name "$teardrop_padvia$")
		(hatch none 0.1)
		(priority 32009)
		(attr
			(teardrop
				(type padvia)
			)
		)
		(connect_pads yes
			(clearance 0)
		)
		(min_thickness 0.0254)
		(filled_areas_thickness no)
		(fill yes
			(thermal_gap 0.5)
			(thermal_bridge_width 0.5)
			(island_removal_mode 1)
			(island_area_min 10)
		)
		(polygon
			(pts
				(xy 129.3375 83.1595) (xy 129.337596 83.165822) (xy 129.332011 83.205325) (xy 129.317078 83.223547)
				(xy 129.2875 83.236495) (xy 129.4 83.623) (xy 129.5125 83.236495) (xy 129.485507 83.225379) (xy 129.470405 83.209852)
				(xy 129.462404 83.165822) (xy 129.4625 83.1595)
			)
		)
	)
	(zone
		(net 127)
		(net_name "/USB-C console/FTDI_LED_RX")
		(layer "F.Cu")
		(name "$teardrop_padvia$")
		(hatch none 0.1)
		(priority 30173)
		(attr
			(teardrop
				(type padvia)
			)
		)
		(connect_pads yes
			(clearance 0)
		)
		(min_thickness 0.0254)
		(filled_areas_thickness no)
		(fill yes
			(thermal_gap 0.5)
			(thermal_bridge_width 0.5)
			(island_removal_mode 1)
			(island_area_min 10)
		)
		(polygon
			(pts
				(xy 112.4625 71.12) (xy 112.481757 71.06156) (xy 112.542765 71.007485) (xy 112.652366 70.967203)
				(xy 112.76 70.956021) (xy 112.4 70.559) (xy 112.04 70.956021) (xy 112.115789 70.961642) (xy 112.182251 70.975856)
				(xy 112.23852 70.997451) (xy 112.283209 71.025051) (xy 112.313499 71.055041) (xy 112.331876 71.088017)
				(xy 112.3375 71.12)
			)
		)
	)
	(zone
		(net 162)
		(net_name "Net-(J2A-TX_{FAULT})")
		(layer "F.Cu")
		(name "$teardrop_padvia$")
		(hatch none 0.1)
		(priority 31734)
		(attr
			(teardrop
				(type padvia)
			)
		)
		(connect_pads yes
			(clearance 0)
		)
		(min_thickness 0.0254)
		(filled_areas_thickness no)
		(fill yes
			(thermal_gap 0.5)
			(thermal_bridge_width 0.5)
			(island_removal_mode 1)
			(island_area_min 10)
		)
		(polygon
			(pts
				(xy 142.9875 167.309323) (xy 142.982682 167.378763) (xy 142.96896 167.430087) (xy 142.922245 167.505628)
				(xy 142.912702 167.517768) (xy 142.862919 167.584997) (xy 143.05 167.711) (xy 143.237081 167.584997)
				(xy 143.187299 167.517769) (xy 143.132894 167.434603) (xy 143.11781 167.381748) (xy 143.1125 167.309323)
			)
		)
	)
	(zone
		(net 208)
		(net_name "/Backplane/UART.RX")
		(layer "F.Cu")
		(name "$teardrop_padvia$")
		(hatch none 0.1)
		(priority 32118)
		(attr
			(teardrop
				(type padvia)
			)
		)
		(connect_pads yes
			(clearance 0)
		)
		(min_thickness 0.0254)
		(filled_areas_thickness no)
		(fill yes
			(thermal_gap 0.5)
			(thermal_bridge_width 0.5)
			(island_removal_mode 1)
			(island_area_min 10)
		)
		(polygon
			(pts
				(xy 315.46 167.4455) (xy 315.453678 167.445596) (xy 315.414175 167.440011) (xy 315.395953 167.425078)
				(xy 315.383005 167.3955) (xy 315.134 167.508) (xy 315.383005 167.6205) (xy 315.394121 167.593506)
				(xy 315.409648 167.578405) (xy 315.453678 167.570404) (xy 315.46 167.5705)
			)
		)
	)
	(zone
		(net 193)
		(net_name "/OCuLink/PCIe_{REF0}.CK-")
		(layer "F.Cu")
		(name "$teardrop_padvia$")
		(hatch none 0.1)
		(priority 31350)
		(attr
			(teardrop
				(type padvia)
			)
		)
		(connect_pads yes
			(clearance 0)
		)
		(min_thickness 0.0254)
		(filled_areas_thickness no)
		(fill yes
			(thermal_gap 0.5)
			(thermal_bridge_width 0.5)
			(island_removal_mode 1)
			(island_area_min 10)
		)
		(polygon
			(pts
				(xy 99.396202 161.0545) (xy 99.349416 161.049765) (xy 99.313964 161.036621) (xy 99.265766 160.991613)
				(xy 99.24159 160.953392) (xy 99.21422 160.910225) (xy 99.177558 160.868268) (xy 99.027706 161.0315)
				(xy 99.048566 161.252177) (xy 99.149237 161.247548) (xy 99.232603 161.25098) (xy 99.23467 161.251105)
				(xy 99.396202 161.2565)
			)
		)
	)
	(zone
		(net 193)
		(net_name "/OCuLink/PCIe_{REF0}.CK-")
		(layer "F.Cu")
		(name "$teardrop_padvia$")
		(hatch none 0.1)
		(priority 30434)
		(attr
			(teardrop
				(type padvia)
			)
		)
		(connect_pads yes
			(clearance 0)
		)
		(min_thickness 0.0254)
		(filled_areas_thickness no)
		(fill yes
			(thermal_gap 0.5)
			(thermal_bridge_width 0.5)
			(island_removal_mode 1)
			(island_area_min 10)
		)
		(polygon
			(pts
				(xy 210.434479 129.8315) (xy 210.512726 129.789542) (xy 210.611279 129.75353) (xy 210.688154 129.738171)
				(xy 210.768421 129.735558) (xy 210.831754 129.745) (xy 210.801 129.425) (xy 210.505 129.326085)
				(xy 210.507815 129.450467) (xy 210.495293 129.541353) (xy 210.478304 129.583387) (xy 210.453452 129.615034)
				(xy 210.434479 129.6295)
			)
		)
	)
	(zone
		(net 553)
		(net_name "/2xUSB3.0+RJ45/FLG_1B")
		(layer "F.Cu")
		(name "$teardrop_padvia$")
		(hatch none 0.1)
		(priority 30995)
		(attr
			(teardrop
				(type padvia)
			)
		)
		(connect_pads yes
			(clearance 0)
		)
		(min_thickness 0.0254)
		(filled_areas_thickness no)
		(fill yes
			(thermal_gap 0.5)
			(thermal_bridge_width 0.5)
			(island_removal_mode 1)
			(island_area_min 10)
		)
		(polygon
			(pts
				(xy 121.5075 87.622) (xy 121.487531 87.684866) (xy 121.461079 87.716844) (xy 121.423668 87.745358)
				(xy 121.376473 87.767882) (xy 121.318833 87.783093) (xy 121.318202 87.783202) (xy 121.57 88.061)
				(xy 121.821798 87.783202) (xy 121.766365 87.768905) (xy 121.72048 87.747825) (xy 121.682799 87.72046)
				(xy 121.655566 87.689552) (xy 121.638528 87.656265) (xy 121.632511 87.623434) (xy 121.6325 87.622)
			)
		)
	)
	(zone
		(net 192)
		(net_name "/OCuLink/PCIe_{REF0}.CK+")
		(layer "F.Cu")
		(name "$teardrop_padvia$")
		(hatch none 0.1)
		(priority 31434)
		(attr
			(teardrop
				(type padvia)
			)
		)
		(connect_pads yes
			(clearance 0)
		)
		(min_thickness 0.0254)
		(filled_areas_thickness no)
		(fill yes
			(thermal_gap 0.5)
			(thermal_bridge_width 0.5)
			(island_removal_mode 1)
			(island_area_min 10)
		)
		(polygon
			(pts
				(xy 99.396202 161.4435) (xy 99.23467 161.448895) (xy 99.15026 161.452445) (xy 99.048566 161.447823)
				(xy 99.027706 161.6685) (xy 99.177558 161.831731) (xy 99.231698 161.763062) (xy 99.241589 161.746608)
				(xy 99.266089 161.707935) (xy 99.295596 161.675721) (xy 99.336752 161.653673) (xy 99.396202 161.6455)
			)
		)
	)
	(zone
		(net 1)
		(net_name "GND")
		(layer "F.Cu")
		(name "$teardrop_padvia$")
		(hatch none 0.1)
		(priority 30870)
		(attr
			(teardrop
				(type padvia)
			)
		)
		(connect_pads yes
			(clearance 0)
		)
		(min_thickness 0.0254)
		(filled_areas_thickness no)
		(fill yes
			(thermal_gap 0.5)
			(thermal_bridge_width 0.5)
			(island_removal_mode 1)
			(island_area_min 10)
		)
		(polygon
			(pts
				(xy 197.80861 78.045163) (xy 197.814382 78.004426) (xy 197.834786 77.962511) (xy 197.861961 77.93421)
				(xy 197.901507 77.910781) (xy 197.97411 77.89151) (xy 197.70861 77.631163) (xy 197.44311 77.89151)
				(xy 197.496252 77.903377) (xy 197.537291 77.921825) (xy 197.588992 77.972499) (xy 197.608328 78.036068)
				(xy 197.60861 78.045163)
			)
		)
	)
	(zone
		(net 605)
		(net_name "Net-(U37-~{OE3})")
		(layer "F.Cu")
		(name "$teardrop_padvia$")
		(hatch none 0.1)
		(priority 30939)
		(attr
			(teardrop
				(type padvia)
			)
		)
		(connect_pads yes
			(clearance 0)
		)
		(min_thickness 0.0254)
		(filled_areas_thickness no)
		(fill yes
			(thermal_gap 0.5)
			(thermal_bridge_width 0.5)
			(island_removal_mode 1)
			(island_area_min 10)
		)
		(polygon
			(pts
				(xy 218.994501 132.6825) (xy 219.057367 132.702469) (xy 219.089345 132.728921) (xy 219.117859 132.766332)
				(xy 219.140383 132.813527) (xy 219.155594 132.871167) (xy 219.155703 132.871798) (xy 219.433501 132.62)
				(xy 219.155703 132.368202) (xy 219.141406 132.423635) (xy 219.120326 132.46952) (xy 219.092961 132.507201)
				(xy 219.062053 132.534434) (xy 219.028766 132.551472) (xy 218.995935 132.557489) (xy 218.994501 132.5575)
			)
		)
	)
	(zone
		(net 638)
		(net_name "Net-(U41-A1)")
		(layer "F.Cu")
		(name "$teardrop_padvia$")
		(hatch none 0.1)
		(priority 32044)
		(attr
			(teardrop
				(type padvia)
			)
		)
		(connect_pads yes
			(clearance 0)
		)
		(min_thickness 0.0254)
		(filled_areas_thickness no)
		(fill yes
			(thermal_gap 0.5)
			(thermal_bridge_width 0.5)
			(island_removal_mode 1)
			(island_area_min 10)
		)
		(polygon
			(pts
				(xy 129.78995 83.218338) (xy 129.795236 83.221663) (xy 129.804336 83.230835) (xy 129.779758 83.248082)
				(xy 129.900707 83.622707) (xy 129.953122 83.2095) (xy 129.919495 83.193225) (xy 129.895914 83.157139)
				(xy 129.878337 83.129951)
			)
		)
	)
	(zone
		(net 639)
		(net_name "Net-(U41-IO0_0)")
		(layer "F.Cu")
		(name "$teardrop_padvia$")
		(hatch none 0.1)
		(priority 31084)
		(attr
			(teardrop
				(type padvia)
			)
		)
		(connect_pads yes
			(clearance 0)
		)
		(min_thickness 0.0254)
		(filled_areas_thickness no)
		(fill yes
			(thermal_gap 0.5)
			(thermal_bridge_width 0.5)
			(island_removal_mode 1)
			(island_area_min 10)
		)
		(polygon
			(pts
				(xy 127.318 82.9975) (xy 127.258588 82.977727) (xy 127.202503 82.914453) (xy 127.180801 82.865828)
				(xy 127.166127 82.806468) (xy 127.164347 82.7945) (xy 126.904 83.06) (xy 127.164347 83.3255) (xy 127.177197 83.265361)
				(xy 127.197131 83.215477) (xy 127.223056 83.175358) (xy 127.252876 83.146345) (xy 127.284294 83.128854)
				(xy 127.316105 83.122521) (xy 127.318 83.1225)
			)
		)
	)
	(zone
		(net 136)
		(net_name "/Com Express 7 MGMT/~{TYPE0}")
		(layer "F.Cu")
		(name "$teardrop_padvia$")
		(hatch none 0.1)
		(priority 30961)
		(attr
			(teardrop
				(type padvia)
			)
		)
		(connect_pads yes
			(clearance 0)
		)
		(min_thickness 0.0254)
		(filled_areas_thickness no)
		(fill yes
			(thermal_gap 0.5)
			(thermal_bridge_width 0.5)
			(island_removal_mode 1)
			(island_area_min 10)
		)
		(polygon
			(pts
				(xy 252.063 132.7775) (xy 252.000134 132.757531) (xy 251.968156 132.731079) (xy 251.939642 132.693668)
				(xy 251.917118 132.646473) (xy 251.901907 132.588833) (xy 251.901798 132.588202) (xy 251.624 132.84)
				(xy 251.901798 133.091798) (xy 251.916095 133.036365) (xy 251.937175 132.99048) (xy 251.96454 132.952799)
				(xy 251.995448 132.925566) (xy 252.028735 132.908528) (xy 252.061566 132.902511) (xy 252.063 132.9025)
			)
		)
	)
	(zone
		(net 425)
		(net_name "/2xSFP+/I2C_{SFP0}.SDA")
		(layer "F.Cu")
		(name "$teardrop_padvia$")
		(hatch none 0.1)
		(priority 31883)
		(attr
			(teardrop
				(type padvia)
			)
		)
		(connect_pads yes
			(clearance 0)
		)
		(min_thickness 0.0254)
		(filled_areas_thickness no)
		(fill yes
			(thermal_gap 0.5)
			(thermal_bridge_width 0.5)
			(island_removal_mode 1)
			(island_area_min 10)
		)
		(polygon
			(pts
				(xy 193.177515 153.289127) (xy 193.131819 153.236618) (xy 193.105231 153.190623) (xy 193.084847 153.104175)
				(xy 193.083011 153.08884) (xy 193.070677 153.006105) (xy 192.849293 153.049293) (xy 192.806105 153.270677)
				(xy 192.88884 153.283011) (xy 192.986119 153.303349) (xy 193.034159 153.330057) (xy 193.089127 153.377515)
			)
		)
	)
	(zone
		(net 296)
		(net_name "/2xUSB3.0+RJ45/GbE.CTREF")
		(layer "F.Cu")
		(name "$teardrop_padvia$")
		(hatch none 0.1)
		(priority 30637)
		(attr
			(teardrop
				(type padvia)
			)
		)
		(connect_pads yes
			(clearance 0)
		)
		(min_thickness 0.0254)
		(filled_areas_thickness no)
		(fill yes
			(thermal_gap 0.5)
			(thermal_bridge_width 0.5)
			(island_removal_mode 1)
			(island_area_min 10)
		)
		(polygon
			(pts
				(xy 182.5875 169.62) (xy 182.598438 169.581177) (xy 182.620195 169.566067) (xy 182.66 169.56) (xy 182.525 168.684)
				(xy 182.39 169.56) (xy 182.425281 169.564517) (xy 182.446797 169.576138) (xy 182.461995 169.608961)
				(xy 182.4625 169.62)
			)
		)
	)
	(zone
		(net 947)
		(net_name "/2xSFP+/KR to SFI #2/SFI_R.TX+")
		(layer "F.Cu")
		(name "$teardrop_padvia$")
		(hatch none 0.1)
		(priority 31968)
		(attr
			(teardrop
				(type padvia)
			)
		)
		(connect_pads yes
			(clearance 0)
		)
		(min_thickness 0.0254)
		(filled_areas_thickness no)
		(fill yes
			(thermal_gap 0.5)
			(thermal_bridge_width 0.5)
			(island_removal_mode 1)
			(island_area_min 10)
		)
		(polygon
			(pts
				(xy 128.9 146.717279) (xy 128.924062 146.786651) (xy 128.960577 146.896598) (xy 128.970888 146.956686)
				(xy 128.97 147.018536) (xy 129.17 146.991) (xy 129.228769 146.76) (xy 129.147423 146.765298) (xy 129.095406 146.756508)
				(xy 129.073886 146.742657) (xy 129.061647 146.722599) (xy 129.06 146.717279)
			)
		)
	)
	(zone
		(net 970)
		(net_name "/M.2 key M #2/M2_3V3")
		(layer "F.Cu")
		(name "$teardrop_padvia$")
		(hatch none 0.1)
		(priority 30763)
		(attr
			(teardrop
				(type padvia)
			)
		)
		(connect_pads yes
			(clearance 0)
		)
		(min_thickness 0.0254)
		(filled_areas_thickness no)
		(fill yes
			(thermal_gap 0.5)
			(thermal_bridge_width 0.5)
			(island_removal_mode 1)
			(island_area_min 10)
		)
		(polygon
			(pts
				(xy 304.097 80.978677) (xy 304.103932 80.8211) (xy 304.132456 80.707565) (xy 304.1495 80.665778)
				(xy 303.947 80.577) (xy 303.7445 80.665778) (xy 303.778883 80.761822) (xy 303.794101 80.863702)
				(xy 303.797 80.978677)
			)
		)
	)
	(zone
		(net 537)
		(net_name "/Backplane/PCIe_{x2}.RX0-")
		(layer "F.Cu")
		(name "$teardrop_padvia$")
		(hatch none 0.1)
		(priority 30020)
		(attr
			(teardrop
				(type padvia)
			)
		)
		(connect_pads yes
			(clearance 0)
		)
		(min_thickness 0.0254)
		(filled_areas_thickness no)
		(fill yes
			(thermal_gap 0.5)
			(thermal_bridge_width 0.5)
			(island_removal_mode 1)
			(island_area_min 10)
		)
		(polygon
			(pts
				(xy 317.860744 160.0055) (xy 317.893777 160.011457) (xy 317.923712 160.033158) (xy 317.939644 160.060607)
				(xy 317.949306 160.100407) (xy 317.95 160.165591) (xy 319.451 160.11) (xy 319.254117 159.835) (xy 318.774522 159.844225)
				(xy 318.255858 159.820754) (xy 317.860744 159.8035)
			)
		)
	)
	(zone
		(net 685)
		(net_name "/2xSFP+/KR to SFI #1/SFI_R.TX-")
		(layer "F.Cu")
		(name "$teardrop_padvia$")
		(hatch none 0.1)
		(priority 31948)
		(attr
			(teardrop
				(type padvia)
			)
		)
		(connect_pads yes
			(clearance 0)
		)
		(min_thickness 0.0254)
		(filled_areas_thickness no)
		(fill yes
			(thermal_gap 0.5)
			(thermal_bridge_width 0.5)
			(island_removal_mode 1)
			(island_area_min 10)
		)
		(polygon
			(pts
				(xy 146.68 146.717279) (xy 146.668264 146.740315) (xy 146.645802 146.756014) (xy 146.569443 146.765137)
				(xy 146.511231 146.76) (xy 146.57 146.991) (xy 146.77 147.018536) (xy 146.774353 146.919743) (xy 146.815938 146.786651)
				(xy 146.84 146.717279)
			)
		)
	)
	(zone
		(net 77)
		(net_name "+5V_AON")
		(layer "F.Cu")
		(name "$teardrop_padvia$")
		(hatch none 0.1)
		(priority 31298)
		(attr
			(teardrop
				(type padvia)
			)
		)
		(connect_pads yes
			(clearance 0)
		)
		(min_thickness 0.0254)
		(filled_areas_thickness no)
		(fill yes
			(thermal_gap 0.5)
			(thermal_bridge_width 0.5)
			(island_removal_mode 1)
			(island_area_min 10)
		)
		(polygon
			(pts
				(xy 188.608611 73.701486) (xy 188.603898 73.779397) (xy 188.59091 73.838181) (xy 188.548809 73.929211)
				(xy 188.50611 74.014384) (xy 188.70861 74.103162) (xy 188.91111 74.014385) (xy 188.868411 73.929214)
				(xy 188.825743 73.83638) (xy 188.813166 73.778242) (xy 188.80861 73.701487)
			)
		)
	)
	(zone
		(net 1)
		(net_name "GND")
		(layer "F.Cu")
		(name "$teardrop_padvia$")
		(hatch none 0.1)
		(priority 31320)
		(attr
			(teardrop
				(type padvia)
			)
		)
		(connect_pads yes
			(clearance 0)
		)
		(min_thickness 0.0254)
		(filled_areas_thickness no)
		(fill yes
			(thermal_gap 0.5)
			(thermal_bridge_width 0.5)
			(island_removal_mode 1)
			(island_area_min 10)
		)
		(polygon
			(pts
				(xy 181.125 162.087793) (xy 181.129731 162.032196) (xy 181.14285 161.989645) (xy 181.188022 161.927772)
				(xy 181.211704 161.905388) (xy 181.280694 161.831389) (xy 181.1 161.699) (xy 180.883268 161.753421)
				(xy 180.88519 161.761215) (xy 180.916806 161.910064) (xy 180.925 162.087793)
			)
		)
	)
	(zone
		(net 684)
		(net_name "Net-(U45C-ST)")
		(layer "F.Cu")
		(name "$teardrop_padvia$")
		(hatch none 0.1)
		(priority 30972)
		(attr
			(teardrop
				(type padvia)
			)
		)
		(connect_pads yes
			(clearance 0)
		)
		(min_thickness 0.0254)
		(filled_areas_thickness no)
		(fill yes
			(thermal_gap 0.5)
			(thermal_bridge_width 0.5)
			(island_removal_mode 1)
			(island_area_min 10)
		)
		(polygon
			(pts
				(xy 125.3825 134.318) (xy 125.402469 134.255134) (xy 125.428921 134.223156) (xy 125.466332 134.194642)
				(xy 125.513527 134.172118) (xy 125.571167 134.156907) (xy 125.571798 134.156798) (xy 125.32 133.879)
				(xy 125.068202 134.156798) (xy 125.123635 134.171095) (xy 125.16952 134.192175) (xy 125.207201 134.21954)
				(xy 125.234434 134.250448) (xy 125.251472 134.283735) (xy 125.257489 134.316566) (xy 125.2575 134.318)
			)
		)
	)
	(zone
		(net 685)
		(net_name "/2xSFP+/KR to SFI #1/SFI_R.TX-")
		(layer "F.Cu")
		(name "$teardrop_padvia$")
		(hatch none 0.1)
		(priority 31176)
		(attr
			(teardrop
				(type padvia)
			)
		)
		(connect_pads yes
			(clearance 0)
		)
		(min_thickness 0.0254)
		(filled_areas_thickness no)
		(fill yes
			(thermal_gap 0.5)
			(thermal_bridge_width 0.5)
			(island_removal_mode 1)
			(island_area_min 10)
		)
		(polygon
			(pts
				(xy 146.84 143.17679) (xy 146.835347 143.112802) (xy 146.822777 143.062121) (xy 146.778645 142.980204)
				(xy 146.767609 142.964616) (xy 146.726024 142.899819) (xy 146.695196 142.811227) (xy 146.45 142.859)
				(xy 146.401227 143.105196) (xy 146.488185 143.107002) (xy 146.531073 143.101889) (xy 146.588443 143.095867)
				(xy 146.635848 143.099993) (xy 146.668097 143.123792) (xy 146.68 143.17679)
			)
		)
	)
	(zone
		(net 139)
		(net_name "/Com Express 7 MGMT/SPI_POWER")
		(layer "F.Cu")
		(name "$teardrop_padvia$")
		(hatch none 0.1)
		(priority 30182)
		(attr
			(teardrop
				(type padvia)
			)
		)
		(connect_pads yes
			(clearance 0)
		)
		(min_thickness 0.0254)
		(filled_areas_thickness no)
		(fill yes
			(thermal_gap 0.5)
			(thermal_bridge_width 0.5)
			(island_removal_mode 1)
			(island_area_min 10)
		)
		(polygon
			(pts
				(xy 263.14 162.381) (xy 263.127069 162.38123) (xy 263.087853 162.380312) (xy 263.047639 162.367831)
				(xy 263.01439 162.331992) (xy 262.996072 162.261) (xy 262.519 162.531) (xy 262.996072 162.801) (xy 263.005013 162.752921)
				(xy 263.020649 162.719595) (xy 263.062804 162.687218) (xy 263.127069 162.68077) (xy 263.14 162.681)
			)
		)
	)
	(zone
		(net 293)
		(net_name "/2xUSB3.0+RJ45/GbE.MDI1+")
		(layer "F.Cu")
		(name "$teardrop_padvia$")
		(hatch none 0.1)
		(priority 31638)
		(attr
			(teardrop
				(type padvia)
			)
		)
		(connect_pads yes
			(clearance 0)
		)
		(min_thickness 0.0254)
		(filled_areas_thickness no)
		(fill yes
			(thermal_gap 0.5)
			(thermal_bridge_width 0.5)
			(island_removal_mode 1)
			(island_area_min 10)
		)
		(polygon
			(pts
				(xy 180.525 167.742084) (xy 180.529756 167.702162) (xy 180.54305 167.673745) (xy 180.587129 167.641329)
				(xy 180.632262 167.62605) (xy 180.678541 167.610756) (xy 180.725003 167.587081) (xy 180.6 167.399)
				(xy 180.379323 167.398242) (xy 180.377203 167.536699) (xy 180.375 167.742084)
			)
		)
	)
	(zone
		(net 1)
		(net_name "GND")
		(layer "F.Cu")
		(name "$teardrop_padvia$")
		(hatch none 0.1)
		(priority 31265)
		(attr
			(teardrop
				(type padvia)
			)
		)
		(connect_pads yes
			(clearance 0)
		)
		(min_thickness 0.0254)
		(filled_areas_thickness no)
		(fill yes
			(thermal_gap 0.5)
			(thermal_bridge_width 0.5)
			(island_removal_mode 1)
			(island_area_min 10)
		)
		(polygon
			(pts
				(xy 176.625 150.325677) (xy 176.629713 150.247764) (xy 176.6427 150.18898) (xy 176.684802 150.097947)
				(xy 176.7275 150.012778) (xy 176.525 149.924) (xy 176.3225 150.012778) (xy 176.365198 150.097949)
				(xy 176.407867 150.190783) (xy 176.420444 150.248922) (xy 176.425 150.325677)
			)
		)
	)
	(zone
		(net 487)
		(net_name "/2xSFP+/I2C_{SFP1}.SCL")
		(layer "F.Cu")
		(name "$teardrop_padvia$")
		(hatch none 0.1)
		(priority 30677)
		(attr
			(teardrop
				(type padvia)
			)
		)
		(connect_pads yes
			(clearance 0)
		)
		(min_thickness 0.0254)
		(filled_areas_thickness no)
		(fill yes
			(thermal_gap 0.5)
			(thermal_bridge_width 0.5)
			(island_removal_mode 1)
			(island_area_min 10)
		)
		(polygon
			(pts
				(xy 194.4625 150.2) (xy 194.451563 150.238823) (xy 194.429805 150.253933) (xy 194.39 150.26) (xy 194.525 151.136)
				(xy 194.66 150.26) (xy 194.624719 150.255483) (xy 194.603203 150.243862) (xy 194.588005 150.211039)
				(xy 194.5875 150.2)
			)
		)
	)
	(zone
		(net 51)
		(net_name "Net-(C13-Pad1)")
		(layer "F.Cu")
		(name "$teardrop_padvia$")
		(hatch none 0.1)
		(priority 30465)
		(attr
			(teardrop
				(type padvia)
			)
		)
		(connect_pads yes
			(clearance 0)
		)
		(min_thickness 0.0254)
		(filled_areas_thickness no)
		(fill yes
			(thermal_gap 0.5)
			(thermal_bridge_width 0.5)
			(island_removal_mode 1)
			(island_area_min 10)
		)
		(polygon
			(pts
				(xy 130.92 98.348) (xy 130.919662 98.33113) (xy 130.920241 98.286174) (xy 130.932059 98.238831)
				(xy 130.966638 98.196427) (xy 131.0355 98.166291) (xy 130.77 97.909) (xy 130.5045 98.166291) (xy 130.549269 98.181848)
				(xy 130.580885 98.202565) (xy 130.613619 98.253701) (xy 130.620338 98.33113) (xy 130.62 98.348)
			)
		)
	)
	(zone
		(net 290)
		(net_name "/2xUSB3.0+RJ45/GbE.MDI2+")
		(layer "F.Cu")
		(name "$teardrop_padvia$")
		(hatch none 0.1)
		(priority 31641)
		(attr
			(teardrop
				(type padvia)
			)
		)
		(connect_pads yes
			(clearance 0)
		)
		(min_thickness 0.0254)
		(filled_areas_thickness no)
		(fill yes
			(thermal_gap 0.5)
			(thermal_bridge_width 0.5)
			(island_removal_mode 1)
			(island_area_min 10)
		)
		(polygon
			(pts
				(xy 179.025 167.742084) (xy 179.029756 167.702162) (xy 179.04305 167.673745) (xy 179.087129 167.641329)
				(xy 179.132262 167.62605) (xy 179.178541 167.610756) (xy 179.225003 167.587081) (xy 179.1 167.399)
				(xy 178.879323 167.398242) (xy 178.877203 167.536699) (xy 178.875 167.742084)
			)
		)
	)
	(zone
		(net 1)
		(net_name "GND")
		(layer "F.Cu")
		(name "$teardrop_padvia$")
		(hatch none 0.1)
		(priority 31934)
		(attr
			(teardrop
				(type padvia)
			)
		)
		(connect_pads yes
			(clearance 0)
		)
		(min_thickness 0.0254)
		(filled_areas_thickness no)
		(fill yes
			(thermal_gap 0.5)
			(thermal_bridge_width 0.5)
			(island_removal_mode 1)
			(island_area_min 10)
		)
		(polygon
			(pts
				(xy 112.18 132.51) (xy 112.190115 132.509847) (xy 112.220832 132.51046) (xy 112.25332 132.518782)
				(xy 112.282475 132.542675) (xy 112.303191 132.59) (xy 112.536 132.41) (xy 112.303191 132.23) (xy 112.289833 132.265901)
				(xy 112.271601 132.289199) (xy 112.226276 132.308899) (xy 112.190115 132.310153) (xy 112.18 132.31)
			)
		)
	)
	(zone
		(net 790)
		(net_name "Net-(U38-1A)")
		(layer "F.Cu")
		(name "$teardrop_padvia$")
		(hatch none 0.1)
		(priority 30146)
		(attr
			(teardrop
				(type padvia)
			)
		)
		(connect_pads yes
			(clearance 0)
		)
		(min_thickness 0.0254)
		(filled_areas_thickness no)
		(fill yes
			(thermal_gap 0.5)
			(thermal_bridge_width 0.5)
			(island_removal_mode 1)
			(island_area_min 10)
		)
		(polygon
			(pts
				(xy 309.0795 79.945) (xy 309.098864 79.876519) (xy 309.162284 79.803581) (xy 309.211068 79.771117)
				(xy 309.269712 79.744883) (xy 309.339421 79.726421) (xy 308.998 79.334) (xy 308.656579 79.726421)
				(xy 308.731988 79.743541) (xy 308.798197 79.768084) (xy 308.854819 79.799109) (xy 308.899802 79.834893)
				(xy 308.930555 79.871682) (xy 308.949067 79.910213) (xy 308.9545 79.945)
			)
		)
	)
	(zone
		(net 1)
		(net_name "GND")
		(layer "F.Cu")
		(name "$teardrop_padvia$")
		(hatch none 0.1)
		(priority 30467)
		(attr
			(teardrop
				(type padvia)
			)
		)
		(connect_pads yes
			(clearance 0)
		)
		(min_thickness 0.0254)
		(filled_areas_thickness no)
		(fill yes
			(thermal_gap 0.5)
			(thermal_bridge_width 0.5)
			(island_removal_mode 1)
			(island_area_min 10)
		)
		(polygon
			(pts
				(xy 234.640708 76.198) (xy 234.64037 76.18113) (xy 234.640949 76.136174) (xy 234.652767 76.088831)
				(xy 234.687346 76.046427) (xy 234.756208 76.016291) (xy 234.490708 75.759) (xy 234.225208 76.016291)
				(xy 234.269977 76.031848) (xy 234.301593 76.052565) (xy 234.334327 76.103701) (xy 234.341046 76.18113)
				(xy 234.340708 76.198)
			)
		)
	)
	(zone
		(net 1)
		(net_name "GND")
		(layer "F.Cu")
		(name "$teardrop_padvia$")
		(hatch none 0.1)
		(priority 30218)
		(attr
			(teardrop
				(type padvia)
			)
		)
		(connect_pads yes
			(clearance 0)
		)
		(min_thickness 0.0254)
		(filled_areas_thickness no)
		(fill yes
			(thermal_gap 0.5)
			(thermal_bridge_width 0.5)
			(island_removal_mode 1)
			(island_area_min 10)
		)
		(polygon
			(pts
				(xy 125.183 147.927) (xy 125.17465 147.896391) (xy 125.164039 147.843406) (xy 125.177044 147.820274)
				(xy 125.213 147.803808) (xy 125.033 147.111) (xy 124.853 147.803808) (xy 124.882959 147.815742)
				(xy 124.898272 147.832064) (xy 124.900108 147.869738) (xy 124.89135 147.896391) (xy 124.883 147.927)
			)
		)
	)
	(zone
		(net 362)
		(net_name "Net-(J12D-~{SUS_STAT}{slash}~{ESPI_RESET})")
		(layer "F.Cu")
		(name "$teardrop_padvia$")
		(hatch none 0.1)
		(priority 30659)
		(attr
			(teardrop
				(type padvia)
			)
		)
		(connect_pads yes
			(clearance 0)
		)
		(min_thickness 0.0254)
		(filled_areas_thickness no)
		(fill yes
			(thermal_gap 0.5)
			(thermal_bridge_width 0.5)
			(island_removal_mode 1)
			(island_area_min 10)
		)
		(polygon
			(pts
				(xy 184.5875 164.07) (xy 184.598438 164.031177) (xy 184.620195 164.016067) (xy 184.66 164.01) (xy 184.525 163.134)
				(xy 184.39 164.01) (xy 184.425281 164.014517) (xy 184.446797 164.026138) (xy 184.461995 164.058961)
				(xy 184.4625 164.07)
			)
		)
	)
	(zone
		(net 538)
		(net_name "Net-(Q5-D)")
		(layer "F.Cu")
		(name "$teardrop_padvia$")
		(hatch none 0.1)
		(priority 30997)
		(attr
			(teardrop
				(type padvia)
			)
		)
		(connect_pads yes
			(clearance 0)
		)
		(min_thickness 0.0254)
		(filled_areas_thickness no)
		(fill yes
			(thermal_gap 0.5)
			(thermal_bridge_width 0.5)
			(island_removal_mode 1)
			(island_area_min 10)
		)
		(polygon
			(pts
				(xy 260.9325 94.775) (xy 260.952469 94.712134) (xy 260.978921 94.680156) (xy 261.016332 94.651642)
				(xy 261.063527 94.629118) (xy 261.121167 94.613907) (xy 261.121798 94.613798) (xy 260.87 94.336)
				(xy 260.618202 94.613798) (xy 260.673635 94.628095) (xy 260.71952 94.649175) (xy 260.757201 94.67654)
				(xy 260.784434 94.707448) (xy 260.801472 94.740735) (xy 260.807489 94.773566) (xy 260.8075 94.775)
			)
		)
	)
	(zone
		(net 488)
		(net_name "/2xSFP+/I2C_{SFP0}.SCL")
		(layer "F.Cu")
		(name "$teardrop_padvia$")
		(hatch none 0.1)
		(priority 31070)
		(attr
			(teardrop
				(type padvia)
			)
		)
		(connect_pads yes
			(clearance 0)
		)
		(min_thickness 0.0254)
		(filled_areas_thickness no)
		(fill yes
			(thermal_gap 0.5)
			(thermal_bridge_width 0.5)
			(island_removal_mode 1)
			(island_area_min 10)
		)
		(polygon
			(pts
				(xy 179.293 146.9375) (xy 179.233588 146.917727) (xy 179.177503 146.854453) (xy 179.155801 146.805828)
				(xy 179.141127 146.746468) (xy 179.139347 146.7345) (xy 178.879 147) (xy 179.139347 147.2655) (xy 179.152197 147.205361)
				(xy 179.172131 147.155477) (xy 179.198056 147.115358) (xy 179.227876 147.086345) (xy 179.259294 147.068854)
				(xy 179.291105 147.062521) (xy 179.293 147.0625)
			)
		)
	)
	(zone
		(net 219)
		(net_name "/Com Express 7 Interfaces/PCIe_{B1x4}.TX1-")
		(layer "F.Cu")
		(name "$teardrop_padvia$")
		(hatch none 0.1)
		(priority 31386)
		(attr
			(teardrop
				(type padvia)
			)
		)
		(connect_pads yes
			(clearance 0)
		)
		(min_thickness 0.0254)
		(filled_areas_thickness no)
		(fill yes
			(thermal_gap 0.5)
			(thermal_bridge_width 0.5)
			(island_removal_mode 1)
			(island_area_min 10)
		)
		(polygon
			(pts
				(xy 207.550908 165.031191) (xy 207.514477 165.060925) (xy 207.480114 165.076699) (xy 207.414208 165.078954)
				(xy 207.370088 165.069023) (xy 207.320212 165.057853) (xy 207.264619 165.054109) (xy 207.274079 165.275493)
				(xy 207.44487 165.416785) (xy 207.512781 165.342328) (xy 207.574156 165.285807) (xy 207.575708 165.284432)
				(xy 207.693744 165.174027)
			)
		)
	)
	(zone
		(net 16)
		(net_name "/Com Express 7 Interfaces/PCIe_{B1x2}.RX0-")
		(layer "F.Cu")
		(name "$teardrop_padvia$")
		(hatch none 0.1)
		(priority 31453)
		(attr
			(teardrop
				(type padvia)
			)
		)
		(connect_pads yes
			(clearance 0)
		)
		(min_thickness 0.0254)
		(filled_areas_thickness no)
		(fill yes
			(thermal_gap 0.5)
			(thermal_bridge_width 0.5)
			(island_removal_mode 1)
			(island_area_min 10)
		)
		(polygon
			(pts
				(xy 206.0935 131.036416) (xy 206.100472 131.206647) (xy 206.102323 131.384068) (xy 206.323 131.401)
				(xy 206.484165 131.249081) (xy 206.4159 131.197228) (xy 206.39758 131.186815) (xy 206.358573 131.163455)
				(xy 206.326045 131.135008) (xy 206.303764 131.094865) (xy 206.2955 131.036416)
			)
		)
	)
	(zone
		(net 702)
		(net_name "/USB-C console/FTDI_CBUS3")
		(layer "F.Cu")
		(name "$teardrop_padvia$")
		(hatch none 0.1)
		(priority 31632)
		(attr
			(teardrop
				(type padvia)
			)
		)
		(connect_pads yes
			(clearance 0)
		)
		(min_thickness 0.0254)
		(filled_areas_thickness no)
		(fill yes
			(thermal_gap 0.5)
			(thermal_bridge_width 0.5)
			(island_removal_mode 1)
			(island_area_min 10)
		)
		(polygon
			(pts
				(xy 117.539999 76.0875) (xy 117.512927 76.081978) (xy 117.487388 76.063322) (xy 117.471219 76.036703)
				(xy 117.4616 75.997962) (xy 117.459999 75.97) (xy 117.058999 76.15) (xy 117.459999 76.33) (xy 117.464612 76.2845)
				(xy 117.476899 76.251532) (xy 117.515054 76.217156) (xy 117.539999 76.2125)
			)
		)
	)
	(zone
		(net 284)
		(net_name "/Misc/PWM_{C5V}")
		(layer "F.Cu")
		(name "$teardrop_padvia$")
		(hatch none 0.1)
		(priority 30356)
		(attr
			(teardrop
				(type padvia)
			)
		)
		(connect_pads yes
			(clearance 0)
		)
		(min_thickness 0.0254)
		(filled_areas_thickness no)
		(fill yes
			(thermal_gap 0.5)
			(thermal_bridge_width 0.5)
			(island_removal_mode 1)
			(island_area_min 10)
		)
		(polygon
			(pts
				(xy 232.007707 77.1855) (xy 232.04157 77.191281) (xy 232.076191 77.211745) (xy 232.098013 77.23881)
				(xy 232.113707 77.27815) (xy 232.116996 77.293711) (xy 232.823707 77.123) (xy 232.116996 76.952289)
				(xy 232.105407 76.99251) (xy 232.087823 77.021984) (xy 232.040241 77.055173) (xy 232.007707 77.0605)
			)
		)
	)
	(zone
		(net 341)
		(net_name "/Com Express 7 MGMT/SPI.MOSI")
		(layer "F.Cu")
		(name "$teardrop_padvia$")
		(hatch none 0.1)
		(priority 30699)
		(attr
			(teardrop
				(type padvia)
			)
		)
		(connect_pads yes
			(clearance 0)
		)
		(min_thickness 0.0254)
		(filled_areas_thickness no)
		(fill yes
			(thermal_gap 0.5)
			(thermal_bridge_width 0.5)
			(island_removal_mode 1)
			(island_area_min 10)
		)
		(polygon
			(pts
				(xy 222.9625 167.75) (xy 222.951563 167.788823) (xy 222.929805 167.803933) (xy 222.89 167.81) (xy 223.025 168.686)
				(xy 223.16 167.81) (xy 223.124719 167.805483) (xy 223.103203 167.793862) (xy 223.088005 167.761039)
				(xy 223.0875 167.75)
			)
		)
	)
	(zone
		(net 340)
		(net_name "/Com Express 7 MGMT/SPI.CLK")
		(layer "F.Cu")
		(name "$teardrop_padvia$")
		(hatch none 0.1)
		(priority 31672)
		(attr
			(teardrop
				(type padvia)
			)
		)
		(connect_pads yes
			(clearance 0)
		)
		(min_thickness 0.0254)
		(filled_areas_thickness no)
		(fill yes
			(thermal_gap 0.5)
			(thermal_bridge_width 0.5)
			(island_removal_mode 1)
			(island_area_min 10)
		)
		(polygon
			(pts
				(xy 248.200677 161.232) (xy 248.128667 161.227152) (xy 248.075746 161.213219) (xy 247.98691 161.157731)
				(xy 247.925003 161.112919) (xy 247.799 161.3) (xy 247.925003 161.487081) (xy 247.992498 161.436987)
				(xy 248.075495 161.382504) (xy 248.128326 161.367346) (xy 248.200677 161.362)
			)
		)
	)
	(zone
		(net 490)
		(net_name "/2xSFP+/MDIO1.MDIO")
		(layer "F.Cu")
		(name "$teardrop_padvia$")
		(hatch none 0.1)
		(priority 30687)
		(attr
			(teardrop
				(type padvia)
			)
		)
		(connect_pads yes
			(clearance 0)
		)
		(min_thickness 0.0254)
		(filled_areas_thickness no)
		(fill yes
			(thermal_gap 0.5)
			(thermal_bridge_width 0.5)
			(island_removal_mode 1)
			(island_area_min 10)
		)
		(polygon
			(pts
				(xy 197.9625 150.2) (xy 197.951563 150.238823) (xy 197.929805 150.253933) (xy 197.89 150.26) (xy 198.025 151.136)
				(xy 198.16 150.26) (xy 198.124719 150.255483) (xy 198.103203 150.243862) (xy 198.088005 150.211039)
				(xy 198.0875 150.2)
			)
		)
	)
	(zone
		(net 1)
		(net_name "GND")
		(layer "F.Cu")
		(name "$teardrop_padvia$")
		(hatch none 0.1)
		(priority 31250)
		(attr
			(teardrop
				(type padvia)
			)
		)
		(connect_pads yes
			(clearance 0)
		)
		(min_thickness 0.0254)
		(filled_areas_thickness no)
		(fill yes
			(thermal_gap 0.5)
			(thermal_bridge_width 0.5)
			(island_removal_mode 1)
			(island_area_min 10)
		)
		(polygon
			(pts
				(xy 112.639323 138.01) (xy 112.717235 138.014713) (xy 112.77602 138.0277) (xy 112.867051 138.069802)
				(xy 112.952222 138.1125) (xy 113.041 137.91) (xy 112.952222 137.7075) (xy 112.86705 137.750199)
				(xy 112.774217 137.792867) (xy 112.716078 137.805444) (xy 112.639323 137.81)
			)
		)
	)
	(zone
		(net 385)
		(net_name "/Com Express 7 Interfaces/SDIO.CMD")
		(layer "F.Cu")
		(name "$teardrop_padvia$")
		(hatch none 0.1)
		(priority 31465)
		(attr
			(teardrop
				(type padvia)
			)
		)
		(connect_pads yes
			(clearance 0)
		)
		(min_thickness 0.0254)
		(filled_areas_thickness no)
		(fill yes
			(thermal_gap 0.5)
			(thermal_bridge_width 0.5)
			(island_removal_mode 1)
			(island_area_min 10)
		)
		(polygon
			(pts
				(xy 202.616 162.300677) (xy 202.620806 162.230762) (xy 202.634445 162.178579) (xy 202.681099 162.100893)
				(xy 202.691772 162.086995) (xy 202.737081 162.025003) (xy 202.55 161.899) (xy 202.342355 161.975358)
				(xy 202.381768 162.068438) (xy 202.419069 162.163687) (xy 202.434 162.300677)
			)
		)
	)
	(zone
		(net 606)
		(net_name "Net-(U37-~{OE4})")
		(layer "F.Cu")
		(name "$teardrop_padvia$")
		(hatch none 0.1)
		(priority 32106)
		(attr
			(teardrop
				(type padvia)
			)
		)
		(connect_pads yes
			(clearance 0)
		)
		(min_thickness 0.0254)
		(filled_areas_thickness no)
		(fill yes
			(thermal_gap 0.5)
			(thermal_bridge_width 0.5)
			(island_removal_mode 1)
			(island_area_min 10)
		)
		(polygon
			(pts
				(xy 218.569 128.8625) (xy 218.557203 128.863952) (xy 218.528919 128.864129) (xy 218.516348 128.855153)
				(xy 218.507404 128.835) (xy 218.153 128.925) (xy 218.507404 129.015) (xy 218.517008 128.994044)
				(xy 218.530553 128.98537) (xy 218.557203 128.986048) (xy 218.569 128.9875)
			)
		)
	)
	(zone
		(net 1)
		(net_name "GND")
		(layer "F.Cu")
		(name "$teardrop_padvia$")
		(hatch none 0.1)
		(priority 30726)
		(attr
			(teardrop
				(type padvia)
			)
		)
		(connect_pads yes
			(clearance 0)
		)
		(min_thickness 0.0254)
		(filled_areas_thickness no)
		(fill yes
			(thermal_gap 0.5)
			(thermal_bridge_width 0.5)
			(island_removal_mode 1)
			(island_area_min 10)
		)
		(polygon
			(pts
				(xy 305.2375 148.45) (xy 305.242821 148.418265) (xy 305.260069 148.385565) (xy 305.286538 148.359374)
				(xy 305.324964 148.338445) (xy 305.36705 148.32705) (xy 305.175 147.809) (xy 304.98295 148.32705)
				(xy 305.027474 148.339409) (xy 305.0616 148.358008) (xy 305.103536 148.408803) (xy 305.1125 148.45)
			)
		)
	)
	(zone
		(net 693)
		(net_name "/2xUSB3.0+RJ45/DC_FL+")
		(layer "F.Cu")
		(name "$teardrop_padvia$")
		(hatch none 0.1)
		(priority 31980)
		(attr
			(teardrop
				(type padvia)
			)
		)
		(connect_pads yes
			(clearance 0)
		)
		(min_thickness 0.0254)
		(filled_areas_thickness no)
		(fill yes
			(thermal_gap 0.5)
			(thermal_bridge_width 0.5)
			(island_removal_mode 1)
			(island_area_min 10)
		)
		(polygon
			(pts
				(xy 130.285858 109.651923) (xy 130.299094 109.661437) (xy 130.324793 109.683581) (xy 130.32868 109.699941)
				(xy 130.32 109.721498) (xy 130.800707 109.770707) (xy 130.784389 109.635) (xy 130.627296 109.630002)
				(xy 130.508147 109.610026) (xy 130.452418 109.588863) (xy 130.40698 109.559564) (xy 130.391923 109.545858)
			)
		)
	)
	(zone
		(net 5)
		(net_name "/M.2 key E/~{LED_1}")
		(layer "F.Cu")
		(name "$teardrop_padvia$")
		(hatch none 0.1)
		(priority 30856)
		(attr
			(teardrop
				(type padvia)
			)
		)
		(connect_pads yes
			(clearance 0)
		)
		(min_thickness 0.0254)
		(filled_areas_thickness no)
		(fill yes
			(thermal_gap 0.5)
			(thermal_bridge_width 0.5)
			(island_removal_mode 1)
			(island_area_min 10)
		)
		(polygon
			(pts
				(xy 145.2405 72.372) (xy 145.279323 72.382938) (xy 145.294433 72.404695) (xy 145.3005 72.4445) (xy 146.0765 72.3095)
				(xy 145.3005 72.1745) (xy 145.295983 72.209781) (xy 145.284362 72.231297) (xy 145.251539 72.246495)
				(xy 145.2405 72.247)
			)
		)
	)
	(zone
		(net 528)
		(net_name "/Backplane/~{PERST}")
		(layer "F.Cu")
		(name "$teardrop_padvia$")
		(hatch none 0.1)
		(priority 31984)
		(attr
			(teardrop
				(type padvia)
			)
		)
		(connect_pads yes
			(clearance 0)
		)
		(min_thickness 0.0254)
		(filled_areas_thickness no)
		(fill yes
			(thermal_gap 0.5)
			(thermal_bridge_width 0.5)
			(island_removal_mode 1)
			(island_area_min 10)
		)
		(polygon
			(pts
				(xy 308.8185 155.617) (xy 308.829438 155.578177) (xy 308.851195 155.563067) (xy 308.891 155.557)
				(xy 308.756 155.181) (xy 308.621 155.557) (xy 308.656281 155.561517) (xy 308.677797 155.573138)
				(xy 308.692995 155.605961) (xy 308.6935 155.617)
			)
		)
	)
	(zone
		(net 578)
		(net_name "/Power/PG_{1V0}")
		(layer "F.Cu")
		(name "$teardrop_padvia$")
		(hatch none 0.1)
		(priority 30987)
		(attr
			(teardrop
				(type padvia)
			)
		)
		(connect_pads yes
			(clearance 0)
		)
		(min_thickness 0.0254)
		(filled_areas_thickness no)
		(fill yes
			(thermal_gap 0.5)
			(thermal_bridge_width 0.5)
			(island_removal_mode 1)
			(island_area_min 10)
		)
		(polygon
			(pts
				(xy 306.5575 130.602) (xy 306.537531 130.664866) (xy 306.511079 130.696844) (xy 306.473668 130.725358)
				(xy 306.426473 130.747882) (xy 306.368833 130.763093) (xy 306.368202 130.763202) (xy 306.62 131.041)
				(xy 306.871798 130.763202) (xy 306.816365 130.748905) (xy 306.77048 130.727825) (xy 306.732799 130.70046)
				(xy 306.705566 130.669552) (xy 306.688528 130.636265) (xy 306.682511 130.603434) (xy 306.6825 130.602)
			)
		)
	)
	(zone
		(net 2)
		(net_name "+3V3")
		(layer "F.Cu")
		(name "$teardrop_padvia$")
		(hatch none 0.1)
		(priority 30804)
		(attr
			(teardrop
				(type padvia)
			)
		)
		(connect_pads yes
			(clearance 0)
		)
		(min_thickness 0.0254)
		(filled_areas_thickness no)
		(fill yes
			(thermal_gap 0.5)
			(thermal_bridge_width 0.5)
			(island_removal_mode 1)
			(island_area_min 10)
		)
		(polygon
			(pts
				(xy 146.679824 71.458499) (xy 146.837391 71.465429) (xy 146.950917 71.493948) (xy 146.992722 71.510999)
				(xy 147.081499 71.308499) (xy 146.992721 71.105999) (xy 146.896676 71.140382) (xy 146.794795 71.1556)
				(xy 146.679823 71.1585)
			)
		)
	)
	(zone
		(net 689)
		(net_name "/2xUSB3.0+RJ45/DA_FL+")
		(layer "F.Cu")
		(name "$teardrop_padvia$")
		(hatch none 0.1)
		(priority 31149)
		(attr
			(teardrop
				(type padvia)
			)
		)
		(connect_pads yes
			(clearance 0)
		)
		(min_thickness 0.0254)
		(filled_areas_thickness no)
		(fill yes
			(thermal_gap 0.5)
			(thermal_bridge_width 0.5)
			(island_removal_mode 1)
			(island_area_min 10)
		)
		(polygon
			(pts
				(xy 128.526861 113.447073) (xy 128.442002 113.502661) (xy 128.383721 113.52191) (xy 128.315724 113.533528)
				(xy 128.173057 113.5325) (xy 128.209293 113.770707) (xy 128.5475 113.788424) (xy 128.5504 113.695052)
				(xy 128.58624 113.610804) (xy 128.632927 113.553139)
			)
		)
	)
	(zone
		(net 1)
		(net_name "GND")
		(layer "F.Cu")
		(name "$teardrop_padvia$")
		(hatch none 0.1)
		(priority 30189)
		(attr
			(teardrop
				(type padvia)
			)
		)
		(connect_pads yes
			(clearance 0)
		)
		(min_thickness 0.0254)
		(filled_areas_thickness no)
		(fill yes
			(thermal_gap 0.5)
			(thermal_bridge_width 0.5)
			(island_removal_mode 1)
			(island_area_min 10)
		)
		(polygon
			(pts
				(xy 200.049 82.47) (xy 200.054675 82.431486) (xy 200.074403 82.392381) (xy 200.101281 82.365531)
				(xy 200.140389 82.343718) (xy 200.219 82.326072) (xy 199.949 81.849) (xy 199.679 82.326072) (xy 199.733606 82.335617)
				(xy 199.775842 82.352225) (xy 199.828807 82.399911) (xy 199.848684 82.460814) (xy 199.849 82.47)
			)
		)
	)
	(zone
		(net 371)
		(net_name "/Com Express 7 MGMT/I2C.SCL")
		(layer "F.Cu")
		(name "$teardrop_padvia$")
		(hatch none 0.1)
		(priority 31999)
		(attr
			(teardrop
				(type padvia)
			)
		)
		(connect_pads yes
			(clearance 0)
		)
		(min_thickness 0.0254)
		(filled_areas_thickness no)
		(fill yes
			(thermal_gap 0.5)
			(thermal_bridge_width 0.5)
			(island_removal_mode 1)
			(island_area_min 10)
		)
		(polygon
			(pts
				(xy 238.6865 153.552) (xy 238.675563 153.590823) (xy 238.653805 153.605933) (xy 238.614 153.612)
				(xy 238.749 153.963) (xy 238.884 153.612) (xy 238.848719 153.607483) (xy 238.827203 153.595862)
				(xy 238.812005 153.563039) (xy 238.8115 153.552)
			)
		)
	)
	(zone
		(net 323)
		(net_name "/Com Express 7 Interfaces/SDIO.DAT2")
		(layer "F.Cu")
		(name "$teardrop_padvia$")
		(hatch none 0.1)
		(priority 30045)
		(attr
			(teardrop
				(type padvia)
			)
		)
		(connect_pads yes
			(clearance 0)
		)
		(min_thickness 0.0254)
		(filled_areas_thickness no)
		(fill yes
			(thermal_gap 0.5)
			(thermal_bridge_width 0.5)
			(island_removal_mode 1)
			(island_area_min 10)
		)
		(polygon
			(pts
				(xy 110.595 138.919) (xy 110.563366 138.913903) (xy 110.532489 138.898222) (xy 110.505162 138.872417)
				(xy 110.482138 138.835622) (xy 110.465474 138.788468) (xy 110.456279 138.729788) (xy 110.455 138.695)
				(xy 109.504 139.01) (xy 110.455 139.325) (xy 110.459723 139.260141) (xy 110.472784 139.207088) (xy 110.492459 139.165444)
				(xy 110.517125 139.134553) (xy 110.545573 139.113687) (xy 110.575742 139.102878) (xy 110.595 139.101)
			)
		)
	)
	(zone
		(net 73)
		(net_name "+3V3_AON")
		(layer "F.Cu")
		(name "$teardrop_padvia$")
		(hatch none 0.1)
		(priority 32000)
		(attr
			(teardrop
				(type padvia)
			)
		)
		(connect_pads yes
			(clearance 0)
		)
		(min_thickness 0.0254)
		(filled_areas_thickness no)
		(fill yes
			(thermal_gap 0.5)
			(thermal_bridge_width 0.5)
			(island_removal_mode 1)
			(island_area_min 10)
		)
		(polygon
			(pts
				(xy 237.6885 153.552) (xy 237.677563 153.590823) (xy 237.655805 153.605933) (xy 237.616 153.612)
				(xy 237.751 153.963) (xy 237.886 153.612) (xy 237.850719 153.607483) (xy 237.829203 153.595862)
				(xy 237.814005 153.563039) (xy 237.8135 153.552)
			)
		)
	)
	(zone
		(net 1)
		(net_name "GND")
		(layer "F.Cu")
		(name "$teardrop_padvia$")
		(hatch none 0.1)
		(priority 30531)
		(attr
			(teardrop
				(type padvia)
			)
		)
		(connect_pads yes
			(clearance 0)
		)
		(min_thickness 0.0254)
		(filled_areas_thickness no)
		(fill yes
			(thermal_gap 0.5)
			(thermal_bridge_width 0.5)
			(island_removal_mode 1)
			(island_area_min 10)
		)
		(polygon
			(pts
				(xy 222.125 157.62) (xy 222.121667 157.605514) (xy 222.11881 157.57539) (xy 222.130964 157.564349)
				(xy 222.16 157.56) (xy 222.025 156.684) (xy 221.89 157.56) (xy 221.919334 157.564475) (xy 221.931358 157.575801)
				(xy 221.928333 157.605514) (xy 221.925 157.62)
			)
		)
	)
	(zone
		(net 424)
		(net_name "/2xSFP+/I2C_{SFP1}.SDA")
		(layer "F.Cu")
		(name "$teardrop_padvia$")
		(hatch none 0.1)
		(priority 31683)
		(attr
			(teardrop
				(type padvia)
			)
		)
		(connect_pads yes
			(clearance 0)
		)
		(min_thickness 0.0254)
		(filled_areas_thickness no)
		(fill yes
			(thermal_gap 0.5)
			(thermal_bridge_width 0.5)
			(island_removal_mode 1)
			(island_area_min 10)
		)
		(polygon
			(pts
				(xy 192.96235 154.148963) (xy 192.940898 154.120754) (xy 192.934462 154.09531) (xy 192.952161 154.053963)
				(xy 193.006537 154.00438) (xy 193.049858 153.967542) (xy 193.087081 153.925003) (xy 192.899293 153.799293)
				(xy 192.712919 153.925003) (xy 192.761344 154.024596) (xy 192.772112 154.060341) (xy 192.802058 154.142418)
				(xy 192.830051 154.187151) (xy 192.873963 154.23735)
			)
		)
	)
	(zone
		(net 2)
		(net_name "+3V3")
		(layer "F.Cu")
		(name "$teardrop_padvia$")
		(hatch none 0.1)
		(priority 31890)
		(attr
			(teardrop
				(type padvia)
			)
		)
		(connect_pads yes
			(clearance 0)
		)
		(min_thickness 0.0254)
		(filled_areas_thickness no)
		(fill yes
			(thermal_gap 0.5)
			(thermal_bridge_width 0.5)
			(island_removal_mode 1)
			(island_area_min 10)
		)
		(polygon
			(pts
				(xy 174.027515 156.789127) (xy 173.981819 156.736618) (xy 173.955231 156.690623) (xy 173.934847 156.604175)
				(xy 173.933011 156.58884) (xy 173.920677 156.506105) (xy 173.699293 156.549293) (xy 173.656105 156.770677)
				(xy 173.73884 156.783011) (xy 173.836119 156.803349) (xy 173.884159 156.830057) (xy 173.939127 156.877515)
			)
		)
	)
	(zone
		(net 602)
		(net_name "Net-(U37-~{OE0})")
		(layer "F.Cu")
		(name "$teardrop_padvia$")
		(hatch none 0.1)
		(priority 32103)
		(attr
			(teardrop
				(type padvia)
			)
		)
		(connect_pads yes
			(clearance 0)
		)
		(min_thickness 0.0254)
		(filled_areas_thickness no)
		(fill yes
			(thermal_gap 0.5)
			(thermal_bridge_width 0.5)
			(island_removal_mode 1)
			(island_area_min 10)
		)
		(polygon
			(pts
				(xy 212.788 127.7875) (xy 212.799797 127.786048) (xy 212.828081 127.785871) (xy 212.840652 127.794847)
				(xy 212.849596 127.815) (xy 213.204 127.725) (xy 212.849596 127.635) (xy 212.839992 127.655956)
				(xy 212.826447 127.66463) (xy 212.799797 127.663952) (xy 212.788 127.6625)
			)
		)
	)
	(zone
		(net 207)
		(net_name "/Backplane/UART.TX")
		(layer "F.Cu")
		(name "$teardrop_padvia$")
		(hatch none 0.1)
		(priority 32125)
		(attr
			(teardrop
				(type padvia)
			)
		)
		(connect_pads yes
			(clearance 0)
		)
		(min_thickness 0.0254)
		(filled_areas_thickness no)
		(fill yes
			(thermal_gap 0.5)
			(thermal_bridge_width 0.5)
			(island_removal_mode 1)
			(island_area_min 10)
		)
		(polygon
			(pts
				(xy 315.46 167.9455) (xy 315.453678 167.945596) (xy 315.414175 167.940011) (xy 315.395953 167.925078)
				(xy 315.383005 167.8955) (xy 315.134 168.008) (xy 315.383005 168.1205) (xy 315.394121 168.093506)
				(xy 315.409648 168.078405) (xy 315.453678 168.070404) (xy 315.46 168.0705)
			)
		)
	)
	(zone
		(net 78)
		(net_name "+1V8")
		(layer "F.Cu")
		(name "$teardrop_padvia$")
		(hatch none 0.1)
		(priority 30348)
		(attr
			(teardrop
				(type padvia)
			)
		)
		(connect_pads yes
			(clearance 0)
		)
		(min_thickness 0.0254)
		(filled_areas_thickness no)
		(fill yes
			(thermal_gap 0.5)
			(thermal_bridge_width 0.5)
			(island_removal_mode 1)
			(island_area_min 10)
		)
		(polygon
			(pts
				(xy 124.3195 150.596) (xy 124.313719 150.629863) (xy 124.293254 150.664486) (xy 124.266188 150.686307)
				(xy 124.226849 150.702) (xy 124.211289 150.705289) (xy 124.382 151.412) (xy 124.552711 150.705289)
				(xy 124.51249 150.6937) (xy 124.483017 150.676116) (xy 124.449827 150.628533) (xy 124.4445 150.596)
			)
		)
	)
	(zone
		(net 2)
		(net_name "+3V3")
		(layer "F.Cu")
		(name "$teardrop_padvia$")
		(hatch none 0.1)
		(priority 30736)
		(attr
			(teardrop
				(type padvia)
			)
		)
		(connect_pads yes
			(clearance 0)
		)
		(min_thickness 0.0254)
		(filled_areas_thickness no)
		(fill yes
			(thermal_gap 0.5)
			(thermal_bridge_width 0.5)
			(island_removal_mode 1)
			(island_area_min 10)
		)
		(polygon
			(pts
				(xy 303.4145 104.17) (xy 303.409203 104.201401) (xy 303.392126 104.233656) (xy 303.365646 104.259863)
				(xy 303.327224 104.280921) (xy 303.28295 104.29295) (xy 303.475 104.811) (xy 303.66705 104.29295)
				(xy 303.623198 104.280629) (xy 303.589633 104.262077) (xy 303.548347 104.211289) (xy 303.5395 104.17)
			)
		)
	)
	(zone
		(net 1)
		(net_name "GND")
		(layer "F.Cu")
		(hatch edge 0.5)
		(priority 16)
		(connect_pads yes
			(clearance 0.15)
		)
		(min_thickness 0.25)
		(filled_areas_thickness no)
		(fill yes
			(thermal_gap 0.2)
			(thermal_bridge_width 0.5)
		)
		(polygon
			(pts
				(xy 312.1395 133.21) (xy 312.1395 133.71) (xy 312.3395 133.91) (xy 313.3895 133.91) (xy 313.7395 134.26)
				(xy 318.75 134.26) (xy 318.75 142.01) (xy 314.6145 142.01) (xy 314.6145 136.685) (xy 314.3895 136.46)
				(xy 313.8395 136.46) (xy 313.5895 136.21) (xy 313.5895 135.01) (xy 313.0895 134.51) (xy 312.3395 134.51)
				(xy 312.1395 134.71) (xy 312.1395 135.31) (xy 312.0395 135.41) (xy 311.6895 135.41) (xy 311.5395 135.56)
				(xy 311.5395 136.91) (xy 311.2395 137.21) (xy 309.9395 137.21) (xy 309.6395 136.91) (xy 309.6395 134.71)
				(xy 310.4395 133.91) (xy 310.4395 133.11) (xy 310.5895 132.96) (xy 311.8895 132.96)
			)
		)
	)
	(zone
		(net 228)
		(net_name "/M.2 key M #1/~{PERST_D}")
		(layer "F.Cu")
		(name "$teardrop_padvia$")
		(hatch none 0.1)
		(priority 31769)
		(attr
			(teardrop
				(type padvia)
			)
		)
		(connect_pads yes
			(clearance 0)
		)
		(min_thickness 0.0254)
		(filled_areas_thickness no)
		(fill yes
			(thermal_gap 0.5)
			(thermal_bridge_width 0.5)
			(island_removal_mode 1)
			(island_area_min 10)
		)
		(polygon
			(pts
				(xy 177.329053 104.926577) (xy 177.398494 104.931395) (xy 177.449818 104.945117) (xy 177.525359 104.991832)
				(xy 177.537499 105.001376) (xy 177.604727 105.051158) (xy 177.73073 104.864077) (xy 177.604727 104.676996)
				(xy 177.537498 104.726779) (xy 177.454332 104.781183) (xy 177.401478 104.796267) (xy 177.329053 104.801577)
			)
		)
	)
	(zone
		(net 225)
		(net_name "/Com Express 7 Interfaces/PCIe_{B1x4}.TX0-")
		(layer "F.Cu")
		(name "$teardrop_padvia$")
		(hatch none 0.1)
		(priority 30238)
		(attr
			(teardrop
				(type padvia)
			)
		)
		(connect_pads yes
			(clearance 0)
		)
		(min_thickness 0.0254)
		(filled_areas_thickness no)
		(fill yes
			(thermal_gap 0.5)
			(thermal_bridge_width 0.5)
			(island_removal_mode 1)
			(island_area_min 10)
		)
		(polygon
			(pts
				(xy 210.0705 169.62) (xy 210.06742 169.605773) (xy 210.065252 169.575473) (xy 210.078123 169.564372)
				(xy 210.108295 169.56) (xy 210.025 168.684) (xy 209.875 168.932978) (xy 209.894356 169.174182) (xy 209.879599 169.446888)
				(xy 209.8685 169.62)
			)
		)
	)
	(zone
		(net 1)
		(net_name "GND")
		(layer "F.Cu")
		(name "$teardrop_padvia$")
		(hatch none 0.1)
		(priority 31275)
		(attr
			(teardrop
				(type padvia)
			)
		)
		(connect_pads yes
			(clearance 0)
		)
		(min_thickness 0.0254)
		(filled_areas_thickness no)
		(fill yes
			(thermal_gap 0.5)
			(thermal_bridge_width 0.5)
			(island_removal_mode 1)
			(island_area_min 10)
		)
		(polygon
			(pts
				(xy 213.45 151.899323) (xy 213.445287 151.977234) (xy 213.4323 152.036018) (xy 213.390199 152.127048)
				(xy 213.3475 152.212221) (xy 213.55 152.301) (xy 213.7525 152.212221) (xy 213.709801 152.12705)
				(xy 213.667133 152.034217) (xy 213.654556 151.976078) (xy 213.65 151.899323)
			)
		)
	)
	(zone
		(net 1)
		(net_name "GND")
		(layer "F.Cu")
		(name "$teardrop_padvia$")
		(hatch none 0.1)
		(priority 31522)
		(attr
			(teardrop
				(type padvia)
			)
		)
		(connect_pads yes
			(clearance 0)
		)
		(min_thickness 0.0254)
		(filled_areas_thickness no)
		(fill yes
			(thermal_gap 0.5)
			(thermal_bridge_width 0.5)
			(island_removal_mode 1)
			(island_area_min 10)
		)
		(polygon
			(pts
				(xy 240.570851 131.572273) (xy 240.575953 131.576895) (xy 240.586689 131.587741) (xy 240.588872 131.600262)
				(xy 240.571408 131.613927) (xy 240.523202 131.628202) (xy 240.800707 131.880707) (xy 240.964525 131.585)
				(xy 240.880188 131.567536) (xy 240.798654 131.515893) (xy 240.733046 131.452313) (xy 240.712273 131.430851)
			)
		)
	)
	(zone
		(net 531)
		(net_name "/Com Express 7 Interfaces/SD_CD")
		(layer "F.Cu")
		(name "$teardrop_padvia$")
		(hatch none 0.1)
		(priority 30642)
		(attr
			(teardrop
				(type padvia)
			)
		)
		(connect_pads yes
			(clearance 0)
		)
		(min_thickness 0.0254)
		(filled_areas_thickness no)
		(fill yes
			(thermal_gap 0.5)
			(thermal_bridge_width 0.5)
			(island_removal_mode 1)
			(island_area_min 10)
		)
		(polygon
			(pts
				(xy 207.0875 164.07) (xy 207.098438 164.031177) (xy 207.120195 164.016067) (xy 207.16 164.01) (xy 207.025 163.134)
				(xy 206.89 164.01) (xy 206.925281 164.014517) (xy 206.946797 164.026138) (xy 206.961995 164.058961)
				(xy 206.9625 164.07)
			)
		)
	)
	(zone
		(net 614)
		(net_name "/PCIe misc/DIF1-")
		(layer "F.Cu")
		(name "$teardrop_padvia$")
		(hatch none 0.1)
		(priority 30416)
		(attr
			(teardrop
				(type padvia)
			)
		)
		(connect_pads yes
			(clearance 0)
		)
		(min_thickness 0.0254)
		(filled_areas_thickness no)
		(fill yes
			(thermal_gap 0.5)
			(thermal_bridge_width 0.5)
			(island_removal_mode 1)
			(island_area_min 10)
		)
		(polygon
			(pts
				(xy 212.121716 130.0185) (xy 212.102706 130.026878) (xy 211.931234 130.091704) (xy 211.830478 130.110101)
				(xy 211.726795 130.105) (xy 211.759 130.425) (xy 212.055 130.522817) (xy 212.048549 130.390588)
				(xy 212.0601 130.297117) (xy 212.076242 130.259794) (xy 212.100253 130.233078) (xy 212.121716 130.2205)
			)
		)
	)
	(zone
		(net 75)
		(net_name "Net-(U50-IN+)")
		(layer "F.Cu")
		(name "$teardrop_padvia$")
		(hatch none 0.1)
		(priority 31076)
		(attr
			(teardrop
				(type padvia)
			)
		)
		(connect_pads yes
			(clearance 0)
		)
		(min_thickness 0.0254)
		(filled_areas_thickness no)
		(fill yes
			(thermal_gap 0.5)
			(thermal_bridge_width 0.5)
			(island_removal_mode 1)
			(island_area_min 10)
		)
		(polygon
			(pts
				(xy 313.827999 98.3295) (xy 313.847772 98.270088) (xy 313.911046 98.214003) (xy 313.959671 98.192301)
				(xy 314.019031 98.177627) (xy 314.030999 98.175847) (xy 313.765499 97.9155) (xy 313.499999 98.175847)
				(xy 313.560138 98.188697) (xy 313.610022 98.208631) (xy 313.650141 98.234556) (xy 313.679154 98.264376)
				(xy 313.696645 98.295794) (xy 313.702978 98.327605) (xy 313.702999 98.3295)
			)
		)
	)
	(zone
		(net 2)
		(net_name "+3V3")
		(layer "F.Cu")
		(name "$teardrop_padvia$")
		(hatch none 0.1)
		(priority 31258)
		(attr
			(teardrop
				(type padvia)
			)
		)
		(connect_pads yes
			(clearance 0)
		)
		(min_thickness 0.0254)
		(filled_areas_thickness no)
		(fill yes
			(thermal_gap 0.5)
			(thermal_bridge_width 0.5)
			(island_removal_mode 1)
			(island_area_min 10)
		)
		(polygon
			(pts
				(xy 111.77 134.960677) (xy 111.774713 134.882764) (xy 111.7877 134.82398) (xy 111.829802 134.732947)
				(xy 111.8725 134.647778) (xy 111.67 134.559) (xy 111.4675 134.647778) (xy 111.510198 134.732949)
				(xy 111.552867 134.825783) (xy 111.565444 134.883922) (xy 111.57 134.960677)
			)
		)
	)
	(zone
		(net 1)
		(net_name "GND")
		(layer "F.Cu")
		(name "$teardrop_padvia$")
		(hatch none 0.1)
		(priority 30889)
		(attr
			(teardrop
				(type padvia)
			)
		)
		(connect_pads yes
			(clearance 0)
		)
		(min_thickness 0.0254)
		(filled_areas_thickness no)
		(fill yes
			(thermal_gap 0.5)
			(thermal_bridge_width 0.5)
			(island_removal_mode 1)
			(island_area_min 10)
		)
		(polygon
			(pts
				(xy 259.062211 77.622) (xy 259.023736 77.617302) (xy 258.994706 77.604417) (xy 258.955073 77.559443)
				(xy 258.937619 77.525066) (xy 258.903447 77.465655) (xy 258.729708 77.605) (xy 258.717904 77.825677)
				(xy 258.806227 77.846907) (xy 258.851197 77.867823) (xy 258.938852 77.904647) (xy 258.994269 77.917186)
				(xy 259.062211 77.922)
			)
		)
	)
	(zone
		(net 895)
		(net_name "Net-(J2B-RS0)")
		(layer "F.Cu")
		(name "$teardrop_padvia$")
		(hatch none 0.1)
		(priority 30060)
		(attr
			(teardrop
				(type padvia)
			)
		)
		(connect_pads yes
			(clearance 0)
		)
		(min_thickness 0.0254)
		(filled_areas_thickness no)
		(fill yes
			(thermal_gap 0.5)
			(thermal_bridge_width 0.5)
			(island_removal_mode 1)
			(island_area_min 10)
		)
		(polygon
			(pts
				(xy 141.312736 161.495652) (xy 141.377615 161.437595) (xy 141.437096 161.397584) (xy 141.542061 161.359114)
				(xy 141.678356 161.349873) (xy 141.77714 161.346966) (xy 141.893889 161.331738) (xy 141.810707 160.909293)
				(xy 141.388262 160.826111) (xy 141.370953 160.988348) (xy 141.370127 161.041644) (xy 141.367095 161.131998)
				(xy 141.35074 161.218037) (xy 141.307634 161.307285) (xy 141.224348 161.407264)
			)
		)
	)
	(zone
		(net 987)
		(net_name "Net-(Q13-B)")
		(layer "F.Cu")
		(name "$teardrop_padvia$")
		(hatch none 0.1)
		(priority 30851)
		(attr
			(teardrop
				(type padvia)
			)
		)
		(connect_pads yes
			(clearance 0)
		)
		(min_thickness 0.0254)
		(filled_areas_thickness no)
		(fill yes
			(thermal_gap 0.5)
			(thermal_bridge_width 0.5)
			(island_removal_mode 1)
			(island_area_min 10)
		)
		(polygon
			(pts
				(xy 201.399 82.909837) (xy 201.390552 82.971511) (xy 201.376111 83.004234) (xy 201.351412 83.034073)
				(xy 201.319291 83.055404) (xy 201.275562 83.070044) (xy 201.270592 83.071039) (xy 201.52239 83.348837)
				(xy 201.773438 83.070538) (xy 201.717998 83.057157) (xy 201.674896 83.037409) (xy 201.62008 82.984581)
				(xy 201.599346 82.91976) (xy 201.599 82.909837)
			)
		)
	)
	(zone
		(net 378)
		(net_name "/Com Express 7 Interfaces/USB1.D+")
		(layer "F.Cu")
		(name "$teardrop_padvia$")
		(hatch none 0.1)
		(priority 31499)
		(attr
			(teardrop
				(type padvia)
			)
		)
		(connect_pads yes
			(clearance 0)
		)
		(min_thickness 0.0254)
		(filled_areas_thickness no)
		(fill yes
			(thermal_gap 0.5)
			(thermal_bridge_width 0.5)
			(island_removal_mode 1)
			(island_area_min 10)
		)
		(polygon
			(pts
				(xy 158.290416 71.7025) (xy 158.454857 71.698316) (xy 158.637562 71.698177) (xy 158.651 71.4775)
				(xy 158.497104 71.318311) (xy 158.448225 71.385836) (xy 158.434851 71.41218) (xy 158.413476 71.452443)
				(xy 158.386767 71.486002) (xy 158.347992 71.508979) (xy 158.290416 71.5175)
			)
		)
	)
	(zone
		(net 1)
		(net_name "GND")
		(layer "F.Cu")
		(name "$teardrop_padvia$")
		(hatch none 0.1)
		(priority 30603)
		(attr
			(teardrop
				(type padvia)
			)
		)
		(connect_pads yes
			(clearance 0)
		)
		(min_thickness 0.0254)
		(filled_areas_thickness no)
		(fill yes
			(thermal_gap 0.5)
			(thermal_bridge_width 0.5)
			(island_removal_mode 1)
			(island_area_min 10)
		)
		(polygon
			(pts
				(xy 195.925 167.75) (xy 195.928333 167.764486) (xy 195.93119 167.79461) (xy 195.919036 167.805651)
				(xy 195.89 167.81) (xy 196.025 168.686) (xy 196.16 167.81) (xy 196.130666 167.805525) (xy 196.118642 167.794199)
				(xy 196.121667 167.764486) (xy 196.125 167.75)
			)
		)
	)
	(zone
		(net 14)
		(net_name "/Com Express 7 Interfaces/PCIe_{B1x2}.RX0+")
		(layer "F.Cu")
		(name "$teardrop_padvia$")
		(hatch none 0.1)
		(priority 31339)
		(attr
			(teardrop
				(type padvia)
			)
		)
		(connect_pads yes
			(clearance 0)
		)
		(min_thickness 0.0254)
		(filled_areas_thickness no)
		(fill yes
			(thermal_gap 0.5)
			(thermal_bridge_width 0.5)
			(island_removal_mode 1)
			(island_area_min 10)
		)
		(polygon
			(pts
				(xy 202.9795 163.982504) (xy 202.974765 164.02929) (xy 202.961621 164.064742) (xy 202.916613 164.112939)
				(xy 202.878393 164.137115) (xy 202.835226 164.164484) (xy 202.793268 164.201147) (xy 202.9565 164.351)
				(xy 203.177177 164.33014) (xy 203.172548 164.229469) (xy 203.17598 164.146102) (xy 203.176105 164.144035)
				(xy 203.1815 163.982504)
			)
		)
	)
	(zone
		(net 578)
		(net_name "/Power/PG_{1V0}")
		(layer "F.Cu")
		(name "$teardrop_padvia$")
		(hatch none 0.1)
		(priority 31779)
		(attr
			(teardrop
				(type padvia)
			)
		)
		(connect_pads yes
			(clearance 0)
		)
		(min_thickness 0.0254)
		(filled_areas_thickness no)
		(fill yes
			(thermal_gap 0.5)
			(thermal_bridge_width 0.5)
			(island_removal_mode 1)
			(island_area_min 10)
		)
		(polygon
			(pts
				(xy 311.327499 119.060677) (xy 311.332317 118.991236) (xy 311.346039 118.939912) (xy 311.392754 118.86437)
				(xy 311.402298 118.852229) (xy 311.45208 118.785003) (xy 311.264999 118.659) (xy 311.077918 118.785003)
				(xy 311.1277 118.852231) (xy 311.182105 118.935397) (xy 311.197189 118.988251) (xy 311.202499 119.060677)
			)
		)
	)
	(zone
		(net 724)
		(net_name "/2xSFP+/KR to SFI #1/TMS")
		(layer "F.Cu")
		(name "$teardrop_padvia$")
		(hatch none 0.1)
		(priority 30109)
		(attr
			(teardrop
				(type padvia)
			)
		)
		(connect_pads yes
			(clearance 0)
		)
		(min_thickness 0.0254)
		(filled_areas_thickness no)
		(fill yes
			(thermal_gap 0.5)
			(thermal_bridge_width 0.5)
			(island_removal_mode 1)
			(island_area_min 10)
		)
		(polygon
			(pts
				(xy 153.8125 130.227794) (xy 153.817315 130.145733) (xy 153.831019 130.080388) (xy 153.877576 129.98712)
				(xy 153.945787 129.908657) (xy 154.001942 129.847158) (xy 154.061801 129.768339) (xy 153.75 129.559)
				(xy 153.438199 129.768339) (xy 153.535219 129.888517) (xy 153.554214 129.908658) (xy 153.607366 129.967541)
				(xy 153.649591 130.031624) (xy 153.677449 130.114008) (xy 153.6875 130.227794)
			)
		)
	)
	(zone
		(net 1)
		(net_name "GND")
		(layer "F.Cu")
		(name "$teardrop_padvia$")
		(hatch none 0.1)
		(priority 30527)
		(attr
			(teardrop
				(type padvia)
			)
		)
		(connect_pads yes
			(clearance 0)
		)
		(min_thickness 0.0254)
		(filled_areas_thickness no)
		(fill yes
			(thermal_gap 0.5)
			(thermal_bridge_width 0.5)
			(island_removal_mode 1)
			(island_area_min 10)
		)
		(polygon
			(pts
				(xy 175.925 162.2) (xy 175.928333 162.214486) (xy 175.93119 162.24461) (xy 175.919036 162.255651)
				(xy 175.89 162.26) (xy 176.025 163.136) (xy 176.16 162.26) (xy 176.130666 162.255525) (xy 176.118642 162.244199)
				(xy 176.121667 162.214486) (xy 176.125 162.2)
			)
		)
	)
	(zone
		(net 744)
		(net_name "/2xSFP+/KR to SFI #2/TMS")
		(layer "F.Cu")
		(name "$teardrop_padvia$")
		(hatch none 0.1)
		(priority 31695)
		(attr
			(teardrop
				(type padvia)
			)
		)
		(connect_pads yes
			(clearance 0)
		)
		(min_thickness 0.0254)
		(filled_areas_thickness no)
		(fill yes
			(thermal_gap 0.5)
			(thermal_bridge_width 0.5)
			(island_removal_mode 1)
			(island_area_min 10)
		)
		(polygon
			(pts
				(xy 135.5275 130.109323) (xy 135.522682 130.178763) (xy 135.50896 130.230087) (xy 135.462245 130.305628)
				(xy 135.452702 130.317768) (xy 135.402919 130.384997) (xy 135.59 130.511) (xy 135.777081 130.384997)
				(xy 135.727299 130.317769) (xy 135.672894 130.234603) (xy 135.65781 130.181748) (xy 135.6525 130.109323)
			)
		)
	)
	(zone
		(net 1)
		(net_name "GND")
		(layer "F.Cu")
		(name "$teardrop_padvia$")
		(hatch none 0.1)
		(priority 30780)
		(attr
			(teardrop
				(type padvia)
			)
		)
		(connect_pads yes
			(clearance 0)
		)
		(min_thickness 0.0254)
		(filled_areas_thickness no)
		(fill yes
			(thermal_gap 0.5)
			(thermal_bridge_width 0.5)
			(island_removal_mode 1)
			(island_area_min 10)
		)
		(polygon
			(pts
				(xy 152.969177 81.9095) (xy 152.811606 81.902569) (xy 152.698078 81.874049) (xy 152.656278 81.857)
				(xy 152.5675 82.0595) (xy 152.656278 82.262) (xy 152.752317 82.227618) (xy 152.854189 82.2124) (xy 152.969177 82.2095)
			)
		)
	)
	(zone
		(net 1)
		(net_name "GND")
		(layer "F.Cu")
		(name "$teardrop_padvia$")
		(hatch none 0.1)
		(priority 31280)
		(attr
			(teardrop
				(type padvia)
			)
		)
		(connect_pads yes
			(clearance 0)
		)
		(min_thickness 0.0254)
		(filled_areas_thickness no)
		(fill yes
			(thermal_gap 0.5)
			(thermal_bridge_width 0.5)
			(island_removal_mode 1)
			(island_area_min 10)
		)
		(polygon
			(pts
				(xy 190.60861 77.701486) (xy 190.603897 77.779397) (xy 190.59091 77.838181) (xy 190.548809 77.929211)
				(xy 190.50611 78.014384) (xy 190.70861 78.103163) (xy 190.91111 78.014384) (xy 190.868411 77.929213)
				(xy 190.825743 77.83638) (xy 190.813166 77.778241) (xy 190.80861 77.701486)
			)
		)
	)
	(zone
		(net 641)
		(net_name "Net-(U41-IO0_2)")
		(layer "F.Cu")
		(name "$teardrop_padvia$")
		(hatch none 0.1)
		(priority 32022)
		(attr
			(teardrop
				(type padvia)
			)
		)
		(connect_pads yes
			(clearance 0)
		)
		(min_thickness 0.0254)
		(filled_areas_thickness no)
		(fill yes
			(thermal_gap 0.5)
			(thermal_bridge_width 0.5)
			(island_removal_mode 1)
			(island_area_min 10)
		)
		(polygon
			(pts
				(xy 128.2495 85.372501) (xy 128.255822 85.372405) (xy 128.295325 85.37799) (xy 128.313548 85.392922)
				(xy 128.326496 85.4225) (xy 128.713 85.31) (xy 128.326494 85.1975) (xy 128.315378 85.224494) (xy 128.299851 85.239596)
				(xy 128.255821 85.247597) (xy 128.2495 85.247501)
			)
		)
	)
	(zone
		(net 1)
		(net_name "GND")
		(layer "F.Cu")
		(name "$teardrop_padvia$")
		(hatch none 0.1)
		(priority 31216)
		(attr
			(teardrop
				(type padvia)
			)
		)
		(connect_pads yes
			(clearance 0)
		)
		(min_thickness 0.0254)
		(filled_areas_thickness no)
		(fill yes
			(thermal_gap 0.5)
			(thermal_bridge_width 0.5)
			(island_removal_mode 1)
			(island_area_min 10)
		)
		(polygon
			(pts
				(xy 180.925 169.498323) (xy 180.92028 169.567646) (xy 180.907244 169.620549) (xy 180.855344 169.713135)
				(xy 180.803541 169.796636) (xy 181 169.9) (xy 181.207644 169.823641) (xy 181.175418 169.743142)
				(xy 181.139035 169.641683) (xy 181.125 169.498323)
			)
		)
	)
	(zone
		(net 359)
		(net_name "/Com Express 7 MGMT/SMBus.~{INT}")
		(layer "F.Cu")
		(name "$teardrop_padvia$")
		(hatch none 0.1)
		(priority 31866)
		(attr
			(teardrop
				(type padvia)
			)
		)
		(connect_pads yes
			(clearance 0)
		)
		(min_thickness 0.0254)
		(filled_areas_thickness no)
		(fill yes
			(thermal_gap 0.5)
			(thermal_bridge_width 0.5)
			(island_removal_mode 1)
			(island_area_min 10)
		)
		(polygon
			(pts
				(xy 183.672485 145.260873) (xy 183.718181 145.313382) (xy 183.744768 145.359376) (xy 183.765152 145.445825)
				(xy 183.766988 145.461158) (xy 183.779323 145.543895) (xy 184.000707 145.500707) (xy 184.043895 145.279323)
				(xy 183.961158 145.266988) (xy 183.86388 145.246651) (xy 183.81584 145.219943) (xy 183.760873 145.172485)
			)
		)
	)
	(zone
		(net 1)
		(net_name "GND")
		(layer "F.Cu")
		(name "$teardrop_padvia$")
		(hatch none 0.1)
		(priority 31310)
		(attr
			(teardrop
				(type padvia)
			)
		)
		(connect_pads yes
			(clearance 0)
		)
		(min_thickness 0.0254)
		(filled_areas_thickness no)
		(fill yes
			(thermal_gap 0.5)
			(thermal_bridge_width 0.5)
			(island_removal_mode 1)
			(island_area_min 10)
		)
		(polygon
			(pts
				(xy 205.625 167.498148) (xy 205.629746 167.435351) (xy 205.642971 167.387575) (xy 205.688455 167.316519)
				(xy 205.704462 167.297985) (xy 205.762081 167.225003) (xy 205.575 167.099) (xy 205.362745 167.164229)
				(xy 205.382421 167.226697) (xy 205.413993 167.342031) (xy 205.425 167.498148)
			)
		)
	)
	(zone
		(net 1)
		(net_name "GND")
		(layer "F.Cu")
		(name "$teardrop_padvia$")
		(hatch none 0.1)
		(priority 30028)
		(attr
			(teardrop
				(type padvia)
			)
		)
		(connect_pads yes
			(clearance 0)
		)
		(min_thickness 0.0254)
		(filled_areas_thickness no)
		(fill yes
			(thermal_gap 0.5)
			(thermal_bridge_width 0.5)
			(island_removal_mode 1)
			(island_area_min 10)
		)
		(polygon
			(pts
				(xy 317.84 161.01) (xy 317.892671 161.017457) (xy 317.946335 161.049659) (xy 317.969018 161.080423)
				(xy 317.985714 161.123461) (xy 317.990273 161.144727) (xy 319.451 160.91) (xy 317.990273 160.675273)
				(xy 317.977656 160.721208) (xy 317.958906 160.755539) (xy 317.908407 160.796597) (xy 317.84 160.81)
			)
		)
	)
	(zone
		(net 586)
		(net_name "Net-(U22-FB)")
		(layer "F.Cu")
		(name "$teardrop_padvia$")
		(hatch none 0.1)
		(priority 30620)
		(attr
			(teardrop
				(type padvia)
			)
		)
		(connect_pads yes
			(clearance 0)
		)
		(min_thickness 0.0254)
		(filled_areas_thickness no)
		(fill yes
			(thermal_gap 0.5)
			(thermal_bridge_width 0.5)
			(island_removal_mode 1)
			(island_area_min 10)
		)
		(polygon
			(pts
				(xy 313.653044 136.675933) (xy 313.713026 136.764661) (xy 313.736579 136.827163) (xy 313.752015 136.898507)
				(xy 313.755499 137.021794) (xy 314.076206 136.940707) (xy 314.133669 136.645) (xy 314.040744 136.65849)
				(xy 313.955545 136.660927) (xy 313.883078 136.653302) (xy 313.820469 136.636292) (xy 313.741432 136.587545)
			)
		)
	)
	(zone
		(net 2)
		(net_name "+3V3")
		(layer "F.Cu")
		(name "$teardrop_padvia$")
		(hatch none 0.1)
		(priority 30183)
		(attr
			(teardrop
				(type padvia)
			)
		)
		(connect_pads yes
			(clearance 0)
		)
		(min_thickness 0.0254)
		(filled_areas_thickness no)
		(fill yes
			(thermal_gap 0.5)
			(thermal_bridge_width 0.5)
			(island_removal_mode 1)
			(island_area_min 10)
		)
		(polygon
			(pts
				(xy 309.471475 77.374107) (xy 309.447948 77.375119) (xy 309.428528 77.364418) (xy 309.401926 77.311641)
				(xy 309.382776 77.156463) (xy 308.997293 77.483707) (xy 309.377461 77.81749) (xy 309.402053 77.711338)
				(xy 309.4602 77.617685) (xy 309.546141 77.544791) (xy 309.612894 77.515529)
			)
		)
	)
	(zone
		(net 2)
		(net_name "+3V3")
		(layer "F.Cu")
		(name "$teardrop_padvia$")
		(hatch none 0.1)
		(priority 30892)
		(attr
			(teardrop
				(type padvia)
			)
		)
		(connect_pads yes
			(clearance 0)
		)
		(min_thickness 0.0254)
		(filled_areas_thickness no)
		(fill yes
			(thermal_gap 0.5)
			(thermal_bridge_width 0.5)
			(island_removal_mode 1)
			(island_area_min 10)
		)
		(polygon
			(pts
				(xy 125.183 150.063219) (xy 125.187702 150.027773) (xy 125.200618 150.001777) (xy 125.245254 149.968893)
				(xy 125.282487 149.954763) (xy 125.345003 149.927081) (xy 125.22 149.739) (xy 124.999323 149.716302)
				(xy 124.973973 149.800834) (xy 124.947937 149.847867) (xy 124.903725 149.936341) (xy 124.888743 149.992948)
				(xy 124.883 150.063219)
			)
		)
	)
	(zone
		(net 262)
		(net_name "/Com Express 7 Interfaces/PCIe_{B2Bx4}.RX0-")
		(layer "F.Cu")
		(name "$teardrop_padvia$")
		(hatch none 0.1)
		(priority 30517)
		(attr
			(teardrop
				(type padvia)
			)
		)
		(connect_pads yes
			(clearance 0)
		)
		(min_thickness 0.0254)
		(filled_areas_thickness no)
		(fill yes
			(thermal_gap 0.5)
			(thermal_bridge_width 0.5)
			(island_removal_mode 1)
			(island_area_min 10)
		)
		(polygon
			(pts
				(xy 195.424 162.2) (xy 195.427537 162.214678) (xy 195.430808 162.244685) (xy 195.418857 162.255673)
				(xy 195.39 162.26) (xy 195.525 163.136) (xy 195.66 162.26) (xy 195.630796 162.255525) (xy 195.619003 162.244203)
				(xy 195.622463 162.214678) (xy 195.626 162.2)
			)
		)
	)
	(zone
		(net 1)
		(net_name "GND")
		(layer "F.Cu")
		(name "$teardrop_padvia$")
		(hatch none 0.1)
		(priority 31015)
		(attr
			(teardrop
				(type padvia)
			)
		)
		(connect_pads yes
			(clearance 0)
		)
		(min_thickness 0.0254)
		(filled_areas_thickness no)
		(fill yes
			(thermal_gap 0.5)
			(thermal_bridge_width 0.5)
			(island_removal_mode 1)
			(island_area_min 10)
		)
		(polygon
			(pts
				(xy 192.791058 141.59453) (xy 192.732485 141.624862) (xy 192.691169 141.62877) (xy 192.644553 141.622479)
				(xy 192.595254 141.605033) (xy 192.54374 141.575031) (xy 192.543217 141.574662) (xy 192.524832 141.949143)
				(xy 192.899313 141.930758) (xy 192.870225 141.881452) (xy 192.852686 141.8341) (xy 192.845392 141.788105)
				(xy 192.847991 141.746993) (xy 192.85948 141.711409) (xy 192.87844 141.683939) (xy 192.879446 141.682918)
			)
		)
	)
	(zone
		(net 1)
		(net_name "GND")
		(layer "F.Cu")
		(name "$teardrop_padvia$")
		(hatch none 0.1)
		(priority 31557)
		(attr
			(teardrop
				(type padvia)
			)
		)
		(connect_pads yes
			(clearance 0)
		)
		(min_thickness 0.0254)
		(filled_areas_thickness no)
		(fill yes
			(thermal_gap 0.5)
			(thermal_bridge_width 0.5)
			(island_removal_mode 1)
			(island_area_min 10)
		)
		(polygon
			(pts
				(xy 249.118 130.593) (xy 249.109751 130.570923) (xy 249.099017 130.532428) (xy 249.111982 130.518475)
				(xy 249.148 130.513) (xy 248.968 130.137) (xy 248.788 130.513) (xy 248.821735 130.51754) (xy 248.835928 130.529323)
				(xy 248.832446 130.557817) (xy 248.826249 130.570923) (xy 248.818 130.593)
			)
		)
	)
	(zone
		(net 264)
		(net_name "/Com Express 7 Interfaces/PCIe_{B2Bx4}.RX0+")
		(layer "F.Cu")
		(name "$teardrop_padvia$")
		(hatch none 0.1)
		(priority 31905)
		(attr
			(teardrop
				(type padvia)
			)
		)
		(connect_pads yes
			(clearance 0)
		)
		(min_thickness 0.0254)
		(filled_areas_thickness no)
		(fill yes
			(thermal_gap 0.5)
			(thermal_bridge_width 0.5)
			(island_removal_mode 1)
			(island_area_min 10)
		)
		(polygon
			(pts
				(xy 195.096418 161.893916) (xy 195.133636 161.850005) (xy 195.15607 161.809009) (xy 195.170344 161.730542)
				(xy 195.168404 161.681328) (xy 195.166359 161.619576) (xy 195.174715 161.549837) (xy 194.957207 161.499293)
				(xy 194.831497 161.687081) (xy 194.88454 161.704912) (xy 194.907082 161.708833) (xy 194.957167 161.721444)
				(xy 194.964717 161.732951) (xy 194.953583 161.751081)
			)
		)
	)
	(zone
		(net 273)
		(net_name "/M.2 key M #2/PCIE_{REF}.CK+")
		(layer "F.Cu")
		(name "$teardrop_padvia$")
		(hatch none 0.1)
		(priority 31427)
		(attr
			(teardrop
				(type padvia)
			)
		)
		(connect_pads yes
			(clearance 0)
		)
		(min_thickness 0.0254)
		(filled_areas_thickness no)
		(fill yes
			(thermal_gap 0.5)
			(thermal_bridge_width 0.5)
			(island_removal_mode 1)
			(island_area_min 10)
		)
		(polygon
			(pts
				(xy 299.542 75.127139) (xy 299.547395 75.28867) (xy 299.550945 75.373081) (xy 299.546323 75.474775)
				(xy 299.767 75.495635) (xy 299.930231 75.345782) (xy 299.861562 75.291642) (xy 299.845108 75.281751)
				(xy 299.806435 75.257251) (xy 299.774221 75.227744) (xy 299.752173 75.186588) (xy 299.744 75.127139)
			)
		)
	)
	(zone
		(net 599)
		(net_name "Net-(U34-~{INT})")
		(layer "F.Cu")
		(name "$teardrop_padvia$")
		(hatch none 0.1)
		(priority 30825)
		(attr
			(teardrop
				(type padvia)
			)
		)
		(connect_pads yes
			(clearance 0)
		)
		(min_thickness 0.0254)
		(filled_areas_thickness no)
		(fill yes
			(thermal_gap 0.5)
			(thermal_bridge_width 0.5)
			(island_removal_mode 1)
			(island_area_min 10)
		)
		(polygon
			(pts
				(xy 243.109173 131.239214) (xy 243.14069 131.162839) (xy 243.172525 131.125286) (xy 243.214632 131.095006)
				(xy 243.26705 131.07705) (xy 243.075707 130.559293) (xy 242.88295 131.07705) (xy 242.974394 131.098781)
				(xy 243.017555 131.129249) (xy 243.020786 131.150827)
			)
		)
	)
	(zone
		(net 1)
		(net_name "GND")
		(layer "F.Cu")
		(name "$teardrop_padvia$")
		(hatch none 0.1)
		(priority 30575)
		(attr
			(teardrop
				(type padvia)
			)
		)
		(connect_pads yes
			(clearance 0)
		)
		(min_thickness 0.0254)
		(filled_areas_thickness no)
		(fill yes
			(thermal_gap 0.5)
			(thermal_bridge_width 0.5)
			(island_removal_mode 1)
			(island_area_min 10)
		)
		(polygon
			(pts
				(xy 215.425 150.2) (xy 215.428333 150.214486) (xy 215.43119 150.24461) (xy 215.419036 150.255651)
				(xy 215.39 150.26) (xy 215.525 151.136) (xy 215.66 150.26) (xy 215.630666 150.255525) (xy 215.618642 150.244199)
				(xy 215.621667 150.214486) (xy 215.625 150.2)
			)
		)
	)
	(zone
		(net 1)
		(net_name "GND")
		(layer "F.Cu")
		(name "$teardrop_padvia$")
		(hatch none 0.1)
		(priority 30552)
		(attr
			(teardrop
				(type padvia)
			)
		)
		(connect_pads yes
			(clearance 0)
		)
		(min_thickness 0.0254)
		(filled_areas_thickness no)
		(fill yes
			(thermal_gap 0.5)
			(thermal_bridge_width 0.5)
			(island_removal_mode 1)
			(island_area_min 10)
		)
		(polygon
			(pts
				(xy 211.925 155.75) (xy 211.928333 155.764486) (xy 211.93119 155.79461) (xy 211.919036 155.805651)
				(xy 211.89 155.81) (xy 212.025 156.686) (xy 212.16 155.81) (xy 212.130666 155.805525) (xy 212.118642 155.794199)
				(xy 212.121667 155.764486) (xy 212.125 155.75)
			)
		)
	)
	(zone
		(net 580)
		(net_name "Net-(U18-FB)")
		(layer "F.Cu")
		(name "$teardrop_padvia$")
		(hatch none 0.1)
		(priority 32137)
		(attr
			(teardrop
				(type padvia)
			)
		)
		(connect_pads yes
			(clearance 0)
		)
		(min_thickness 0.0254)
		(filled_areas_thickness no)
		(fill yes
			(thermal_gap 0.5)
			(thermal_bridge_width 0.5)
			(island_removal_mode 1)
			(island_area_min 10)
		)
		(polygon
			(pts
				(xy 309.97692 121.074499) (xy 309.993646 121.073084) (xy 310.03397 121.073109) (xy 310.054265 121.082236)
				(xy 310.072521 121.102564) (xy 310.315999 121.013999) (xy 310.079358 120.922602) (xy 310.060468 120.941759)
				(xy 310.039973 120.950813) (xy 309.995139 120.95104) (xy 309.97692 120.949499)
			)
		)
	)
	(zone
		(net 1)
		(net_name "GND")
		(layer "F.Cu")
		(name "$teardrop_padvia$")
		(hatch none 0.1)
		(priority 31112)
		(attr
			(teardrop
				(type padvia)
			)
		)
		(connect_pads yes
			(clearance 0)
		)
		(min_thickness 0.0254)
		(filled_areas_thickness no)
		(fill yes
			(thermal_gap 0.5)
			(thermal_bridge_width 0.5)
			(island_removal_mode 1)
			(island_area_min 10)
		)
		(polygon
			(pts
				(xy 193.586553 141.471493) (xy 193.558524 141.415501) (xy 193.563607 141.331102) (xy 193.582645 141.281373)
				(xy 193.614243 141.229023) (xy 193.621447 141.219301) (xy 193.249617 141.222945) (xy 193.245973 141.594775)
				(xy 193.297584 141.561336) (xy 193.346953 141.540159) (xy 193.393653 141.530122) (xy 193.435255 141.530692)
				(xy 193.469839 141.540541) (xy 193.496811 141.558556) (xy 193.498165 141.559881)
			)
		)
	)
	(zone
		(net 561)
		(net_name "Net-(U5-A1)")
		(layer "F.Cu")
		(name "$teardrop_padvia$")
		(hatch none 0.1)
		(priority 32012)
		(attr
			(teardrop
				(type padvia)
			)
		)
		(connect_pads yes
			(clearance 0)
		)
		(min_thickness 0.0254)
		(filled_areas_thickness no)
		(fill yes
			(thermal_gap 0.5)
			(thermal_bridge_width 0.5)
			(island_removal_mode 1)
			(island_area_min 10)
		)
		(polygon
			(pts
				(xy 158.4875 158.2095) (xy 158.487596 158.215822) (xy 158.482011 158.255325) (xy 158.467078 158.273547)
				(xy 158.4375 158.286495) (xy 158.55 158.673) (xy 158.6625 158.286495) (xy 158.635507 158.275379)
				(xy 158.620405 158.259852) (xy 158.612404 158.215822) (xy 158.6125 158.2095)
			)
		)
	)
	(zone
		(net 281)
		(net_name "/Misc/TACH_{B5V}")
		(layer "F.Cu")
		(name "$teardrop_padvia$")
		(hatch none 0.1)
		(priority 32028)
		(attr
			(teardrop
				(type padvia)
			)
		)
		(connect_pads yes
			(clearance 0)
		)
		(min_thickness 0.0254)
		(filled_areas_thickness no)
		(fill yes
			(thermal_gap 0.5)
			(thermal_bridge_width 0.5)
			(island_removal_mode 1)
			(island_area_min 10)
		)
		(polygon
			(pts
				(xy 250.789209 76.843) (xy 250.783687 76.870072) (xy 250.765031 76.895611) (xy 250.738412 76.91178)
				(xy 250.699671 76.921399) (xy 250.671709 76.923) (xy 250.851709 77.124) (xy 251.031709 76.923) (xy 250.986209 76.918387)
				(xy 250.953241 76.9061) (xy 250.918865 76.867945) (xy 250.914209 76.843)
			)
		)
	)
	(zone
		(net 322)
		(net_name "/Com Express 7 Interfaces/SDIO.DAT1")
		(layer "F.Cu")
		(name "$teardrop_padvia$")
		(hatch none 0.1)
		(priority 30712)
		(attr
			(teardrop
				(type padvia)
			)
		)
		(connect_pads yes
			(clearance 0)
		)
		(min_thickness 0.0254)
		(filled_areas_thickness no)
		(fill yes
			(thermal_gap 0.5)
			(thermal_bridge_width 0.5)
			(island_removal_mode 1)
			(island_area_min 10)
		)
		(polygon
			(pts
				(xy 207.091 169.62) (xy 207.089426 169.607843) (xy 207.090715 169.576295) (xy 207.10519 169.564616)
				(xy 207.136651 169.56) (xy 207.025 168.684) (xy 206.875 169.56) (xy 206.902296 169.564475) (xy 206.913828 169.575797)
				(xy 206.911744 169.606097) (xy 206.909 169.62)
			)
		)
	)
	(zone
		(net 1)
		(net_name "GND")
		(layer "F.Cu")
		(name "$teardrop_padvia$")
		(hatch none 0.1)
		(priority 30609)
		(attr
			(teardrop
				(type padvia)
			)
		)
		(connect_pads yes
			(clearance 0)
		)
		(min_thickness 0.0254)
		(filled_areas_thickness no)
		(fill yes
			(thermal_gap 0.5)
			(thermal_bridge_width 0.5)
			(island_removal_mode 1)
			(island_area_min 10)
		)
		(polygon
			(pts
				(xy 201.125 157.62) (xy 201.121667 157.605514) (xy 201.11881 157.57539) (xy 201.130964 157.564349)
				(xy 201.16 157.56) (xy 201.025 156.684) (xy 200.89 157.56) (xy 200.919334 157.564475) (xy 200.931358 157.575801)
				(xy 200.928333 157.605514) (xy 200.925 157.62)
			)
		)
	)
	(zone
		(net 374)
		(net_name "/2xUSB3.0+RJ45/USB_2.D-")
		(layer "F.Cu")
		(name "$teardrop_padvia$")
		(hatch none 0.1)
		(priority 30287)
		(attr
			(teardrop
				(type padvia)
			)
		)
		(connect_pads yes
			(clearance 0)
		)
		(min_thickness 0.0254)
		(filled_areas_thickness no)
		(fill yes
			(thermal_gap 0.5)
			(thermal_bridge_width 0.5)
			(island_removal_mode 1)
			(island_area_min 10)
		)
		(polygon
			(pts
				(xy 196.4925 162.2) (xy 196.494085 162.212189) (xy 196.492704 162.243738) (xy 196.477931 162.255396)
				(xy 196.445877 162.26) (xy 196.525 163.136) (xy 196.675 162.906314) (xy 196.655715 162.6469) (xy 196.668097 162.373917)
				(xy 196.6775 162.2)
			)
		)
	)
	(zone
		(net 374)
		(net_name "/2xUSB3.0+RJ45/USB_2.D-")
		(layer "F.Cu")
		(name "$teardrop_padvia$")
		(hatch none 0.1)
		(priority 31494)
		(attr
			(teardrop
				(type padvia)
			)
		)
		(connect_pads yes
			(clearance 0)
		)
		(min_thickness 0.0254)
		(filled_areas_thickness no)
		(fill yes
			(thermal_gap 0.5)
			(thermal_bridge_width 0.5)
			(island_removal_mode 1)
			(island_area_min 10)
		)
		(polygon
			(pts
				(xy 196.6775 161.859584) (xy 196.673316 161.695141) (xy 196.673177 161.512437) (xy 196.4525 161.499)
				(xy 196.293311 161.652895) (xy 196.360836 161.701773) (xy 196.387179 161.715148) (xy 196.427443 161.736523)
				(xy 196.461001 161.763232) (xy 196.483979 161.802007) (xy 196.4925 161.859584)
			)
		)
	)
	(zone
		(net 43)
		(net_name "/2xUSB3.0+RJ45/P2_VBUS")
		(layer "F.Cu")
		(hatch edge 0.5)
		(priority 34)
		(connect_pads yes
			(clearance 0.15)
		)
		(min_thickness 0.25)
		(filled_areas_thickness no)
		(fill yes
			(thermal_gap 0.5)
			(thermal_bridge_width 0.5)
			(smoothing fillet)
			(radius 0.2)
		)
		(polygon
			(pts
				(xy 116.25 91.21) (xy 116.3 91.16) (xy 116.3 89.56) (xy 109.3 89.56) (xy 109.3 91.66) (xy 112.3 91.66)
				(xy 112.75 91.21)
			)
		)
	)
	(zone
		(net 195)
		(net_name "/OCuLink/PCIe_{x4}.RX2-")
		(layer "F.Cu")
		(name "$teardrop_padvia$")
		(hatch none 0.1)
		(priority 31391)
		(attr
			(teardrop
				(type padvia)
			)
		)
		(connect_pads yes
			(clearance 0)
		)
		(min_thickness 0.0254)
		(filled_areas_thickness no)
		(fill yes
			(thermal_gap 0.5)
			(thermal_bridge_width 0.5)
			(island_removal_mode 1)
			(island_area_min 10)
		)
		(polygon
			(pts
				(xy 109.0065 149.167496) (xy 109.001105 149.005964) (xy 108.997555 148.921553) (xy 109.002177 148.819859)
				(xy 108.7815 148.799) (xy 108.618268 148.948852) (xy 108.686936 149.002992) (xy 108.703392 149.012884)
				(xy 108.742064 149.037384) (xy 108.774279 149.06689) (xy 108.796327 149.108046) (xy 108.8045 149.167496)
			)
		)
	)
	(zone
		(net 215)
		(net_name "/Com Express 7 Interfaces/PCIe_{B1x4}.TX2-")
		(layer "F.Cu")
		(name "$teardrop_padvia$")
		(hatch none 0.1)
		(priority 31337)
		(attr
			(teardrop
				(type padvia)
			)
		)
		(connect_pads yes
			(clearance 0)
		)
		(min_thickness 0.0254)
		(filled_areas_thickness no)
		(fill yes
			(thermal_gap 0.5)
			(thermal_bridge_width 0.5)
			(island_removal_mode 1)
			(island_area_min 10)
		)
		(polygon
			(pts
				(xy 206.468809 166.350908) (xy 206.439075 166.314477) (xy 206.423301 166.280114) (xy 206.421045 166.214209)
				(xy 206.430976 166.170087) (xy 206.442147 166.120211) (xy 206.445891 166.064618) (xy 206.224507 166.074079)
				(xy 206.083214 166.24487) (xy 206.157673 166.312783) (xy 206.214195 166.37416) (xy 206.215566 166.375707)
				(xy 206.325973 166.493744)
			)
		)
	)
	(zone
		(net 542)
		(net_name "Net-(Q9-E)")
		(layer "F.Cu")
		(name "$teardrop_padvia$")
		(hatch none 0.1)
		(priority 31303)
		(attr
			(teardrop
				(type padvia)
			)
		)
		(connect_pads yes
			(clearance 0)
		)
		(min_thickness 0.0254)
		(filled_areas_thickness no)
		(fill yes
			(thermal_gap 0.5)
			(thermal_bridge_width 0.5)
			(island_removal_mode 1)
			(island_area_min 10)
		)
		(polygon
			(pts
				(xy 121.399323 141.011) (xy 121.477653 141.015713) (xy 121.536712 141.028701) (xy 121.627625 141.070412)
				(xy 121.712752 141.112719) (xy 121.801 140.91) (xy 121.711685 140.707722) (xy 121.626483 140.750809)
				(xy 121.53394 140.793743) (xy 121.475927 140.80641) (xy 121.399323 140.811)
			)
		)
	)
	(zone
		(net 73)
		(net_name "+3V3_AON")
		(layer "F.Cu")
		(name "$teardrop_padvia$")
		(hatch none 0.1)
		(priority 30199)
		(attr
			(teardrop
				(type padvia)
			)
		)
		(connect_pads yes
			(clearance 0)
		)
		(min_thickness 0.0254)
		(filled_areas_thickness no)
		(fill yes
			(thermal_gap 0.5)
			(thermal_bridge_width 0.5)
			(island_removal_mode 1)
			(island_area_min 10)
		)
		(polygon
			(pts
				(xy 302.402 104.04611) (xy 302.385366 103.976108) (xy 302.356423 103.911702) (xy 302.304643 103.780192)
				(xy 302.297679 103.712217) (xy 302.315001 103.644898) (xy 302.020001 103.609) (xy 301.851704 103.925863)
				(xy 301.908821 103.930895) (xy 301.9431 103.94359) (xy 301.957994 103.958584) (xy 301.963479 103.976196)
				(xy 301.957247 104.018442) (xy 301.952 104.04611)
			)
		)
	)
	(zone
		(net 1)
		(net_name "GND")
		(layer "F.Cu")
		(name "$teardrop_padvia$")
		(hatch none 0.1)
		(priority 30950)
		(attr
			(teardrop
				(type padvia)
			)
		)
		(connect_pads yes
			(clearance 0)
		)
		(min_thickness 0.0254)
		(filled_areas_thickness no)
		(fill yes
			(thermal_gap 0.5)
			(thermal_bridge_width 0.5)
			(island_removal_mode 1)
			(island_area_min 10)
		)
		(polygon
			(pts
				(xy 112.838 149.8175) (xy 112.775134 149.797531) (xy 112.743156 149.771079) (xy 112.714642 149.733668)
				(xy 112.692118 149.686473) (xy 112.676907 149.628833) (xy 112.676798 149.628202) (xy 112.399 149.88)
				(xy 112.676798 150.131798) (xy 112.691095 150.076365) (xy 112.712175 150.03048) (xy 112.73954 149.992799)
				(xy 112.770448 149.965566) (xy 112.803735 149.948528) (xy 112.836566 149.942511) (xy 112.838 149.9425)
			)
		)
	)
	(zone
		(net 628)
		(net_name "/PCIe redriver/TX_SW")
		(layer "F.Cu")
		(name "$teardrop_padvia$")
		(hatch none 0.1)
		(priority 30965)
		(attr
			(teardrop
				(type padvia)
			)
		)
		(connect_pads yes
			(clearance 0)
		)
		(min_thickness 0.0254)
		(filled_areas_thickness no)
		(fill yes
			(thermal_gap 0.5)
			(thermal_bridge_width 0.5)
			(island_removal_mode 1)
			(island_area_min 10)
		)
		(polygon
			(pts
				(xy 113.838 143.8175) (xy 113.775134 143.797531) (xy 113.743156 143.771079) (xy 113.714642 143.733668)
				(xy 113.692118 143.686473) (xy 113.676907 143.628833) (xy 113.676798 143.628202) (xy 113.399 143.88)
				(xy 113.676798 144.131798) (xy 113.691095 144.076365) (xy 113.712175 144.03048) (xy 113.73954 143.992799)
				(xy 113.770448 143.965566) (xy 113.803735 143.948528) (xy 113.836566 143.942511) (xy 113.838 143.9425)
			)
		)
	)
	(zone
		(net 695)
		(net_name "/2xUSB3.0+RJ45/DD_FL+")
		(layer "F.Cu")
		(name "$teardrop_padvia$")
		(hatch none 0.1)
		(priority 31147)
		(attr
			(teardrop
				(type padvia)
			)
		)
		(connect_pads yes
			(clearance 0)
		)
		(min_thickness 0.0254)
		(filled_areas_thickness no)
		(fill yes
			(thermal_gap 0.5)
			(thermal_bridge_width 0.5)
			(island_removal_mode 1)
			(island_area_min 10)
		)
		(polygon
			(pts
				(xy 128.526861 101.747073) (xy 128.442002 101.802661) (xy 128.383721 101.82191) (xy 128.315724 101.833528)
				(xy 128.173057 101.8325) (xy 128.209293 102.070707) (xy 128.5475 102.088424) (xy 128.5504 101.995052)
				(xy 128.58624 101.910804) (xy 128.632927 101.853139)
			)
		)
	)
	(zone
		(net 1)
		(net_name "GND")
		(layer "F.Cu")
		(name "$teardrop_padvia$")
		(hatch none 0.1)
		(priority 30731)
		(attr
			(teardrop
				(type padvia)
			)
		)
		(connect_pads yes
			(clearance 0)
		)
		(min_thickness 0.0254)
		(filled_areas_thickness no)
		(fill yes
			(thermal_gap 0.5)
			(thermal_bridge_width 0.5)
			(island_removal_mode 1)
			(island_area_min 10)
		)
		(polygon
			(pts
				(xy 306.4125 149.77) (xy 306.407179 149.801735) (xy 306.389931 149.834435) (xy 306.363462 149.860626)
				(xy 306.325036 149.881555) (xy 306.28295 149.89295) (xy 306.475 150.411) (xy 306.66705 149.89295)
				(xy 306.622526 149.880591) (xy 306.5884 149.861992) (xy 306.546464 149.811197) (xy 306.5375 149.77)
			)
		)
	)
	(zone
		(net 237)
		(net_name "/Com Express 7 Interfaces/PCIe_{B2Bx4}.RX3-")
		(layer "F.Cu")
		(name "$teardrop_padvia$")
		(hatch none 0.1)
		(priority 30273)
		(attr
			(teardrop
				(type padvia)
			)
		)
		(connect_pads yes
			(clearance 0)
		)
		(min_thickness 0.0254)
		(filled_areas_thickness no)
		(fill yes
			(thermal_gap 0.5)
			(thermal_bridge_width 0.5)
			(island_removal_mode 1)
			(island_area_min 10)
		)
		(polygon
			(pts
				(xy 186.8685 162.2) (xy 186.879599 162.373112) (xy 186.894216 162.60051) (xy 186.891181 162.735138)
				(xy 186.875 162.887021) (xy 187.025 163.136) (xy 187.108295 162.26) (xy 187.077864 162.255523) (xy 187.065097 162.244185)
				(xy 187.06742 162.214227) (xy 187.0705 162.2)
			)
		)
	)
	(zone
		(net 578)
		(net_name "/Power/PG_{1V0}")
		(layer "F.Cu")
		(name "$teardrop_padvia$")
		(hatch none 0.1)
		(priority 32130)
		(attr
			(teardrop
				(type padvia)
			)
		)
		(connect_pads yes
			(clearance 0)
		)
		(min_thickness 0.0254)
		(filled_areas_thickness no)
		(fill yes
			(thermal_gap 0.5)
			(thermal_bridge_width 0.5)
			(island_removal_mode 1)
			(island_area_min 10)
		)
		(polygon
			(pts
				(xy 311.202499 118.82092) (xy 311.203974 118.838386) (xy 311.204103 118.879831) (xy 311.195116 118.900844)
				(xy 311.174999 118.919986) (xy 311.264999 119.159999) (xy 311.354999 118.919986) (xy 311.335581 118.901842)
				(xy 311.326393 118.881938) (xy 311.326024 118.838386) (xy 311.327499 118.82092)
			)
		)
	)
	(zone
		(net 929)
		(net_name "/2xSFP+/SFP1_LEDG")
		(layer "F.Cu")
		(name "$teardrop_padvia$")
		(hatch none 0.1)
		(priority 30946)
		(attr
			(teardrop
				(type padvia)
			)
		)
		(connect_pads yes
			(clearance 0)
		)
		(min_thickness 0.0254)
		(filled_areas_thickness no)
		(fill yes
			(thermal_gap 0.5)
			(thermal_bridge_width 0.5)
			(island_removal_mode 1)
			(island_area_min 10)
		)
		(polygon
			(pts
				(xy 154.8815 162.548) (xy 154.901469 162.485134) (xy 154.927921 162.453156) (xy 154.965332 162.424642)
				(xy 155.012527 162.402118) (xy 155.070167 162.386907) (xy 155.070798 162.386798) (xy 154.819 162.109)
				(xy 154.567202 162.386798) (xy 154.622635 162.401095) (xy 154.66852 162.422175) (xy 154.706201 162.44954)
				(xy 154.733434 162.480448) (xy 154.750472 162.513735) (xy 154.756489 162.546566) (xy 154.7565 162.548)
			)
		)
	)
	(zone
		(net 748)
		(net_name "Net-(U45C-AMUXA)")
		(layer "F.Cu")
		(name "$teardrop_padvia$")
		(hatch none 0.1)
		(priority 31701)
		(attr
			(teardrop
				(type padvia)
			)
		)
		(connect_pads yes
			(clearance 0)
		)
		(min_thickness 0.0254)
		(filled_areas_thickness no)
		(fill yes
			(thermal_gap 0.5)
			(thermal_bridge_width 0.5)
			(island_removal_mode 1)
			(island_area_min 10)
		)
		(polygon
			(pts
				(xy 129.6775 129.739323) (xy 129.672682 129.808763) (xy 129.65896 129.860087) (xy 129.612245 129.935628)
				(xy 129.602702 129.947768) (xy 129.552919 130.014997) (xy 129.74 130.141) (xy 129.927081 130.014997)
				(xy 129.877299 129.947769) (xy 129.822894 129.864603) (xy 129.80781 129.811748) (xy 129.8025 129.739323)
			)
		)
	)
	(zone
		(net 969)
		(net_name "/M.2 key M #1/M2_3V3")
		(layer "F.Cu")
		(hatch edge 0.5)
		(priority 26)
		(connect_pads yes
			(clearance 0.15)
		)
		(min_thickness 0.25)
		(filled_areas_thickness no)
		(fill yes
			(thermal_gap 0.2)
			(thermal_bridge_width 0.5)
			(smoothing fillet)
			(radius 0.2)
		)
		(polygon
			(pts
				(xy 178.75 109.66) (xy 177.599999 109.66) (xy 177.599999 111.61) (xy 178.75 111.61)
			)
		)
	)
	(zone
		(net 1)
		(net_name "GND")
		(layer "F.Cu")
		(name "$teardrop_padvia$")
		(hatch none 0.1)
		(priority 31212)
		(attr
			(teardrop
				(type padvia)
			)
		)
		(connect_pads yes
			(clearance 0)
		)
		(min_thickness 0.0254)
		(filled_areas_thickness no)
		(fill yes
			(thermal_gap 0.5)
			(thermal_bridge_width 0.5)
			(island_removal_mode 1)
			(island_area_min 10)
		)
		(polygon
			(pts
				(xy 205.425 151.899323) (xy 205.42028 151.968646) (xy 205.407244 152.021549) (xy 205.355344 152.114135)
				(xy 205.303541 152.197636) (xy 205.5 152.301) (xy 205.707644 152.224641) (xy 205.675418 152.144142)
				(xy 205.639035 152.042683) (xy 205.625 151.899323)
			)
		)
	)
	(zone
		(net 80)
		(net_name "Net-(Q6-D)")
		(layer "F.Cu")
		(name "$teardrop_padvia$")
		(hatch none 0.1)
		(priority 31181)
		(attr
			(teardrop
				(type padvia)
			)
		)
		(connect_pads yes
			(clearance 0)
		)
		(min_thickness 0.0254)
		(filled_areas_thickness no)
		(fill yes
			(thermal_gap 0.5)
			(thermal_bridge_width 0.5)
			(island_removal_mode 1)
			(island_area_min 10)
		)
		(polygon
			(pts
				(xy 261.2 91.1) (xy 261.201041 91.117067) (xy 261.202052 91.147854) (xy 261.19301 91.177992) (xy 261.163349 91.200901)
				(xy 261.1025 91.21) (xy 261.35 91.486) (xy 261.5975 91.21) (xy 261.551135 91.205377) (xy 261.521618 91.193013)
				(xy 261.49926 91.157975) (xy 261.498959 91.117067) (xy 261.5 91.1)
			)
		)
	)
	(zone
		(net 188)
		(net_name "/OCuLink/PCIe_{x4}.RX1+")
		(layer "F.Cu")
		(name "$teardrop_padvia$")
		(hatch none 0.1)
		(priority 32081)
		(attr
			(teardrop
				(type padvia)
			)
		)
		(connect_pads yes
			(clearance 0)
		)
		(min_thickness 0.0254)
		(filled_areas_thickness no)
		(fill yes
			(thermal_gap 0.5)
			(thermal_bridge_width 0.5)
			(island_removal_mode 1)
			(island_area_min 10)
		)
		(polygon
			(pts
				(xy 97.899 150.375) (xy 97.906198 150.395648) (xy 97.915792 150.427984) (xy 97.908965 150.442007)
				(xy 97.8875 150.451995) (xy 98 150.701) (xy 98.1125 150.451995) (xy 98.091324 150.442271) (xy 98.084269 150.428643)
				(xy 98.093802 150.395648) (xy 98.101 150.375)
			)
		)
	)
	(zone
		(net 536)
		(net_name "Net-(Q3-D)")
		(layer "F.Cu")
		(name "$teardrop_padvia$")
		(hatch none 0.1)
		(priority 30841)
		(attr
			(teardrop
				(type padvia)
			)
		)
		(connect_pads yes
			(clearance 0)
		)
		(min_thickness 0.0254)
		(filled_areas_thickness no)
		(fill yes
			(thermal_gap 0.5)
			(thermal_bridge_width 0.5)
			(island_removal_mode 1)
			(island_area_min 10)
		)
		(polygon
			(pts
				(xy 292.12 96.598) (xy 292.12621 96.551789) (xy 292.149677 96.50339) (xy 292.177584 96.475034) (xy 292.21781 96.451988)
				(xy 292.271798 96.436798) (xy 292.02 96.159) (xy 291.768202 96.436798) (xy 291.817054 96.449931)
				(xy 291.854564 96.469335) (xy 291.901987 96.521945) (xy 291.919743 96.588446) (xy 291.92 96.598)
			)
		)
	)
	(zone
		(net 433)
		(net_name "/2xSFP+/10GKR_SFP0.RX-")
		(layer "F.Cu")
		(name "$teardrop_padvia$")
		(hatch none 0.1)
		(priority 31565)
		(attr
			(teardrop
				(type padvia)
			)
		)
		(connect_pads yes
			(clearance 0)
		)
		(min_thickness 0.0254)
		(filled_areas_thickness no)
		(fill yes
			(thermal_gap 0.5)
			(thermal_bridge_width 0.5)
			(island_removal_mode 1)
			(island_area_min 10)
		)
		(polygon
			(pts
				(xy 197.960042 159.21) (xy 197.78421 159.213027) (xy 197.605115 159.214323) (xy 197.599 159.435)
				(xy 197.787081 159.560003) (xy 197.827016 159.478503) (xy 197.845329 159.436246) (xy 197.868931 159.40176)
				(xy 197.904833 159.378519) (xy 197.960042 159.37)
			)
		)
	)
	(zone
		(net 1)
		(net_name "GND")
		(layer "F.Cu")
		(name "$teardrop_padvia$")
		(hatch none 0.1)
		(priority 31991)
		(attr
			(teardrop
				(type padvia)
			)
		)
		(connect_pads yes
			(clearance 0)
		)
		(min_thickness 0.0254)
		(filled_areas_thickness no)
		(fill yes
			(thermal_gap 0.5)
			(thermal_bridge_width 0.5)
			(island_removal_mode 1)
			(island_area_min 10)
		)
		(polygon
			(pts
				(xy 307.9565 82.852) (xy 307.945563 82.890823) (xy 307.923805 82.905933) (xy 307.884 82.912) (xy 308.019 83.288)
				(xy 308.154 82.912) (xy 308.118719 82.907483) (xy 308.097203 82.895862) (xy 308.082005 82.863039)
				(xy 308.0815 82.852)
			)
		)
	)
	(zone
		(net 126)
		(net_name "/2xUSB3.0+RJ45/P2_D+")
		(layer "F.Cu")
		(name "$teardrop_padvia$")
		(hatch none 0.1)
		(priority 30452)
		(attr
			(teardrop
				(type padvia)
			)
		)
		(connect_pads yes
			(clearance 0)
		)
		(min_thickness 0.0254)
		(filled_areas_thickness no)
		(fill yes
			(thermal_gap 0.5)
			(thermal_bridge_width 0.5)
			(island_removal_mode 1)
			(island_area_min 10)
		)
		(polygon
			(pts
				(xy 129.236343 116.3825) (xy 129.263065 116.406971) (xy 129.283083 116.439077) (xy 129.305852 116.533989)
				(xy 129.305 116.696839) (xy 129.601 116.6) (xy 129.634492 116.28) (xy 129.514069 116.290401) (xy 129.38215 116.266354)
				(xy 129.255208 116.209723) (xy 129.236343 116.1975)
			)
		)
	)
	(zone
		(net 1)
		(net_name "GND")
		(layer "F.Cu")
		(name "$teardrop_padvia$")
		(hatch none 0.1)
		(priority 30801)
		(attr
			(teardrop
				(type padvia)
			)
		)
		(connect_pads yes
			(clearance 0)
		)
		(min_thickness 0.0254)
		(filled_areas_thickness no)
		(fill yes
			(thermal_gap 0.5)
			(thermal_bridge_width 0.5)
			(island_removal_mode 1)
			(island_area_min 10)
		)
		(polygon
			(pts
				(xy 225.577255 160.210613) (xy 225.460933 160.317131) (xy 225.360488 160.377242) (xy 225.318879 160.394742)
				(xy 225.399293 160.600707) (xy 225.605257 160.68112) (xy 225.648854 160.588899) (xy 225.710126 160.506107)
				(xy 225.789387 160.422745)
			)
		)
	)
	(zone
		(net 1)
		(net_name "GND")
		(layer "F.Cu")
		(name "$teardrop_padvia$")
		(hatch none 0.1)
		(priority 30874)
		(attr
			(teardrop
				(type padvia)
			)
		)
		(connect_pads yes
			(clearance 0)
		)
		(min_thickness 0.0254)
		(filled_areas_thickness no)
		(fill yes
			(thermal_gap 0.5)
			(thermal_bridge_width 0.5)
			(island_removal_mode 1)
			(island_area_min 10)
		)
		(polygon
			(pts
				(xy 190.80861 78.045163) (xy 190.814382 78.004426) (xy 190.834786 77.962511) (xy 190.861961 77.93421)
				(xy 190.901507 77.910781) (xy 190.97411 77.89151) (xy 190.70861 77.631163) (xy 190.44311 77.89151)
				(xy 190.496252 77.903377) (xy 190.537291 77.921825) (xy 190.588992 77.972499) (xy 190.608328 78.036068)
				(xy 190.60861 78.045163)
			)
		)
	)
	(zone
		(net 76)
		(net_name "Net-(C63-Pad2)")
		(layer "F.Cu")
		(hatch edge 0.5)
		(priority 1)
		(connect_pads yes
			(clearance 0.15)
		)
		(min_thickness 0.25)
		(filled_areas_thickness no)
		(fill yes
			(thermal_gap 0.2)
			(thermal_bridge_width 0.5)
			(smoothing fillet)
			(radius 0.2)
		)
		(polygon
			(pts
				(xy 310.8005 128.76) (xy 310.8005 132.36) (xy 310.1755 132.985) (xy 310.1755 133.735) (xy 309.3505 134.56)
				(xy 309.3505 136.91) (xy 309.0505 137.21) (xy 304.7505 137.21) (xy 304.7505 134.5445) (xy 306.014849 134.5445)
				(xy 308.098433 132.422008) (xy 308.098822 129.661678) (xy 309.3005 128.46) (xy 310.5005 128.46)
			)
		)
	)
	(zone
		(net 545)
		(net_name "Net-(Q11-G)")
		(layer "F.Cu")
		(name "$teardrop_padvia$")
		(hatch none 0.1)
		(priority 30323)
		(attr
			(teardrop
				(type padvia)
			)
		)
		(connect_pads yes
			(clearance 0)
		)
		(min_thickness 0.0254)
		(filled_areas_thickness no)
		(fill yes
			(thermal_gap 0.5)
			(thermal_bridge_width 0.5)
			(island_removal_mode 1)
			(island_area_min 10)
		)
		(polygon
			(pts
				(xy 253.864 126.2715) (xy 253.915931 126.291545) (xy 253.939051 126.317406) (xy 253.957567 126.353879)
				(xy 253.974 126.4565) (xy 254.475 126.209) (xy 253.974 125.9615) (xy 253.969299 126.019882) (xy 253.956394 126.06718)
				(xy 253.937084 126.103425) (xy 253.913162 126.128668) (xy 253.864 126.1465)
			)
		)
	)
	(zone
		(net 2)
		(net_name "+3V3")
		(layer "F.Cu")
		(name "$teardrop_padvia$")
		(hatch none 0.1)
		(priority 30178)
		(attr
			(teardrop
				(type padvia)
			)
		)
		(connect_pads yes
			(clearance 0)
		)
		(min_thickness 0.0254)
		(filled_areas_thickness no)
		(fill yes
			(thermal_gap 0.5)
			(thermal_bridge_width 0.5)
			(island_removal_mode 1)
			(island_area_min 10)
		)
		(polygon
			(pts
				(xy 138.013691 169.035303) (xy 138.011029 169.013093) (xy 138.018987 168.992377) (xy 138.066541 168.9569)
				(xy 138.176672 168.930991) (xy 138.221229 168.927821) (xy 137.919293 168.439293) (xy 137.618771 168.927821)
				(xy 137.729772 168.950339) (xy 137.833124 169.007639) (xy 137.876577 169.047348) (xy 137.908655 169.089394)
				(xy 137.925303 169.123691)
			)
		)
	)
	(zone
		(net 2)
		(net_name "+3V3")
		(layer "F.Cu")
		(name "$teardrop_padvia$")
		(hatch none 0.1)
		(priority 30308)
		(attr
			(teardrop
				(type padvia)
			)
		)
		(connect_pads yes
			(clearance 0)
		)
		(min_thickness 0.0254)
		(filled_areas_thickness no)
		(fill yes
			(thermal_gap 0.5)
			(thermal_bridge_width 0.5)
			(island_removal_mode 1)
			(island_area_min 10)
		)
		(polygon
			(pts
				(xy 115.838 144.59) (xy 115.787028 144.610463) (xy 115.749217 144.629257) (xy 115.711873 144.637794)
				(xy 115.679423 144.623674) (xy 115.656292 144.5745) (xy 115.399 144.84) (xy 115.656292 145.1055)
				(xy 115.669784 145.069356) (xy 115.687742 145.049384) (xy 115.727141 145.043731) (xy 115.787028 145.069537)
				(xy 115.838 145.09)
			)
		)
	)
	(zone
		(net 589)
		(net_name "/Misc/~{ADDRSEL}")
		(layer "F.Cu")
		(name "$teardrop_padvia$")
		(hatch none 0.1)
		(priority 30983)
		(attr
			(teardrop
				(type padvia)
			)
		)
		(connect_pads yes
			(clearance 0)
		)
		(min_thickness 0.0254)
		(filled_areas_thickness no)
		(fill yes
			(thermal_gap 0.5)
			(thermal_bridge_width 0.5)
			(island_removal_mode 1)
			(island_area_min 10)
		)
		(polygon
			(pts
				(xy 253.1575 82.612999) (xy 253.177469 82.550133) (xy 253.203921 82.518155) (xy 253.241332 82.489641)
				(xy 253.288527 82.467117) (xy 253.346167 82.451906) (xy 253.346798 82.451797) (xy 253.095 82.173999)
				(xy 252.843202 82.451797) (xy 252.898635 82.466094) (xy 252.94452 82.487174) (xy 252.982201 82.514539)
				(xy 253.009434 82.545447) (xy 253.026472 82.578734) (xy 253.032489 82.611565) (xy 253.0325 82.612999)
			)
		)
	)
	(zone
		(net 598)
		(net_name "Net-(U31-~{WC})")
		(layer "F.Cu")
		(name "$teardrop_padvia$")
		(hatch none 0.1)
		(priority 31009)
		(attr
			(teardrop
				(type padvia)
			)
		)
		(connect_pads yes
			(clearance 0)
		)
		(min_thickness 0.0254)
		(filled_areas_thickness no)
		(fill yes
			(thermal_gap 0.5)
			(thermal_bridge_width 0.5)
			(island_removal_mode 1)
			(island_area_min 10)
		)
		(polygon
			(pts
				(xy 238.3125 152.369001) (xy 238.332469 152.306135) (xy 238.358921 152.274157) (xy 238.396332 152.245643)
				(xy 238.443527 152.223119) (xy 238.501167 152.207908) (xy 238.501798 152.207799) (xy 238.25 151.930001)
				(xy 237.998202 152.207799) (xy 238.053635 152.222096) (xy 238.09952 152.243176) (xy 238.137201 152.270541)
				(xy 238.164434 152.301449) (xy 238.181472 152.334736) (xy 238.187489 152.367567) (xy 238.1875 152.369001)
			)
		)
	)
	(zone
		(net 1)
		(net_name "GND")
		(layer "F.Cu")
		(name "$teardrop_padvia$")
		(hatch none 0.1)
		(priority 30879)
		(attr
			(teardrop
				(type padvia)
			)
		)
		(connect_pads yes
			(clearance 0)
		)
		(min_thickness 0.0254)
		(filled_areas_thickness no)
		(fill yes
			(thermal_gap 0.5)
			(thermal_bridge_width 0.5)
			(island_removal_mode 1)
			(island_area_min 10)
		)
		(polygon
			(pts
				(xy 215.057 78.21) (xy 215.097737 78.215772) (xy 215.139652 78.236176) (xy 215.167954 78.263351)
				(xy 215.191382 78.302897) (xy 215.210653 78.3755) (xy 215.471 78.11) (xy 215.210653 77.8445) (xy 215.198786 77.897641)
				(xy 215.180339 77.93868) (xy 215.129665 77.990381) (xy 215.066096 78.009718) (xy 215.057 78.01)
			)
		)
	)
	(zone
		(net 11)
		(net_name "/Com Express 7 Interfaces/PCIe_{B1x2}.TX0-")
		(layer "F.Cu")
		(name "$teardrop_padvia$")
		(hatch none 0.1)
		(priority 31448)
		(attr
			(teardrop
				(type padvia)
			)
		)
		(connect_pads yes
			(clearance 0)
		)
		(min_thickness 0.0254)
		(filled_areas_thickness no)
		(fill yes
			(thermal_gap 0.5)
			(thermal_bridge_width 0.5)
			(island_removal_mode 1)
			(island_area_min 10)
		)
		(polygon
			(pts
				(xy 203.709022 123.876793) (xy 203.834325 123.992236) (xy 203.961089 124.116381) (xy 204.129103 123.972311)
				(xy 204.135641 123.750927) (xy 204.050705 123.762532) (xy 204.030387 123.768123) (xy 203.986287 123.779187)
				(xy 203.943171 123.782073) (xy 203.899031 123.769442) (xy 203.851858 123.733957)
			)
		)
	)
	(zone
		(net 603)
		(net_name "Net-(U37-~{OE1})")
		(layer "F.Cu")
		(name "$teardrop_padvia$")
		(hatch none 0.1)
		(priority 32100)
		(attr
			(teardrop
				(type padvia)
			)
		)
		(connect_pads yes
			(clearance 0)
		)
		(min_thickness 0.0254)
		(filled_areas_thickness no)
		(fill yes
			(thermal_gap 0.5)
			(thermal_bridge_width 0.5)
			(island_removal_mode 1)
			(island_area_min 10)
		)
		(polygon
			(pts
				(xy 213.9405 131.615) (xy 213.939048 131.603203) (xy 213.938871 131.574919) (xy 213.947847 131.562347)
				(xy 213.968 131.553403) (xy 213.878 131.199) (xy 213.788 131.553403) (xy 213.808956 131.563008)
				(xy 213.81763 131.576553) (xy 213.816952 131.603203) (xy 213.8155 131.615)
			)
		)
	)
	(zone
		(net 127)
		(net_name "/USB-C console/FTDI_LED_RX")
		(layer "F.Cu")
		(name "$teardrop_padvia$")
		(hatch none 0.1)
		(priority 31635)
		(attr
			(teardrop
				(type padvia)
			)
		)
		(connect_pads yes
			(clearance 0)
		)
		(min_thickness 0.0254)
		(filled_areas_thickness no)
		(fill yes
			(thermal_gap 0.5)
			(thermal_bridge_width 0.5)
			(island_removal_mode 1)
			(island_area_min 10)
		)
		(polygon
			(pts
				(xy 115.547499 78.205) (xy 115.553021 78.177928) (xy 115.571677 78.152389) (xy 115.598296 78.13622)
				(xy 115.637037 78.126601) (xy 115.664999 78.125) (xy 115.484999 77.724) (xy 115.304999 78.125) (xy 115.350499 78.129613)
				(xy 115.383467 78.1419) (xy 115.417843 78.180055) (xy 115.422499 78.205)
			)
		)
	)
	(zone
		(net 533)
		(net_name "/Com Express 7 MGMT/PSON")
		(layer "F.Cu")
		(name "$teardrop_padvia$")
		(hatch none 0.1)
		(priority 31050)
		(attr
			(teardrop
				(type padvia)
			)
		)
		(connect_pads yes
			(clearance 0)
		)
		(min_thickness 0.0254)
		(filled_areas_thickness no)
		(fill yes
			(thermal_gap 0.5)
			(thermal_bridge_width 0.5)
			(island_removal_mode 1)
			(island_area_min 10)
		)
		(polygon
			(pts
				(xy 243.8625 133.247) (xy 243.882273 133.187588) (xy 243.945547 133.131503) (xy 243.994172 133.109801)
				(xy 244.053532 133.095127) (xy 244.0655 133.093347) (xy 243.8 132.833) (xy 243.5345 133.093347)
				(xy 243.594639 133.106197) (xy 243.644523 133.126131) (xy 243.684642 133.152056) (xy 243.713655 133.181876)
				(xy 243.731146 133.213294) (xy 243.737479 133.245105) (xy 243.7375 133.247)
			)
		)
	)
	(zone
		(net 986)
		(net_name "Net-(D34-C)")
		(layer "F.Cu")
		(name "$teardrop_padvia$")
		(hatch none 0.1)
		(priority 30149)
		(attr
			(teardrop
				(type padvia)
			)
		)
		(connect_pads yes
			(clearance 0)
		)
		(min_thickness 0.0254)
		(filled_areas_thickness no)
		(fill yes
			(thermal_gap 0.5)
			(thermal_bridge_width 0.5)
			(island_removal_mode 1)
			(island_area_min 10)
		)
		(polygon
			(pts
				(xy 195.80861 76.062163) (xy 195.81367 76.028644) (xy 195.829091 75.995738) (xy 195.854873 75.965425)
				(xy 195.891483 75.938919) (xy 195.938658 75.918016) (xy 195.997093 75.90393) (xy 196.06861 75.898184)
				(xy 195.70861 75.501163) (xy 195.34861 75.898184) (xy 195.418681 75.903704) (xy 195.477217 75.917567)
				(xy 195.524564 75.938253) (xy 195.561037 75.964231) (xy 195.58712 75.9942) (xy 195.602852 76.026426)
				(xy 195.60861 76.062163)
			)
		)
	)
	(zone
		(net 1)
		(net_name "GND")
		(layer "F.Cu")
		(name "$teardrop_padvia$")
		(hatch none 0.1)
		(priority 30561)
		(attr
			(teardrop
				(type padvia)
			)
		)
		(connect_pads yes
			(clearance 0)
		)
		(min_thickness 0.0254)
		(filled_areas_thickness no)
		(fill yes
			(thermal_gap 0.5)
			(thermal_bridge_width 0.5)
			(island_removal_mode 1)
			(island_area_min 10)
		)
		(polygon
			(pts
				(xy 222.125 152.07) (xy 222.121667 152.055514) (xy 222.11881 152.02539) (xy 222.130964 152.014349)
				(xy 222.16 152.01) (xy 222.025 151.134) (xy 221.89 152.01) (xy 221.919334 152.014475) (xy 221.931358 152.025801)
				(xy 221.928333 152.055514) (xy 221.925 152.07)
			)
		)
	)
	(zone
		(net 533)
		(net_name "/Com Express 7 MGMT/PSON")
		(layer "F.Cu")
		(name "$teardrop_padvia$")
		(hatch none 0.1)
		(priority 31244)
		(attr
			(teardrop
				(type padvia)
			)
		)
		(connect_pads yes
			(clearance 0)
		)
		(min_thickness 0.0254)
		(filled_areas_thickness no)
		(fill yes
			(thermal_gap 0.5)
			(thermal_bridge_width 0.5)
			(island_removal_mode 1)
			(island_area_min 10)
		)
		(polygon
			(pts
				(xy 303.474323 137.905) (xy 303.550636 137.909712) (xy 303.60836 137.9227) (xy 303.699824 137.966366)
				(xy 303.785059 138.010604) (xy 303.876 137.809) (xy 303.789329 137.605626) (xy 303.704374 137.646753)
				(xy 303.610354 137.688362) (xy 303.551703 137.700581) (xy 303.474323 137.705)
			)
		)
	)
	(zone
		(net 546)
		(net_name "/Com Express 7 MGMT/~{COM7}")
		(layer "F.Cu")
		(name "$teardrop_padvia$")
		(hatch none 0.1)
		(priority 31985)
		(attr
			(teardrop
				(type padvia)
			)
		)
		(connect_pads yes
			(clearance 0)
		)
		(min_thickness 0.0254)
		(filled_areas_thickness no)
		(fill yes
			(thermal_gap 0.5)
			(thermal_bridge_width 0.5)
			(island_removal_mode 1)
			(island_area_min 10)
		)
		(polygon
			(pts
				(xy 249.4065 129.703) (xy 249.395563 129.741823) (xy 249.373805 129.756933) (xy 249.334 129.763)
				(xy 249.469 130.139) (xy 249.604 129.763) (xy 249.568719 129.758483) (xy 249.547203 129.746862)
				(xy 249.532005 129.714039) (xy 249.5315 129.703)
			)
		)
	)
	(zone
		(net 291)
		(net_name "/2xUSB3.0+RJ45/~{GBE0_LINK}")
		(layer "F.Cu")
		(name "$teardrop_padvia$")
		(hatch none 0.1)
		(priority 31700)
		(attr
			(teardrop
				(type padvia)
			)
		)
		(connect_pads yes
			(clearance 0)
		)
		(min_thickness 0.0254)
		(filled_areas_thickness no)
		(fill yes
			(thermal_gap 0.5)
			(thermal_bridge_width 0.5)
			(island_removal_mode 1)
			(island_area_min 10)
		)
		(polygon
			(pts
				(xy 144.5375 152.099323) (xy 144.532682 152.168763) (xy 144.51896 152.220087) (xy 144.472245 152.295628)
				(xy 144.462702 152.307768) (xy 144.412919 152.374997) (xy 144.6 152.501) (xy 144.787081 152.374997)
				(xy 144.737299 152.307769) (xy 144.682894 152.224603) (xy 144.66781 152.171748) (xy 144.6625 152.099323)
			)
		)
	)
	(zone
		(net 527)
		(net_name "/Backplane/GPIO")
		(layer "F.Cu")
		(name "$teardrop_padvia$")
		(hatch none 0.1)
		(priority 32119)
		(attr
			(teardrop
				(type padvia)
			)
		)
		(connect_pads yes
			(clearance 0)
		)
		(min_thickness 0.0254)
		(filled_areas_thickness no)
		(fill yes
			(thermal_gap 0.5)
			(thermal_bridge_width 0.5)
			(island_removal_mode 1)
			(island_area_min 10)
		)
		(polygon
			(pts
				(xy 314.688 164.8955) (xy 314.681678 164.895596) (xy 314.642175 164.890011) (xy 314.623953 164.875078)
				(xy 314.611005 164.8455) (xy 314.362 164.958) (xy 314.611005 165.0705) (xy 314.622121 165.043506)
				(xy 314.637648 165.028405) (xy 314.681678 165.020404) (xy 314.688 165.0205)
			)
		)
	)
	(zone
		(net 873)
		(net_name "Net-(U34-EN)")
		(layer "F.Cu")
		(name "$teardrop_padvia$")
		(hatch none 0.1)
		(priority 30732)
		(attr
			(teardrop
				(type padvia)
			)
		)
		(connect_pads yes
			(clearance 0)
		)
		(min_thickness 0.0254)
		(filled_areas_thickness no)
		(fill yes
			(thermal_gap 0.5)
			(thermal_bridge_width 0.5)
			(island_removal_mode 1)
			(island_area_min 10)
		)
		(polygon
			(pts
				(xy 243.7875 131.2) (xy 243.792821 131.168265) (xy 243.810069 131.135565) (xy 243.836538 131.109374)
				(xy 243.874964 131.088445) (xy 243.91705 131.07705) (xy 243.725 130.559) (xy 243.53295 131.07705)
				(xy 243.577474 131.089409) (xy 243.6116 131.108008) (xy 243.653536 131.158803) (xy 243.6625 131.2)
			)
		)
	)
	(zone
		(net 434)
		(net_name "/Com Express 7 MGMT/~{TYPE1}")
		(layer "F.Cu")
		(name "$teardrop_padvia$")
		(hatch none 0.1)
		(priority 31761)
		(attr
			(teardrop
				(type padvia)
			)
		)
		(connect_pads yes
			(clearance 0)
		)
		(min_thickness 0.0254)
		(filled_areas_thickness no)
		(fill yes
			(thermal_gap 0.5)
			(thermal_bridge_width 0.5)
			(island_removal_mode 1)
			(island_area_min 10)
		)
		(polygon
			(pts
				(xy 249.074323 133.8375) (xy 249.143764 133.842318) (xy 249.195088 133.85604) (xy 249.270629 133.902755)
				(xy 249.282769 133.912299) (xy 249.349997 133.962081) (xy 249.476 133.775) (xy 249.349997 133.587919)
				(xy 249.282768 133.637702) (xy 249.199602 133.692106) (xy 249.146748 133.70719) (xy 249.074323 133.7125)
			)
		)
	)
	(zone
		(net 77)
		(net_name "+5V_AON")
		(layer "F.Cu")
		(name "$teardrop_padvia$")
		(hatch none 0.1)
		(priority 30718)
		(attr
			(teardrop
				(type padvia)
			)
		)
		(connect_pads yes
			(clearance 0)
		)
		(min_thickness 0.0254)
		(filled_areas_thickness no)
		(fill yes
			(thermal_gap 0.5)
			(thermal_bridge_width 0.5)
			(island_removal_mode 1)
			(island_area_min 10)
		)
		(polygon
			(pts
				(xy 303.5395 91.9) (xy 303.544848 91.867909) (xy 303.562282 91.834743) (xy 303.588737 91.808583)
				(xy 303.627163 91.787804) (xy 303.66705 91.77705) (xy 303.475 91.259) (xy 303.28295 91.77705) (xy 303.328153 91.789446)
				(xy 303.362844 91.808095) (xy 303.405426 91.858896) (xy 303.4145 91.9)
			)
		)
	)
	(zone
		(net 757)
		(net_name "Net-(U45B-LOSB)")
		(layer "F.Cu")
		(name "$teardrop_padvia$")
		(hatch none 0.1)
		(priority 31735)
		(attr
			(teardrop
				(type padvia)
			)
		)
		(connect_pads yes
			(clearance 0)
		)
		(min_thickness 0.0254)
		(filled_areas_thickness no)
		(fill yes
			(thermal_gap 0.5)
			(thermal_bridge_width 0.5)
			(island_removal_mode 1)
			(island_area_min 10)
		)
		(polygon
			(pts
				(xy 128.3775 129.739323) (xy 128.372682 129.808763) (xy 128.35896 129.860087) (xy 128.312245 129.935628)
				(xy 128.302702 129.947768) (xy 128.252919 130.014997) (xy 128.44 130.141) (xy 128.627081 130.014997)
				(xy 128.577299 129.947769) (xy 128.522894 129.864603) (xy 128.50781 129.811748) (xy 128.5025 129.739323)
			)
		)
	)
	(zone
		(net 867)
		(net_name "/Backplane/PCIe_{x2}.TX0-")
		(layer "F.Cu")
		(name "$teardrop_padvia$")
		(hatch none 0.1)
		(priority 30282)
		(attr
			(teardrop
				(type padvia)
			)
		)
		(connect_pads yes
			(clearance 0)
		)
		(min_thickness 0.0254)
		(filled_areas_thickness no)
		(fill yes
			(thermal_gap 0.5)
			(thermal_bridge_width 0.5)
			(island_removal_mode 1)
			(island_area_min 10)
		)
		(polygon
			(pts
				(xy 201.8685 150.2) (xy 201.879599 150.373112) (xy 201.894216 150.60051) (xy 201.891181 150.735138)
				(xy 201.875 150.887021) (xy 202.025 151.136) (xy 202.108295 150.26) (xy 202.077864 150.255523) (xy 202.065097 150.244185)
				(xy 202.06742 150.214227) (xy 202.0705 150.2)
			)
		)
	)
	(zone
		(net 953)
		(net_name "/2xSFP+/KR to SFI #2/SFI_R.RX-")
		(layer "F.Cu")
		(name "$teardrop_padvia$")
		(hatch none 0.1)
		(priority 31972)
		(attr
			(teardrop
				(type padvia)
			)
		)
		(connect_pads yes
			(clearance 0)
		)
		(min_thickness 0.0254)
		(filled_areas_thickness no)
		(fill yes
			(thermal_gap 0.5)
			(thermal_bridge_width 0.5)
			(island_removal_mode 1)
			(island_area_min 10)
		)
		(polygon
			(pts
				(xy 131.9 146.739321) (xy 131.957156 146.872485) (xy 131.973682 146.955296) (xy 131.97 147.043457)
				(xy 132.17 147.017) (xy 132.230044 146.786) (xy 132.153465 146.787721) (xy 132.102459 146.777296)
				(xy 132.07741 146.761991) (xy 132.060675 146.740569) (xy 132.06 146.739321)
			)
		)
	)
	(zone
		(net 747)
		(net_name "Net-(U45C-PRBS_{PASS})")
		(layer "F.Cu")
		(name "$teardrop_padvia$")
		(hatch none 0.1)
		(priority 30135)
		(attr
			(teardrop
				(type padvia)
			)
		)
		(connect_pads yes
			(clearance 0)
		)
		(min_thickness 0.0254)
		(filled_areas_thickness no)
		(fill yes
			(thermal_gap 0.5)
			(thermal_bridge_width 0.5)
			(island_removal_mode 1)
			(island_area_min 10)
		)
		(polygon
			(pts
				(xy 131.1025 129.377794) (xy 131.107315 129.295733) (xy 131.121019 129.230388) (xy 131.167576 129.13712)
				(xy 131.235787 129.058657) (xy 131.291942 128.997158) (xy 131.351801 128.918339) (xy 131.04 128.709)
				(xy 130.728199 128.918339) (xy 130.825219 129.038517) (xy 130.844214 129.058658) (xy 130.897366 129.117541)
				(xy 130.939591 129.181624) (xy 130.967449 129.264008) (xy 130.9775 129.377794)
			)
		)
	)
	(zone
		(net 52)
		(net_name "+5V")
		(layer "F.Cu")
		(name "$teardrop_padvia$")
		(hatch none 0.1)
		(priority 30466)
		(attr
			(teardrop
				(type padvia)
			)
		)
		(connect_pads yes
			(clearance 0)
		)
		(min_thickness 0.0254)
		(filled_areas_thickness no)
		(fill yes
			(thermal_gap 0.5)
			(thermal_bridge_width 0.5)
			(island_removal_mode 1)
			(island_area_min 10)
		)
		(polygon
			(pts
				(xy 263.060708 76.198) (xy 263.06037 76.18113) (xy 263.060949 76.136174) (xy 263.072767 76.088831)
				(xy 263.107346 76.046427) (xy 263.176208 76.016291) (xy 262.910708 75.759) (xy 262.645208 76.016291)
				(xy 262.689977 76.031848) (xy 262.721593 76.052565) (xy 262.754327 76.103701) (xy 262.761046 76.18113)
				(xy 262.760708 76.198)
			)
		)
	)
	(zone
		(net 2)
		(net_name "+3V3")
		(layer "F.Cu")
		(name "$teardrop_padvia$")
		(hatch none 0.1)
		(priority 30225)
		(attr
			(teardrop
				(type padvia)
			)
		)
		(connect_pads yes
			(clearance 0)
		)
		(min_thickness 0.0254)
		(filled_areas_thickness no)
		(fill yes
			(thermal_gap 0.5)
			(thermal_bridge_width 0.5)
			(island_removal_mode 1)
			(island_area_min 10)
		)
		(polygon
			(pts
				(xy 259.467708 78.573) (xy 259.498316 78.56465) (xy 259.551301 78.554039) (xy 259.574433 78.567044)
				(xy 259.590899 78.603) (xy 260.283708 78.423) (xy 259.590899 78.243) (xy 259.578965 78.272959) (xy 259.562644 78.288272)
				(xy 259.52497 78.290108) (xy 259.498316 78.28135) (xy 259.467708 78.273)
			)
		)
	)
	(zone
		(net 1)
		(net_name "GND")
		(layer "F.Cu")
		(name "$teardrop_padvia$")
		(hatch none 0.1)
		(priority 31519)
		(attr
			(teardrop
				(type padvia)
			)
		)
		(connect_pads yes
			(clearance 0)
		)
		(min_thickness 0.0254)
		(filled_areas_thickness no)
		(fill yes
			(thermal_gap 0.5)
			(thermal_bridge_width 0.5)
			(island_removal_mode 1)
			(island_area_min 10)
		)
		(polygon
			(pts
				(xy 230.425 157.871811) (xy 230.429429 157.959924) (xy 230.440434 158.026159) (xy 230.453216 158.076953)
				(xy 230.479323 158.217287) (xy 230.7 158.201) (xy 230.825003 158.012919) (xy 230.754706 157.98351)
				(xy 230.731837 157.977712) (xy 230.690896 157.966406) (xy 230.656865 157.949331) (xy 230.633611 157.919971)
				(xy 230.625 157.871811)
			)
		)
	)
	(zone
		(net 1)
		(net_name "GND")
		(layer "F.Cu")
		(name "$teardrop_padvia$")
		(hatch none 0.1)
		(priority 31304)
		(attr
			(teardrop
				(type padvia)
			)
		)
		(connect_pads yes
			(clearance 0)
		)
		(min_thickness 0.0254)
		(filled_areas_thickness no)
		(fill yes
			(thermal_gap 0.5)
			(thermal_bridge_width 0.5)
			(island_removal_mode 1)
			(island_area_min 10)
		)
		(polygon
			(pts
				(xy 112.579323 132.51) (xy 112.661742 132.514716) (xy 112.723451 132.527728) (xy 112.813097 132.565944)
				(xy 112.897397 132.604643) (xy 112.981 132.4) (xy 112.886705 132.199785) (xy 112.801625 132.246274)
				(xy 112.71159 132.291638) (xy 112.654667 132.305106) (xy 112.579323 132.31)
			)
		)
	)
	(zone
		(net 1)
		(net_name "GND")
		(layer "F.Cu")
		(hatch edge 0.5)
		(priority 26)
		(connect_pads yes
			(clearance 0.15)
		)
		(min_thickness 0.25)
		(filled_areas_thickness no)
		(fill yes
			(thermal_gap 0.2)
			(thermal_bridge_width 0.5)
			(smoothing fillet)
			(radius 0.2)
		)
		(polygon
			(pts
				(xy 177.45 94.61) (xy 176.299999 94.61) (xy 176.3 98.11) (xy 177.45 98.11)
			)
		)
	)
	(zone
		(net 2)
		(net_name "+3V3")
		(layer "F.Cu")
		(name "$teardrop_padvia$")
		(hatch none 0.1)
		(priority 30330)
		(attr
			(teardrop
				(type padvia)
			)
		)
		(connect_pads yes
			(clearance 0)
		)
		(min_thickness 0.0254)
		(filled_areas_thickness no)
		(fill yes
			(thermal_gap 0.5)
			(thermal_bridge_width 0.5)
			(island_removal_mode 1)
			(island_area_min 10)
		)
		(polygon
			(pts
				(xy 239.436956 78.275534) (xy 239.387698 78.217229) (xy 239.34466 78.139147) (xy 239.32569 78.078329)
				(xy 239.317256 78.009194) (xy 239.320001 77.949442) (xy 238.999294 78.019293) (xy 238.932074 78.315)
				(xy 239.071603 78.312426) (xy 239.189476 78.344815) (xy 239.283476 78.40551) (xy 239.295534 78.416956)
			)
		)
	)
	(zone
		(net 703)
		(net_name "Net-(U24-GPIO3)")
		(layer "F.Cu")
		(name "$teardrop_padvia$")
		(hatch none 0.1)
		(priority 31750)
		(attr
			(teardrop
				(type padvia)
			)
		)
		(connect_pads yes
			(clearance 0)
		)
		(min_thickness 0.0254)
		(filled_areas_thickness no)
		(fill yes
			(thermal_gap 0.5)
			(thermal_bridge_width 0.5)
			(island_removal_mode 1)
			(island_area_min 10)
		)
		(polygon
			(pts
				(xy 261.499323 85.162499) (xy 261.568764 85.167317) (xy 261.620088 85.181039) (xy 261.695629 85.227754)
				(xy 261.707769 85.237298) (xy 261.774997 85.28708) (xy 261.901 85.099999) (xy 261.774997 84.912918)
				(xy 261.707768 84.962701) (xy 261.624602 85.017105) (xy 261.571748 85.032189) (xy 261.499323 85.037499)
			)
		)
	)
	(zone
		(net 1)
		(net_name "GND")
		(layer "F.Cu")
		(name "$teardrop_padvia$")
		(hatch none 0.1)
		(priority 30768)
		(attr
			(teardrop
				(type padvia)
			)
		)
		(connect_pads yes
			(clearance 0)
		)
		(min_thickness 0.0254)
		(filled_areas_thickness no)
		(fill yes
			(thermal_gap 0.5)
			(thermal_bridge_width 0.5)
			(island_removal_mode 1)
			(island_area_min 10)
		)
		(polygon
			(pts
				(xy 248.365708 76.160677) (xy 248.37264 76.0031) (xy 248.401164 75.889565) (xy 248.418208 75.847778)
				(xy 248.215708 75.759) (xy 248.013208 75.847778) (xy 248.047591 75.943822) (xy 248.062809 76.045702)
				(xy 248.065708 76.160677)
			)
		)
	)
	(zone
		(net 197)
		(net_name "/OCuLink/PCIe_{x4}.RX3-")
		(layer "F.Cu")
		(name "$teardrop_padvia$")
		(hatch none 0.1)
		(priority 31352)
		(attr
			(teardrop
				(type padvia)
			)
		)
		(connect_pads yes
			(clearance 0)
		)
		(min_thickness 0.0254)
		(filled_areas_thickness no)
		(fill yes
			(thermal_gap 0.5)
			(thermal_bridge_width 0.5)
			(island_removal_mode 1)
			(island_area_min 10)
		)
		(polygon
			(pts
				(xy 99.392496 158.0545) (xy 99.34571 158.049765) (xy 99.310258 158.036621) (xy 99.26206 157.991613)
				(xy 99.237884 157.953392) (xy 99.210514 157.910225) (xy 99.173852 157.868268) (xy 99.024 158.0315)
				(xy 99.04486 158.252177) (xy 99.145531 158.247548) (xy 99.228897 158.25098) (xy 99.230964 158.251105)
				(xy 99.392496 158.2565)
			)
		)
	)
	(zone
		(net 738)
		(net_name "Net-(U43B-LS_OK_{IN_B})")
		(layer "F.Cu")
		(name "$teardrop_padvia$")
		(hatch none 0.1)
		(priority 31690)
		(attr
			(teardrop
				(type padvia)
			)
		)
		(connect_pads yes
			(clearance 0)
		)
		(min_thickness 0.0254)
		(filled_areas_thickness no)
		(fill yes
			(thermal_gap 0.5)
			(thermal_bridge_width 0.5)
			(island_removal_mode 1)
			(island_area_min 10)
		)
		(polygon
			(pts
				(xy 145.8875 130.109323) (xy 145.882682 130.178763) (xy 145.86896 130.230087) (xy 145.822245 130.305628)
				(xy 145.812702 130.317768) (xy 145.762919 130.384997) (xy 145.95 130.511) (xy 146.137081 130.384997)
				(xy 146.087299 130.317769) (xy 146.032894 130.234603) (xy 146.01781 130.181748) (xy 146.0125 130.109323)
			)
		)
	)
	(zone
		(net 205)
		(net_name "/Backplane/PCIe_{REF}.CK-")
		(layer "F.Cu")
		(name "$teardrop_padvia$")
		(hatch none 0.1)
		(priority 30417)
		(attr
			(teardrop
				(type padvia)
			)
		)
		(connect_pads yes
			(clearance 0)
		)
		(min_thickness 0.0254)
		(filled_areas_thickness no)
		(fill yes
			(thermal_gap 0.5)
			(thermal_bridge_width 0.5)
			(island_removal_mode 1)
			(island_area_min 10)
		)
		(polygon
			(pts
				(xy 216.7755 133.965521) (xy 216.798758 133.937939) (xy 216.829996 133.917276) (xy 216.921915 133.894401)
				(xy 217.078914 133.895) (xy 216.98 133.599) (xy 216.66 133.568245) (xy 216.669439 133.683376) (xy 216.644667 133.811715)
				(xy 216.586792 133.943281) (xy 216.5735 133.965521)
			)
		)
	)
	(zone
		(net 623)
		(net_name "/PCIe redriver/TX_EQ0")
		(layer "F.Cu")
		(name "$teardrop_padvia$")
		(hatch none 0.1)
		(priority 31863)
		(attr
			(teardrop
				(type padvia)
			)
		)
		(connect_pads yes
			(clearance 0)
		)
		(min_thickness 0.0254)
		(filled_areas_thickness no)
		(fill yes
			(thermal_gap 0.5)
			(thermal_bridge_width 0.5)
			(island_removal_mode 1)
			(island_area_min 10)
		)
		(polygon
			(pts
				(xy 111.522485 148.170873) (xy 111.568181 148.223382) (xy 111.594768 148.269376) (xy 111.615152 148.355825)
				(xy 111.616988 148.371158) (xy 111.629323 148.453895) (xy 111.850707 148.410707) (xy 111.893895 148.189323)
				(xy 111.811158 148.176988) (xy 111.71388 148.156651) (xy 111.66584 148.129943) (xy 111.610873 148.082485)
			)
		)
	)
	(zone
		(net 1)
		(net_name "GND")
		(layer "F.Cu")
		(name "$teardrop_padvia$")
		(hatch none 0.1)
		(priority 30776)
		(attr
			(teardrop
				(type padvia)
			)
		)
		(connect_pads yes
			(clearance 0)
		)
		(min_thickness 0.0254)
		(filled_areas_thickness no)
		(fill yes
			(thermal_gap 0.5)
			(thermal_bridge_width 0.5)
			(island_removal_mode 1)
			(island_area_min 10)
		)
		(polygon
			(pts
				(xy 243.392745 127.099387) (xy 243.509071 126.992864) (xy 243.609522 126.932752) (xy 243.65112 126.915257)
				(xy 243.570707 126.709293) (xy 243.364742 126.628879) (xy 243.321141 126.721105) (xy 243.259861 126.803905)
				(xy 243.180613 126.887255)
			)
		)
	)
	(zone
		(net 2)
		(net_name "+3V3")
		(layer "F.Cu")
		(name "$teardrop_padvia$")
		(hatch none 0.1)
		(priority 31007)
		(attr
			(teardrop
				(type padvia)
			)
		)
		(connect_pads yes
			(clearance 0)
		)
		(min_thickness 0.0254)
		(filled_areas_thickness no)
		(fill yes
			(thermal_gap 0.5)
			(thermal_bridge_width 0.5)
			(island_removal_mode 1)
			(island_area_min 10)
		)
		(polygon
			(pts
				(xy 177.912 103.4525) (xy 177.974866 103.472469) (xy 178.006844 103.498921) (xy 178.035358 103.536332)
				(xy 178.057882 103.583527) (xy 178.073093 103.641167) (xy 178.073202 103.641798) (xy 178.351 103.39)
				(xy 178.073202 103.138202) (xy 178.058905 103.193635) (xy 178.037825 103.23952) (xy 178.01046 103.277201)
				(xy 177.979552 103.304434) (xy 177.946265 103.321472) (xy 177.913434 103.327489) (xy 177.912 103.3275)
			)
		)
	)
	(zone
		(net 873)
		(net_name "Net-(U34-EN)")
		(layer "F.Cu")
		(name "$teardrop_padvia$")
		(hatch none 0.1)
		(priority 31099)
		(attr
			(teardrop
				(type padvia)
			)
		)
		(connect_pads yes
			(clearance 0)
		)
		(min_thickness 0.0254)
		(filled_areas_thickness no)
		(fill yes
			(thermal_gap 0.5)
			(thermal_bridge_width 0.5)
			(island_removal_mode 1)
			(island_area_min 10)
		)
		(polygon
			(pts
				(xy 243.7375 131.461) (xy 243.717727 131.520412) (xy 243.654453 131.576496) (xy 243.605828 131.598198)
				(xy 243.546469 131.612872) (xy 243.5345 131.614652) (xy 243.8 131.875) (xy 244.0655 131.614652)
				(xy 244.005362 131.601803) (xy 243.955478 131.581869) (xy 243.915358 131.555944) (xy 243.886345 131.526124)
				(xy 243.868854 131.494706) (xy 243.862521 131.462895) (xy 243.8625 131.461)
			)
		)
	)
	(zone
		(net 936)
		(net_name "Net-(D14-C)")
		(layer "F.Cu")
		(name "$teardrop_padvia$")
		(hatch none 0.1)
		(priority 30069)
		(attr
			(teardrop
				(type padvia)
			)
		)
		(connect_pads yes
			(clearance 0)
		)
		(min_thickness 0.0254)
		(filled_areas_thickness no)
		(fill yes
			(thermal_gap 0.5)
			(thermal_bridge_width 0.5)
			(island_removal_mode 1)
			(island_area_min 10)
		)
		(polygon
			(pts
				(xy 283.907376 75.458987) (xy 283.858972 75.38335) (xy 283.831545 75.265171) (xy 283.836341 75.104513)
				(xy 283.86 74.990883) (xy 283.359293 74.999293) (xy 283.250883 75.4) (xy 283.3801 75.402425) (xy 283.500173 75.415035)
				(xy 283.600002 75.435583) (xy 283.688033 75.46477) (xy 283.753367 75.49715) (xy 283.807034 75.5361)
				(xy 283.818987 75.547376)
			)
		)
	)
	(zone
		(net 671)
		(net_name "/2xSFP+/KR to SFI #2/MDC_R")
		(layer "F.Cu")
		(name "$teardrop_padvia$")
		(hatch none 0.1)
		(priority 30347)
		(attr
			(teardrop
				(type padvia)
			)
		)
		(connect_pads yes
			(clearance 0)
		)
		(min_thickness 0.0254)
		(filled_areas_thickness no)
		(fill yes
			(thermal_gap 0.5)
			(thermal_bridge_width 0.5)
			(island_removal_mode 1)
			(island_area_min 10)
		)
		(polygon
			(pts
				(xy 123.6705 146.297) (xy 123.664719 146.330863) (xy 123.644254 146.365486) (xy 123.617188 146.387307)
				(xy 123.577849 146.403) (xy 123.562289 146.406289) (xy 123.733 147.113) (xy 123.903711 146.406289)
				(xy 123.86349 146.3947) (xy 123.834017 146.377116) (xy 123.800827 146.329533) (xy 123.7955 146.297)
			)
		)
	)
	(zone
		(net 344)
		(net_name "/Com Express 7 MGMT/SER0.TX")
		(layer "F.Cu")
		(name "$teardrop_padvia$")
		(hatch none 0.1)
		(priority 31860)
		(attr
			(teardrop
				(type padvia)
			)
		)
		(connect_pads yes
			(clearance 0)
		)
		(min_thickness 0.0254)
		(filled_areas_thickness no)
		(fill yes
			(thermal_gap 0.5)
			(thermal_bridge_width 0.5)
			(island_removal_mode 1)
			(island_area_min 10)
		)
		(polygon
			(pts
				(xy 163.472485 105.660873) (xy 163.518181 105.713382) (xy 163.544768 105.759376) (xy 163.565152 105.845825)
				(xy 163.566988 105.861158) (xy 163.579323 105.943895) (xy 163.800707 105.900707) (xy 163.843895 105.679323)
				(xy 163.761158 105.666988) (xy 163.66388 105.646651) (xy 163.61584 105.619943) (xy 163.560873 105.572485)
			)
		)
	)
	(zone
		(net 73)
		(net_name "+3V3_AON")
		(layer "F.Cu")
		(name "$teardrop_padvia$")
		(hatch none 0.1)
		(priority 30834)
		(attr
			(teardrop
				(type padvia)
			)
		)
		(connect_pads yes
			(clearance 0)
		)
		(min_thickness 0.0254)
		(filled_areas_thickness no)
		(fill yes
			(thermal_gap 0.5)
			(thermal_bridge_width 0.5)
			(island_removal_mode 1)
			(island_area_min 10)
		)
		(polygon
			(pts
				(xy 250.617 131.802153) (xy 250.612294 131.743678) (xy 250.599352 131.695187) (xy 250.552548 131.61617)
				(xy 250.50486 131.565483) (xy 250.452928 131.509266) (xy 250.414814 131.43988) (xy 250.205 131.509)
				(xy 250.114147 131.711226) (xy 250.176744 131.723145) (xy 250.198769 131.724103) (xy 250.280281 131.736345)
				(xy 250.306925 131.759201) (xy 250.317 131.802153)
			)
		)
	)
	(zone
		(net 400)
		(net_name "/Com Express 7 MGMT/FAN_PWM")
		(layer "F.Cu")
		(name "$teardrop_padvia$")
		(hatch none 0.1)
		(priority 31102)
		(attr
			(teardrop
				(type padvia)
			)
		)
		(connect_pads yes
			(clearance 0)
		)
		(min_thickness 0.0254)
		(filled_areas_thickness no)
		(fill yes
			(thermal_gap 0.5)
			(thermal_bridge_width 0.5)
			(island_removal_mode 1)
			(island_area_min 10)
		)
		(polygon
			(pts
				(xy 239.9375 77.607) (xy 239.917727 77.666412) (xy 239.854453 77.722496) (xy 239.805828 77.744198)
				(xy 239.746469 77.758872) (xy 239.7345 77.760652) (xy 240 78.021) (xy 240.2655 77.760652) (xy 240.205362 77.747803)
				(xy 240.155478 77.727869) (xy 240.115358 77.701944) (xy 240.086345 77.672124) (xy 240.068854 77.640706)
				(xy 240.062521 77.608895) (xy 240.0625 77.607)
			)
		)
	)
	(zone
		(net 1)
		(net_name "GND")
		(layer "F.Cu")
		(name "$teardrop_padvia$")
		(hatch none 0.1)
		(priority 31758)
		(attr
			(teardrop
				(type padvia)
			)
		)
		(connect_pads yes
			(clearance 0)
		)
		(min_thickness 0.0254)
		(filled_areas_thickness no)
		(fill yes
			(thermal_gap 0.5)
			(thermal_bridge_width 0.5)
			(island_removal_mode 1)
			(island_area_min 10)
		)
		(polygon
			(pts
				(xy 112.489323 149.9425) (xy 112.558764 149.947318) (xy 112.610088 149.96104) (xy 112.685629 150.007755)
				(xy 112.697769 150.017299) (xy 112.764997 150.067081) (xy 112.891 149.88) (xy 112.764997 149.692919)
				(xy 112.697768 149.742702) (xy 112.614602 149.797106) (xy 112.561748 149.81219) (xy 112.489323 149.8175)
			)
		)
	)
	(zone
		(net 2)
		(net_name "+3V3")
		(layer "F.Cu")
		(name "$teardrop_padvia$")
		(hatch none 0.1)
		(priority 31674)
		(attr
			(teardrop
				(type padvia)
			)
		)
		(connect_pads yes
			(clearance 0)
		)
		(min_thickness 0.0254)
		(filled_areas_thickness no)
		(fill yes
			(thermal_gap 0.5)
			(thermal_bridge_width 0.5)
			(island_removal_mode 1)
			(island_area_min 10)
		)
		(polygon
			(pts
				(xy 262.043715 93.781672) (xy 262.083773 93.73507) (xy 262.108739 93.692581) (xy 262.134031 93.603732)
				(xy 262.149879 93.537355) (xy 262.18708 93.462003) (xy 262.000706 93.336293) (xy 261.812918 93.462003)
				(xy 261.87115 93.521761) (xy 261.905221 93.547685) (xy 261.947678 93.580854) (xy 261.976625 93.614176)
				(xy 261.982397 93.650652) (xy 261.955328 93.693285)
			)
		)
	)
	(zone
		(net 187)
		(net_name "/OCuLink/PCIe_{x4}.RX0-")
		(layer "F.Cu")
		(name "$teardrop_padvia$")
		(hatch none 0.1)
		(priority 32086)
		(attr
			(teardrop
				(type padvia)
			)
		)
		(connect_pads yes
			(clearance 0)
		)
		(min_thickness 0.0254)
		(filled_areas_thickness no)
		(fill yes
			(thermal_gap 0.5)
			(thermal_bridge_width 0.5)
			(island_removal_mode 1)
			(island_area_min 10)
		)
		(polygon
			(pts
				(xy 96.901 150.375) (xy 96.908198 150.395648) (xy 96.917792 150.427984) (xy 96.910965 150.442007)
				(xy 96.8895 150.451995) (xy 97.002 150.701) (xy 97.1145 150.451995) (xy 97.093324 150.442271) (xy 97.086269 150.428643)
				(xy 97.095802 150.395648) (xy 97.103 150.375)
			)
		)
	)
	(zone
		(net 349)
		(net_name "Net-(J12D-LPC_AD0{slash}ESPI_IO_0)")
		(layer "F.Cu")
		(name "$teardrop_padvia$")
		(hatch none 0.1)
		(priority 30661)
		(attr
			(teardrop
				(type padvia)
			)
		)
		(connect_pads yes
			(clearance 0)
		)
		(min_thickness 0.0254)
		(filled_areas_thickness no)
		(fill yes
			(thermal_gap 0.5)
			(thermal_bridge_width 0.5)
			(island_removal_mode 1)
			(island_area_min 10)
		)
		(polygon
			(pts
				(xy 177.5875 164.07) (xy 177.598438 164.031177) (xy 177.620195 164.016067) (xy 177.66 164.01) (xy 177.525 163.134)
				(xy 177.39 164.01) (xy 177.425281 164.014517) (xy 177.446797 164.026138) (xy 177.461995 164.058961)
				(xy 177.4625 164.07)
			)
		)
	)
	(zone
		(net 696)
		(net_name "/2xUSB3.0+RJ45/DD_FL-")
		(layer "F.Cu")
		(name "$teardrop_padvia$")
		(hatch none 0.1)
		(priority 31915)
		(attr
			(teardrop
				(type padvia)
			)
		)
		(connect_pads yes
			(clearance 0)
		)
		(min_thickness 0.0254)
		(filled_areas_thickness no)
		(fill yes
			(thermal_gap 0.5)
			(thermal_bridge_width 0.5)
			(island_removal_mode 1)
			(island_area_min 10)
		)
		(polygon
			(pts
				(xy 130.28395 101.51) (xy 130.41119 101.487646) (xy 130.546305 101.46159) (xy 130.708188 101.455)
				(xy 130.746 101.315) (xy 130.32 101.295457) (xy 130.320803 101.334429) (xy 130.31205 101.353082)
				(xy 130.288332 101.359795) (xy 130.28395 101.36)
			)
		)
	)
	(zone
		(net 354)
		(net_name "Net-(J12D-~{LPC_DRQ1}{slash}~{ESPI_ALERT1})")
		(layer "F.Cu")
		(name "$teardrop_padvia$")
		(hatch none 0.1)
		(priority 31839)
		(attr
			(teardrop
				(type padvia)
			)
		)
		(connect_pads yes
			(clearance 0)
		)
		(min_thickness 0.0254)
		(filled_areas_thickness no)
		(fill yes
			(thermal_gap 0.5)
			(thermal_bridge_width 0.5)
			(island_removal_mode 1)
			(island_area_min 10)
		)
		(polygon
			(pts
				(xy 179.839127 165.372485) (xy 179.786618 165.418181) (xy 179.740623 165.444768) (xy 179.654174 165.465152)
				(xy 179.638841 165.466988) (xy 179.556105 165.479323) (xy 179.599293 165.700707) (xy 179.820677 165.743895)
				(xy 179.833011 165.66116) (xy 179.853349 165.563881) (xy 179.880057 165.515841) (xy 179.927515 165.460873)
			)
		)
	)
	(zone
		(net 357)
		(net_name "/Com Express 7 MGMT/SMBus.SCL")
		(layer "F.Cu")
		(name "$teardrop_padvia$")
		(hatch none 0.1)
		(priority 31886)
		(attr
			(teardrop
				(type padvia)
			)
		)
		(connect_pads yes
			(clearance 0)
		)
		(min_thickness 0.0254)
		(filled_areas_thickness no)
		(fill yes
			(thermal_gap 0.5)
			(thermal_bridge_width 0.5)
			(island_removal_mode 1)
			(island_area_min 10)
		)
		(polygon
			(pts
				(xy 121.427515 152.964127) (xy 121.381819 152.911618) (xy 121.355231 152.865623) (xy 121.334847 152.779175)
				(xy 121.333011 152.76384) (xy 121.320677 152.681105) (xy 121.099293 152.724293) (xy 121.056105 152.945677)
				(xy 121.13884 152.958011) (xy 121.236119 152.978349) (xy 121.284159 153.005057) (xy 121.339127 153.052515)
			)
		)
	)
	(zone
		(net 84)
		(net_name "/Com Express 7 MGMT/PWRBTN")
		(layer "F.Cu")
		(name "$teardrop_padvia$")
		(hatch none 0.1)
		(priority 31026)
		(attr
			(teardrop
				(type padvia)
			)
		)
		(connect_pads yes
			(clearance 0)
		)
		(min_thickness 0.0254)
		(filled_areas_thickness no)
		(fill yes
			(thermal_gap 0.5)
			(thermal_bridge_width 0.5)
			(island_removal_mode 1)
			(island_area_min 10)
		)
		(polygon
			(pts
				(xy 246.788 128.727501) (xy 246.725135 128.707532) (xy 246.693157 128.68108) (xy 246.664642 128.643669)
				(xy 246.642118 128.596474) (xy 246.626907 128.538834) (xy 246.626798 128.538202) (xy 246.349001 128.79)
				(xy 246.626798 129.041798) (xy 246.641095 128.986365) (xy 246.662175 128.94048) (xy 246.68954 128.902799)
				(xy 246.720448 128.875566) (xy 246.753735 128.858528) (xy 246.786565 128.852511) (xy 246.787999 128.8525)
			)
		)
	)
	(zone
		(net 669)
		(net_name "/2xSFP+/KR to SFI #2/MDIO_R")
		(layer "F.Cu")
		(name "$teardrop_padvia$")
		(hatch none 0.1)
		(priority 31524)
		(attr
			(teardrop
				(type padvia)
			)
		)
		(connect_pads yes
			(clearance 0)
		)
		(min_thickness 0.0254)
		(filled_areas_thickness no)
		(fill yes
			(thermal_gap 0.5)
			(thermal_bridge_width 0.5)
			(island_removal_mode 1)
			(island_area_min 10)
		)
		(polygon
			(pts
				(xy 123.365001 144.103386) (xy 123.38626 144.106614) (xy 123.404389 144.119669) (xy 123.432618 144.178716)
				(xy 123.446228 144.278946) (xy 123.730707 144.049293) (xy 123.46692 143.790086) (xy 123.437108 143.886576)
				(xy 123.376052 143.966054) (xy 123.337266 143.994396) (xy 123.298217 144.011091) (xy 123.276614 144.014999)
			)
		)
	)
	(zone
		(net 2)
		(net_name "+3V3")
		(layer "F.Cu")
		(name "$teardrop_padvia$")
		(hatch none 0.1)
		(priority 30862)
		(attr
			(teardrop
				(type padvia)
			)
		)
		(connect_pads yes
			(clearance 0)
		)
		(min_thickness 0.0254)
		(filled_areas_thickness no)
		(fill yes
			(thermal_gap 0.5)
			(thermal_bridge_width 0.5)
			(island_removal_mode 1)
			(island_area_min 10)
		)
		(polygon
			(pts
				(xy 259.080792 78.273) (xy 258.951062 78.288925) (xy 258.875538 78.313956) (xy 258.809639 78.335767)
				(xy 258.735249 78.344323) (xy 258.729708 78.565) (xy 258.888636 78.719155) (xy 258.929488 78.666356)
				(xy 258.984545 78.601788) (xy 259.024814 78.580878) (xy 259.080792 78.573)
			)
		)
	)
	(zone
		(net 295)
		(net_name "/2xUSB3.0+RJ45/GbE.MDI0+")
		(layer "F.Cu")
		(name "$teardrop_padvia$")
		(hatch none 0.1)
		(priority 31640)
		(attr
			(teardrop
				(type padvia)
			)
		)
		(connect_pads yes
			(clearance 0)
		)
		(min_thickness 0.0254)
		(filled_areas_thickness no)
		(fill yes
			(thermal_gap 0.5)
			(thermal_bridge_width 0.5)
			(island_removal_mode 1)
			(island_area_min 10)
		)
		(polygon
			(pts
				(xy 182.025 167.742084) (xy 182.029756 167.702162) (xy 182.04305 167.673745) (xy 182.087129 167.641329)
				(xy 182.132262 167.62605) (xy 182.178541 167.610756) (xy 182.225003 167.587081) (xy 182.1 167.399)
				(xy 181.879323 167.398242) (xy 181.877203 167.536699) (xy 181.875 167.742084)
			)
		)
	)
	(zone
		(net 1)
		(net_name "GND")
		(layer "F.Cu")
		(name "$teardrop_padvia$")
		(hatch none 0.1)
		(priority 31928)
		(attr
			(teardrop
				(type padvia)
			)
		)
		(connect_pads yes
			(clearance 0)
		)
		(min_thickness 0.0254)
		(filled_areas_thickness no)
		(fill yes
			(thermal_gap 0.5)
			(thermal_bridge_width 0.5)
			(island_removal_mode 1)
			(island_area_min 10)
		)
		(polygon
			(pts
				(xy 314.718 166.91) (xy 314.707885 166.910153) (xy 314.677169 166.90954) (xy 314.64468 166.901218)
				(xy 314.615526 166.877325) (xy 314.594809 166.83) (xy 314.362 167.01) (xy 314.594809 167.19) (xy 314.608168 167.154099)
				(xy 314.626399 167.130801) (xy 314.671725 167.111101) (xy 314.707885 167.109847) (xy 314.718 167.11)
			)
		)
	)
	(zone
		(net 484)
		(net_name "Net-(J12K-10G_PHY_CAP_01)")
		(layer "F.Cu")
		(name "$teardrop_padvia$")
		(hatch none 0.1)
		(priority 31782)
		(attr
			(teardrop
				(type padvia)
			)
		)
		(connect_pads yes
			(clearance 0)
		)
		(min_thickness 0.0254)
		(filled_areas_thickness no)
		(fill yes
			(thermal_gap 0.5)
			(thermal_bridge_width 0.5)
			(island_removal_mode 1)
			(island_area_min 10)
		)
		(polygon
			(pts
				(xy 192.8625 149.600677) (xy 192.867318 149.531236) (xy 192.88104 149.479912) (xy 192.927755 149.40437)
				(xy 192.937299 149.392229) (xy 192.987081 149.325003) (xy 192.8 149.199) (xy 192.612919 149.325003)
				(xy 192.662701 149.392231) (xy 192.717106 149.475397) (xy 192.73219 149.528251) (xy 192.7375 149.600677)
			)
		)
	)
	(zone
		(net 1)
		(net_name "GND")
		(layer "F.Cu")
		(name "$teardrop_padvia$")
		(hatch none 0.1)
		(priority 31229)
		(attr
			(teardrop
				(type padvia)
			)
		)
		(connect_pads yes
			(clearance 0)
		)
		(min_thickness 0.0254)
		(filled_areas_thickness no)
		(fill yes
			(thermal_gap 0.5)
			(thermal_bridge_width 0.5)
			(island_removal_mode 1)
			(island_area_min 10)
		)
		(polygon
			(pts
				(xy 215.125 167.900677) (xy 215.129737 167.809676) (xy 215.142896 167.742587) (xy 215.175418 167.655855)
				(xy 215.207644 167.575358) (xy 215 167.499) (xy 214.803541 167.602363) (xy 214.855343 167.685863)
				(xy 214.904833 167.771955) (xy 214.919614 167.82716) (xy 214.925 167.900677)
			)
		)
	)
	(zone
		(net 612)
		(net_name "/PCIe misc/DIF0-")
		(layer "F.Cu")
		(name "$teardrop_padvia$")
		(hatch none 0.1)
		(priority 30437)
		(attr
			(teardrop
				(type padvia)
			)
		)
		(connect_pads yes
			(clearance 0)
		)
		(min_thickness 0.0254)
		(filled_areas_thickness no)
		(fill yes
			(thermal_gap 0.5)
			(thermal_bridge_width 0.5)
			(island_removal_mode 1)
			(island_area_min 10)
		)
		(polygon
			(pts
				(xy 210.225521 128.4135) (xy 210.147272 128.455459) (xy 210.048716 128.491472) (xy 209.971841 128.50683)
				(xy 209.891576 128.509442) (xy 209.828246 128.5) (xy 209.859 128.82) (xy 210.155 128.918914) (xy 210.152186 128.794529)
				(xy 210.164709 128.703642) (xy 210.181698 128.66161) (xy 210.20655 128.629964) (xy 210.225521 128.6155)
			)
		)
	)
	(zone
		(net 1)
		(net_name "GND")
		(layer "F.Cu")
		(name "$teardrop_padvia$")
		(hatch none 0.1)
		(priority 31939)
		(attr
			(teardrop
				(type padvia)
			)
		)
		(connect_pads yes
			(clearance 0)
		)
		(min_thickness 0.0254)
		(filled_areas_thickness no)
		(fill yes
			(thermal_gap 0.5)
			(thermal_bridge_width 0.5)
			(island_removal_mode 1)
			(island_area_min 10)
		)
		(polygon
			(pts
				(xy 314.78 161.01) (xy 314.790115 161.009847) (xy 314.820832 161.01046) (xy 314.85332 161.018782)
				(xy 314.882475 161.042675) (xy 314.903191 161.09) (xy 315.136 160.91) (xy 314.903191 160.73) (xy 314.889833 160.765901)
				(xy 314.871601 160.789199) (xy 314.826276 160.808899) (xy 314.790115 160.810153) (xy 314.78 160.81)
			)
		)
	)
	(zone
		(net 89)
		(net_name "/Com Express 7 Interfaces/PCIe_{B2Ax4}.RX3-")
		(layer "F.Cu")
		(name "$teardrop_padvia$")
		(hatch none 0.1)
		(priority 31426)
		(attr
			(teardrop
				(type padvia)
			)
		)
		(connect_pads yes
			(clearance 0)
		)
		(min_thickness 0.0254)
		(filled_areas_thickness no)
		(fill yes
			(thermal_gap 0.5)
			(thermal_bridge_width 0.5)
			(island_removal_mode 1)
			(island_area_min 10)
		)
		(polygon
			(pts
				(xy 287.541 75.019852) (xy 287.546395 75.181383) (xy 287.549945 75.265794) (xy 287.545323 75.367488)
				(xy 287.766 75.388348) (xy 287.929231 75.238495) (xy 287.860562 75.184355) (xy 287.844108 75.174464)
				(xy 287.805435 75.149964) (xy 287.773221 75.120457) (xy 287.751173 75.079301) (xy 287.743 75.019852)
			)
		)
	)
	(zone
		(net 121)
		(net_name "/2xSFP+/10GKR_SFP1.TX-")
		(layer "F.Cu")
		(name "$teardrop_padvia$")
		(hatch none 0.1)
		(priority 31566)
		(attr
			(teardrop
				(type padvia)
			)
		)
		(connect_pads yes
			(clearance 0)
		)
		(min_thickness 0.0254)
		(filled_areas_thickness no)
		(fill yes
			(thermal_gap 0.5)
			(thermal_bridge_width 0.5)
			(island_removal_mode 1)
			(island_area_min 10)
		)
		(polygon
			(pts
				(xy 196.885 152.239974) (xy 196.888026 152.415809) (xy 196.889323 152.594889) (xy 197.11 152.601)
				(xy 197.235003 152.412919) (xy 197.153497 152.372984) (xy 197.111243 152.354674) (xy 197.076758 152.331075)
				(xy 197.053519 152.295178) (xy 197.045 152.239974)
			)
		)
	)
	(zone
		(net 432)
		(net_name "/2xSFP+/10GKR_SFP0.RX+")
		(layer "F.Cu")
		(name "$teardrop_padvia$")
		(hatch none 0.1)
		(priority 31564)
		(attr
			(teardrop
				(type padvia)
			)
		)
		(connect_pads yes
			(clearance 0)
		)
		(min_thickness 0.0254)
		(filled_areas_thickness no)
		(fill yes
			(thermal_gap 0.5)
			(thermal_bridge_width 0.5)
			(island_removal_mode 1)
			(island_area_min 10)
		)
		(polygon
			(pts
				(xy 197.960026 158.83) (xy 197.916969 158.825236) (xy 197.885518 158.811888) (xy 197.847099 158.767175)
				(xy 197.827015 158.721501) (xy 197.787081 158.639997) (xy 197.599 158.765) (xy 197.605111 158.985677)
				(xy 197.784193 158.986974) (xy 197.960026 158.99)
			)
		)
	)
	(zone
		(net 720)
		(net_name "Net-(U43C-REFCLK1+)")
		(layer "F.Cu")
		(name "$teardrop_padvia$")
		(hatch none 0.1)
		(priority 31620)
		(attr
			(teardrop
				(type padvia)
			)
		)
		(connect_pads yes
			(clearance 0)
		)
		(min_thickness 0.0254)
		(filled_areas_thickness no)
		(fill yes
			(thermal_gap 0.5)
			(thermal_bridge_width 0.5)
			(island_removal_mode 1)
			(island_area_min 10)
		)
		(polygon
			(pts
				(xy 145.2375 129.772562) (xy 145.232754 129.820603) (xy 145.219534 129.856826) (xy 145.174738 129.904751)
				(xy 145.131452 129.930812) (xy 145.078651 129.962982) (xy 145.027769 130.010146) (xy 145.2 130.151)
				(xy 145.420677 130.106105) (xy 145.393011 129.993898) (xy 145.37128 129.90261) (xy 145.3625 129.772562)
			)
		)
	)
	(zone
		(net 118)
		(net_name "/2xSFP+/KR to SFI #2/REFCLK-")
		(layer "F.Cu")
		(name "$teardrop_padvia$")
		(hatch none 0.1)
		(priority 30636)
		(attr
			(teardrop
				(type padvia)
			)
		)
		(connect_pads yes
			(clearance 0)
		)
		(min_thickness 0.0254)
		(filled_areas_thickness no)
		(fill yes
			(thermal_gap 0.5)
			(thermal_bridge_width 0.5)
			(island_removal_mode 1)
			(island_area_min 10)
		)
		(polygon
			(pts
				(xy 125.683657 141.47) (xy 125.566743 141.525303) (xy 125.491162 141.54403) (xy 125.409242 141.552398)
				(xy 125.285508 141.54) (xy 125.319 141.86) (xy 125.615 141.956839) (xy 125.611699 141.819913) (xy 125.626222 141.716731)
				(xy 125.644263 141.673329) (xy 125.670638 141.640284) (xy 125.683657 141.63)
			)
		)
	)
	(zone
		(net 313)
		(net_name "/2xUSB3.0+RJ45/USB_1.D+")
		(layer "F.Cu")
		(name "$teardrop_padvia$")
		(hatch none 0.1)
		(priority 31549)
		(attr
			(teardrop
				(type padvia)
			)
		)
		(connect_pads yes
			(clearance 0)
		)
		(min_thickness 0.0254)
		(filled_areas_thickness no)
		(fill yes
			(thermal_gap 0.5)
			(thermal_bridge_width 0.5)
			(island_removal_mode 1)
			(island_area_min 10)
		)
		(polygon
			(pts
				(xy 153.2655 123.342084) (xy 153.253901 123.148457) (xy 153.243677 122.998242) (xy 153.023 122.999)
				(xy 152.897997 123.187081) (xy 152.97802 123.223769) (xy 153.017606 123.239158) (xy 153.050215 123.259727)
				(xy 153.072345 123.291895) (xy 153.0805 123.342084)
			)
		)
	)
	(zone
		(net 2)
		(net_name "+3V3")
		(layer "F.Cu")
		(name "$teardrop_padvia$")
		(hatch none 0.1)
		(priority 30147)
		(attr
			(teardrop
				(type padvia)
			)
		)
		(connect_pads yes
			(clearance 0)
		)
		(min_thickness 0.0254)
		(filled_areas_thickness no)
		(fill yes
			(thermal_gap 0.5)
			(thermal_bridge_width 0.5)
			(island_removal_mode 1)
			(island_area_min 10)
		)
		(polygon
			(pts
				(xy 138.002478 156.774091) (xy 138.002913 156.750232) (xy 138.013278 156.728338) (xy 138.065423 156.690023)
				(xy 138.176895 156.662072) (xy 138.231229 156.657821) (xy 137.929293 156.169293) (xy 137.589588 156.631639)
				(xy 137.714277 156.664016) (xy 137.823898 156.729577) (xy 137.866093 156.770924) (xy 137.896407 156.814602)
				(xy 137.914091 156.862478)
			)
		)
	)
	(zone
		(net 65)
		(net_name "+12V")
		(layer "F.Cu")
		(hatch edge 0.5)
		(priority 33)
		(connect_pads yes
			(clearance 0.15)
		)
		(min_thickness 0.25)
		(filled_areas_thickness no)
		(fill yes
			(thermal_gap 0.5)
			(thermal_bridge_width 0.5)
		)
		(polygon
			(pts
				(xy 227.3 157.9) (xy 240.5 157.9) (xy 240.5 162) (xy 227.2 162) (xy 227.2 158)
			)
		)
	)
	(zone
		(net 566)
		(net_name "/2xSFP+/~{LED1_1}")
		(layer "F.Cu")
		(name "$teardrop_padvia$")
		(hatch none 0.1)
		(priority 30504)
		(attr
			(teardrop
				(type padvia)
			)
		)
		(connect_pads yes
			(clearance 0)
		)
		(min_thickness 0.0254)
		(filled_areas_thickness no)
		(fill yes
			(thermal_gap 0.5)
			(thermal_bridge_width 0.5)
			(island_removal_mode 1)
			(island_area_min 10)
		)
		(polygon
			(pts
				(xy 156.080056 161.720556) (xy 156.002239 161.770409) (xy 155.880796 161.798529) (xy 155.806524 161.799743)
				(xy 155.726238 161.790492) (xy 155.723526 161.79) (xy 155.778293 162.110707) (xy 156.074 162.190474)
				(xy 156.070462 162.104034) (xy 156.076546 162.024401) (xy 156.091581 161.951862) (xy 156.114544 161.889048)
				(xy 156.168444 161.808944)
			)
		)
	)
	(zone
		(net 1)
		(net_name "GND")
		(layer "F.Cu")
		(name "$teardrop_padvia$")
		(hatch none 0.1)
		(priority 30778)
		(attr
			(teardrop
				(type padvia)
			)
		)
		(connect_pads yes
			(clearance 0)
		)
		(min_thickness 0.0254)
		(filled_areas_thickness no)
		(fill yes
			(thermal_gap 0.5)
			(thermal_bridge_width 0.5)
			(island_removal_mode 1)
			(island_area_min 10)
		)
		(polygon
			(pts
				(xy 152.969177 83.4095) (xy 152.811606 83.402569) (xy 152.698078 83.374049) (xy 152.656278 83.357)
				(xy 152.5675 83.5595) (xy 152.656278 83.762) (xy 152.752317 83.727618) (xy 152.854189 83.7124) (xy 152.969177 83.7095)
			)
		)
	)
	(zone
		(net 378)
		(net_name "/Com Express 7 Interfaces/USB1.D+")
		(layer "F.Cu")
		(name "$teardrop_padvia$")
		(hatch none 0.1)
		(priority 31500)
		(attr
			(teardrop
				(type padvia)
			)
		)
		(connect_pads yes
			(clearance 0)
		)
		(min_thickness 0.0254)
		(filled_areas_thickness no)
		(fill yes
			(thermal_gap 0.5)
			(thermal_bridge_width 0.5)
			(island_removal_mode 1)
			(island_area_min 10)
		)
		(polygon
			(pts
				(xy 197.773207 164.914679) (xy 197.659885 165.033917) (xy 197.530795 165.163204) (xy 197.677335 165.328749)
				(xy 197.898719 165.332491) (xy 197.885534 165.250181) (xy 197.876363 165.222097) (xy 197.863007 165.178512)
				(xy 197.858163 165.135897) (xy 197.869334 165.092231) (xy 197.904022 165.045494)
			)
		)
	)
	(zone
		(net 304)
		(net_name "Net-(J12D-~{BATLOW})")
		(layer "F.Cu")
		(name "$teardrop_padvia$")
		(hatch none 0.1)
		(priority 30651)
		(attr
			(teardrop
				(type padvia)
			)
		)
		(connect_pads yes
			(clearance 0)
		)
		(min_thickness 0.0254)
		(filled_areas_thickness no)
		(fill yes
			(thermal_gap 0.5)
			(thermal_bridge_width 0.5)
			(island_removal_mode 1)
			(island_area_min 10)
		)
		(polygon
			(pts
				(xy 189.0875 169.62) (xy 189.098438 169.581177) (xy 189.120195 169.566067) (xy 189.16 169.56) (xy 189.025 168.684)
				(xy 188.89 169.56) (xy 188.925281 169.564517) (xy 188.946797 169.576138) (xy 188.961995 169.608961)
				(xy 188.9625 169.62)
			)
		)
	)
	(zone
		(net 638)
		(net_name "Net-(U41-A1)")
		(layer "F.Cu")
		(name "$teardrop_padvia$")
		(hatch none 0.1)
		(priority 30506)
		(attr
			(teardrop
				(type padvia)
			)
		)
		(connect_pads yes
			(clearance 0)
		)
		(min_thickness 0.0254)
		(filled_areas_thickness no)
		(fill yes
			(thermal_gap 0.5)
			(thermal_bridge_width 0.5)
			(island_removal_mode 1)
			(island_area_min 10)
		)
		(polygon
			(pts
				(xy 129.289443 82.541056) (xy 129.23959 82.463239) (xy 129.21147 82.341797) (xy 129.210257 82.267525)
				(xy 129.219508 82.187239) (xy 129.22 82.184527) (xy 128.899293 82.239293) (xy 128.819526 82.535)
				(xy 128.905966 82.531462) (xy 128.985599 82.537546) (xy 129.058138 82.552581) (xy 129.120952 82.575544)
				(xy 129.201055 82.629444)
			)
		)
	)
	(zone
		(net 1)
		(net_name "GND")
		(layer "F.Cu")
		(name "$teardrop_padvia$")
		(hatch none 0.1)
		(priority 30538)
		(attr
			(teardrop
				(type padvia)
			)
		)
		(connect_pads yes
			(clearance 0)
		)
		(min_thickness 0.0254)
		(filled_areas_thickness no)
		(fill yes
			(thermal_gap 0.5)
			(thermal_bridge_width 0.5)
			(island_removal_mode 1)
			(island_area_min 10)
		)
		(polygon
			(pts
				(xy 218.925 150.2) (xy 218.928333 150.214486) (xy 218.93119 150.24461) (xy 218.919036 150.255651)
				(xy 218.89 150.26) (xy 219.025 151.136) (xy 219.16 150.26) (xy 219.130666 150.255525) (xy 219.118642 150.244199)
				(xy 219.121667 150.214486) (xy 219.125 150.2)
			)
		)
	)
	(zone
		(net 73)
		(net_name "+3V3_AON")
		(layer "F.Cu")
		(name "$teardrop_padvia$")
		(hatch none 0.1)
		(priority 31997)
		(attr
			(teardrop
				(type padvia)
			)
		)
		(connect_pads yes
			(clearance 0)
		)
		(min_thickness 0.0254)
		(filled_areas_thickness no)
		(fill yes
			(thermal_gap 0.5)
			(thermal_bridge_width 0.5)
			(island_removal_mode 1)
			(island_area_min 10)
		)
		(polygon
			(pts
				(xy 238.8115 157.271) (xy 238.822438 157.232177) (xy 238.844195 157.217067) (xy 238.884 157.211)
				(xy 238.749 156.86) (xy 238.614 157.211) (xy 238.649281 157.215517) (xy 238.670797 157.227138) (xy 238.685995 157.259961)
				(xy 238.6865 157.271)
			)
		)
	)
	(zone
		(net 108)
		(net_name "/2xSFP+/KR to SFI #1/REFCLK+")
		(layer "F.Cu")
		(name "$teardrop_padvia$")
		(hatch none 0.1)
		(priority 31171)
		(attr
			(teardrop
				(type padvia)
			)
		)
		(connect_pads yes
			(clearance 0)
		)
		(min_thickness 0.0254)
		(filled_areas_thickness no)
		(fill yes
			(thermal_gap 0.5)
			(thermal_bridge_width 0.5)
			(island_removal_mode 1)
			(island_area_min 10)
		)
		(polygon
			(pts
				(xy 145.13321 141.25) (xy 145.197198 141.245347) (xy 145.247878 141.232777) (xy 145.329795 141.188645)
				(xy 145.345383 141.17761) (xy 145.41018 141.136024) (xy 145.498773 141.105196) (xy 145.451 140.86)
				(xy 145.204804 140.811227) (xy 145.202997 140.898185) (xy 145.20811 140.941074) (xy 145.214133 140.998444)
				(xy 145.210007 141.045848) (xy 145.186207 141.078097) (xy 145.13321 141.09)
			)
		)
	)
	(zone
		(net 312)
		(net_name "/2xUSB3.0+RJ45/USB_1.D-")
		(layer "F.Cu")
		(name "$teardrop_padvia$")
		(hatch none 0.1)
		(priority 30455)
		(attr
			(teardrop
				(type padvia)
			)
		)
		(connect_pads yes
			(clearance 0)
		)
		(min_thickness 0.0254)
		(filled_areas_thickness no)
		(fill yes
			(thermal_gap 0.5)
			(thermal_bridge_width 0.5)
			(island_removal_mode 1)
			(island_area_min 10)
		)
		(polygon
			(pts
				(xy 130.960059 118.448) (xy 130.800627 118.511722) (xy 130.703149 118.532836) (xy 130.600857 118.535266)
				(xy 130.564359 118.53) (xy 130.599 118.85) (xy 130.895 118.945963) (xy 130.888127 118.807218) (xy 130.900843 118.708264)
				(xy 130.917615 118.670862) (xy 130.942446 118.643756) (xy 130.960059 118.633)
			)
		)
	)
	(zone
		(net 1)
		(net_name "GND")
		(layer "F.Cu")
		(name "$teardrop_padvia$")
		(hatch none 0.1)
		(priority 31705)
		(attr
			(teardrop
				(type padvia)
			)
		)
		(connect_pads yes
			(clearance 0)
		)
		(min_thickness 0.0254)
		(filled_areas_thickness no)
		(fill yes
			(thermal_gap 0.5)
			(thermal_bridge_width 0.5)
			(island_removal_mode 1)
			(island_area_min 10)
		)
		(polygon
			(pts
				(xy 200.8875 160.574323) (xy 200.882682 160.643763) (xy 200.86896 160.695087) (xy 200.822245 160.770628)
				(xy 200.812702 160.782768) (xy 200.762919 160.849997) (xy 200.95 160.976) (xy 201.137081 160.849997)
				(xy 201.087299 160.782769) (xy 201.032894 160.699603) (xy 201.01781 160.646748) (xy 201.0125 160.574323)
			)
		)
	)
	(zone
		(net 872)
		(net_name "Net-(U34-~{KILL})")
		(layer "F.Cu")
		(name "$teardrop_padvia$")
		(hatch none 0.1)
		(priority 30502)
		(attr
			(teardrop
				(type padvia)
			)
		)
		(connect_pads yes
			(clearance 0)
		)
		(min_thickness 0.0254)
		(filled_areas_thickness no)
		(fill yes
			(thermal_gap 0.5)
			(thermal_bridge_width 0.5)
			(island_removal_mode 1)
			(island_area_min 10)
		)
		(polygon
			(pts
				(xy 245.410556 131.572943) (xy 245.460409 131.65076) (xy 245.488529 131.772203) (xy 245.489743 131.846475)
				(xy 245.480492 131.926761) (xy 245.48 131.929473) (xy 245.800707 131.874706) (xy 245.880474 131.578999)
				(xy 245.794034 131.582537) (xy 245.714401 131.576453) (xy 245.641862 131.561418) (xy 245.579048 131.538455)
				(xy 245.498944 131.484555)
			)
		)
	)
	(zone
		(net 24)
		(net_name "/M.2 key E/~{CLKREQ}")
		(layer "F.Cu")
		(name "$teardrop_padvia$")
		(hatch none 0.1)
		(priority 31127)
		(attr
			(teardrop
				(type padvia)
			)
		)
		(connect_pads yes
			(clearance 0)
		)
		(min_thickness 0.0254)
		(filled_areas_thickness no)
		(fill yes
			(thermal_gap 0.5)
			(thermal_bridge_width 0.5)
			(island_removal_mode 1)
			(island_area_min 10)
		)
		(polygon
			(pts
				(xy 155.257 84.1225) (xy 155.316412 84.142273) (xy 155.372497 84.205547) (xy 155.394199 84.254172)
				(xy 155.408873 84.313531) (xy 155.410653 84.3255) (xy 155.671 84.06) (xy 155.410653 83.7945) (xy 155.397804 83.854638)
				(xy 155.37787 83.904522) (xy 155.351945 83.944641) (xy 155.322125 83.973654) (xy 155.290707 83.991146)
				(xy 155.258896 83.997479) (xy 155.257 83.9975)
			)
		)
	)
	(zone
		(net 526)
		(net_name "/Backplane/~{PRSNT}")
		(layer "F.Cu")
		(name "$teardrop_padvia$")
		(hatch none 0.1)
		(priority 31838)
		(attr
			(teardrop
				(type padvia)
			)
		)
		(connect_pads yes
			(clearance 0)
		)
		(min_thickness 0.0254)
		(filled_areas_thickness no)
		(fill yes
			(thermal_gap 0.5)
			(thermal_bridge_width 0.5)
			(island_removal_mode 1)
			(island_area_min 10)
		)
		(polygon
			(pts
				(xy 310.739127 165.382485) (xy 310.686618 165.428181) (xy 310.640623 165.454768) (xy 310.554174 165.475152)
				(xy 310.538841 165.476988) (xy 310.456105 165.489323) (xy 310.499293 165.710707) (xy 310.720677 165.753895)
				(xy 310.733011 165.67116) (xy 310.753349 165.573881) (xy 310.780057 165.525841) (xy 310.827515 165.470873)
			)
		)
	)
	(zone
		(net 559)
		(net_name "Net-(U5-SCL)")
		(layer "F.Cu")
		(name "$teardrop_padvia$")
		(hatch none 0.1)
		(priority 32045)
		(attr
			(teardrop
				(type padvia)
			)
		)
		(connect_pads yes
			(clearance 0)
		)
		(min_thickness 0.0254)
		(filled_areas_thickness no)
		(fill yes
			(thermal_gap 0.5)
			(thermal_bridge_width 0.5)
			(island_removal_mode 1)
			(island_area_min 10)
		)
		(polygon
			(pts
				(xy 160.571662 158.179951) (xy 160.554078 158.207117) (xy 160.531271 158.242322) (xy 160.496762 158.2595)
				(xy 160.548293 158.672707) (xy 160.669242 158.298082) (xy 160.646194 158.283513) (xy 160.649233 158.274801)
				(xy 160.654662 158.271677) (xy 160.660049 158.268338)
			)
		)
	)
	(zone
		(net 64)
		(net_name "Net-(U19-V_{CC})")
		(layer "F.Cu")
		(name "$teardrop_padvia$")
		(hatch none 0.1)
		(priority 32127)
		(attr
			(teardrop
				(type padvia)
			)
		)
		(connect_pads yes
			(clearance 0)
		)
		(min_thickness 0.0254)
		(filled_areas_thickness no)
		(fill yes
			(thermal_gap 0.5)
			(thermal_bridge_width 0.5)
			(island_removal_mode 1)
			(island_area_min 10)
		)
		(polygon
			(pts
				(xy 311.327499 106.487078) (xy 311.326024 106.469612) (xy 311.325895 106.428167) (xy 311.334882 106.407153)
				(xy 311.354999 106.388011) (xy 311.264999 106.147999) (xy 311.174999 106.388011) (xy 311.194418 106.406155)
				(xy 311.203605 106.42606) (xy 311.203974 106.469612) (xy 311.202499 106.487078)
			)
		)
	)
	(zone
		(net 77)
		(net_name "+5V_AON")
		(layer "F.Cu")
		(hatch edge 0.5)
		(priority 38)
		(connect_pads yes
			(clearance 0.15)
		)
		(min_thickness 0.25)
		(filled_areas_thickness no)
		(fill yes
			(thermal_gap 0.5)
			(thermal_bridge_width 0.5)
		)
		(polygon
			(pts
				(xy 219.2 162) (xy 219.2 159.1) (xy 216.5 159.1) (xy 216.5 161.2) (xy 216.6 161.3) (xy 217.3 161.3)
				(xy 217.4 161.4) (xy 217.4 162)
			)
		)
	)
	(zone
		(net 984)
		(net_name "Net-(D32-C)")
		(layer "F.Cu")
		(name "$teardrop_padvia$")
		(hatch none 0.1)
		(priority 30151)
		(attr
			(teardrop
				(type padvia)
			)
		)
		(connect_pads yes
			(clearance 0)
		)
		(min_thickness 0.0254)
		(filled_areas_thickness no)
		(fill yes
			(thermal_gap 0.5)
			(thermal_bridge_width 0.5)
			(island_removal_mode 1)
			(island_area_min 10)
		)
		(polygon
			(pts
				(xy 193.80861 76.062163) (xy 193.81367 76.028644) (xy 193.829091 75.995738) (xy 193.854873 75.965425)
				(xy 193.891483 75.938919) (xy 193.938658 75.918016) (xy 193.997093 75.90393) (xy 194.06861 75.898184)
				(xy 193.70861 75.501163) (xy 193.34861 75.898184) (xy 193.418681 75.903704) (xy 193.477217 75.917567)
				(xy 193.524564 75.938253) (xy 193.561037 75.964231) (xy 193.58712 75.9942) (xy 193.602852 76.026426)
				(xy 193.60861 76.062163)
			)
		)
	)
	(zone
		(net 666)
		(net_name "/2xSFP+/KR to SFI #1/SFI_R.TX+")
		(layer "F.Cu")
		(name "$teardrop_padvia$")
		(hatch none 0.1)
		(priority 31163)
		(attr
			(teardrop
				(type padvia)
			)
		)
		(connect_pads yes
			(clearance 0)
		)
		(min_thickness 0.0254)
		(filled_areas_thickness no)
		(fill yes
			(thermal_gap 0.5)
			(thermal_bridge_width 0.5)
			(island_removal_mode 1)
			(island_area_min 10)
		)
		(polygon
			(pts
				(xy 147.22 143.17679) (xy 147.224788 143.139695) (xy 147.238304 143.115431) (xy 147.280007 143.096705)
				(xy 147.368927 143.101889) (xy 147.434222 143.108714) (xy 147.498773 143.105196) (xy 147.45 142.859)
				(xy 147.204804 142.811227) (xy 147.168876 142.909201) (xy 147.132391 142.964616) (xy 147.082365 143.048601)
				(xy 147.066125 143.104227) (xy 147.06 143.17679)
			)
		)
	)
	(zone
		(net 323)
		(net_name "/Com Express 7 Interfaces/SDIO.DAT2")
		(layer "F.Cu")
		(name "$teardrop_padvia$")
		(hatch none 0.1)
		(priority 31333)
		(attr
			(teardrop
				(type padvia)
			)
		)
		(connect_pads yes
			(clearance 0)
		)
		(min_thickness 0.0254)
		(filled_areas_thickness no)
		(fill yes
			(thermal_gap 0.5)
			(thermal_bridge_width 0.5)
			(island_removal_mode 1)
			(island_area_min 10)
		)
		(polygon
			(pts
				(xy 208.918974 170.477333) (xy 208.863678 170.525984) (xy 208.815099 170.556335) (xy 208.719972 170.588472)
				(xy 208.61888 170.619741) (xy 208.699293 170.825707) (xy 208.905257 170.906121) (xy 208.936526 170.80503)
				(xy 208.968015 170.711201) (xy 208.998479 170.662039) (xy 209.047667 170.606026)
			)
		)
	)
	(zone
		(net 222)
		(net_name "/Com Express 7 Interfaces/PCIe_{B1x4}.RX0+")
		(layer "F.Cu")
		(name "$teardrop_padvia$")
		(hatch none 0.1)
		(priority 30259)
		(attr
			(teardrop
				(type padvia)
			)
		)
		(connect_pads yes
			(clearance 0)
		)
		(min_thickness 0.0254)
		(filled_areas_thickness no)
		(fill yes
			(thermal_gap 0.5)
			(thermal_bridge_width 0.5)
			(island_removal_mode 1)
			(island_area_min 10)
		)
		(polygon
			(pts
				(xy 209.4795 162.2) (xy 209.48258 162.214227) (xy 209.484749 162.244527) (xy 209.471877 162.255628)
				(xy 209.441705 162.26) (xy 209.525 163.136) (xy 209.675 162.887021) (xy 209.655644 162.645818) (xy 209.670401 162.373112)
				(xy 209.6815 162.2)
			)
		)
	)
	(zone
		(net 220)
		(net_name "/Com Express 7 Interfaces/PCIe_{B1x4}.TX1+")
		(layer "F.Cu")
		(name "$teardrop_padvia$")
		(hatch none 0.1)
		(priority 31624)
		(attr
			(teardrop
				(type padvia)
			)
		)
		(connect_pads yes
			(clearance 0)
		)
		(min_thickness 0.0254)
		(filled_areas_thickness no)
		(fill yes
			(thermal_gap 0.5)
			(thermal_bridge_width 0.5)
			(island_removal_mode 1)
			(island_area_min 10)
		)
		(polygon
			(pts
				(xy 207.914716 165.3185) (xy 207.857944 165.323246) (xy 207.813244 165.336466) (xy 207.748833 165.382154)
				(xy 207.707397 165.432252) (xy 207.662992 165.486204) (xy 207.602882 165.537026) (xy 207.724214 165.725214)
				(xy 207.945891 165.681319) (xy 207.911091 165.605713) (xy 207.88321 165.545969) (xy 207.888162 165.527388)
				(xy 207.914716 165.5205)
			)
		)
	)
	(zone
		(net 663)
		(net_name "Net-(U43C-ST)")
		(layer "F.Cu")
		(name "$teardrop_padvia$")
		(hatch none 0.1)
		(priority 31471)
		(attr
			(teardrop
				(type padvia)
			)
		)
		(connect_pads yes
			(clearance 0)
		)
		(min_thickness 0.0254)
		(filled_areas_thickness no)
		(fill yes
			(thermal_gap 0.5)
			(thermal_bridge_width 0.5)
			(island_removal_mode 1)
			(island_area_min 10)
		)
		(polygon
			(pts
				(xy 145.091005 139.589393) (xy 145.137948 139.643133) (xy 145.166167 139.690646) (xy 145.188018 139.777796)
				(xy 145.191163 139.808454) (xy 145.204804 139.908773) (xy 145.450707 139.860707) (xy 145.498773 139.614804)
				(xy 145.398454 139.601163) (xy 145.292344 139.581075) (xy 145.239517 139.552515) (xy 145.179393 139.501005)
			)
		)
	)
	(zone
		(net 56)
		(net_name "/USB-C console/USB_D-")
		(layer "F.Cu")
		(name "$teardrop_padvia$")
		(hatch none 0.1)
		(priority 30211)
		(attr
			(teardrop
				(type padvia)
			)
		)
		(connect_pads yes
			(clearance 0)
		)
		(min_thickness 0.0254)
		(filled_areas_thickness no)
		(fill yes
			(thermal_gap 0.5)
			(thermal_bridge_width 0.5)
			(island_removal_mode 1)
			(island_area_min 10)
		)
		(polygon
			(pts
				(xy 106.82874 79.330555) (xy 106.873026 79.382461) (xy 106.913608 79.4481) (xy 106.943882 79.518081)
				(xy 106.966082 79.598791) (xy 106.979 79.731838) (xy 107.279707 79.650707) (xy 107.360838 79.35)
				(xy 107.204698 79.331961) (xy 107.071092 79.281442) (xy 106.965252 79.205327) (xy 106.959555 79.19974)
			)
		)
	)
	(zone
		(net 1)
		(net_name "GND")
		(layer "F.Cu")
		(name "$teardrop_padvia$")
		(hatch none 0.1)
		(priority 31211)
		(attr
			(teardrop
				(type padvia)
			)
		)
		(connect_pads yes
			(clearance 0)
		)
		(min_thickness 0.0254)
		(filled_areas_thickness no)
		(fill yes
			(thermal_gap 0.5)
			(thermal_bridge_width 0.5)
			(island_removal_mode 1)
			(island_area_min 10)
		)
		(polygon
			(pts
				(xy 221.925 157.399323) (xy 221.92028 157.468646) (xy 221.907244 157.521549) (xy 221.855344 157.614135)
				(xy 221.803541 157.697636) (xy 222 157.801) (xy 222.207644 157.724641) (xy 222.175418 157.644142)
				(xy 222.139035 157.542683) (xy 222.125 157.399323)
			)
		)
	)
	(zone
		(net 73)
		(net_name "+3V3_AON")
		(layer "F.Cu")
		(name "$teardrop_padvia$")
		(hatch none 0.1)
		(priority 30307)
		(attr
			(teardrop
				(type padvia)
			)
		)
		(connect_pads yes
			(clearance 0)
		)
		(min_thickness 0.0254)
		(filled_areas_thickness no)
		(fill yes
			(thermal_gap 0.5)
			(thermal_bridge_width 0.5)
			(island_removal_mode 1)
			(island_area_min 10)
		)
		(polygon
			(pts
				(xy 301.078 129.84) (xy 301.029725 129.859603) (xy 300.993127 129.877914) (xy 300.957143 129.885852)
				(xy 300.926336 129.870889) (xy 300.905266 129.820496) (xy 300.639 130.08) (xy 300.88771 130.351234)
				(xy 300.902219 130.316396) (xy 300.92089 130.29709) (xy 300.961752 130.29176) (xy 301.02431 130.3186)
				(xy 301.078 130.34)
			)
		)
	)
	(zone
		(net 365)
		(net_name "/Com Express 7 MGMT/PWR_OK")
		(layer "F.Cu")
		(name "$teardrop_padvia$")
		(hatch none 0.1)
		(priority 31755)
		(attr
			(teardrop
				(type padvia)
			)
		)
		(connect_pads yes
			(clearance 0)
		)
		(min_thickness 0.0254)
		(filled_areas_thickness no)
		(fill yes
			(thermal_gap 0.5)
			(thermal_bridge_width 0.5)
			(island_removal_mode 1)
			(island_area_min 10)
		)
		(polygon
			(pts
				(xy 209.149323 114.2125) (xy 209.218764 114.217318) (xy 209.270088 114.23104) (xy 209.345629 114.277755)
				(xy 209.357769 114.287299) (xy 209.424997 114.337081) (xy 209.551 114.15) (xy 209.424997 113.962919)
				(xy 209.357768 114.012702) (xy 209.274602 114.067106) (xy 209.221748 114.08219) (xy 209.149323 114.0875)
			)
		)
	)
	(zone
		(net 375)
		(net_name "/2xUSB3.0+RJ45/USB_2.D+")
		(layer "F.Cu")
		(name "$teardrop_padvia$")
		(hatch none 0.1)
		(priority 31486)
		(attr
			(teardrop
				(type padvia)
			)
		)
		(connect_pads yes
			(clearance 0)
		)
		(min_thickness 0.0254)
		(filled_areas_thickness no)
		(fill yes
			(thermal_gap 0.5)
			(thermal_bridge_width 0.5)
			(island_removal_mode 1)
			(island_area_min 10)
		)
		(polygon
			(pts
				(xy 132.745494 115.954022) (xy 132.780391 115.925828) (xy 132.813324 115.911532) (xy 132.875816 115.912371)
				(xy 132.922097 115.926363) (xy 132.97407 115.94205) (xy 133.032492 115.948719) (xy 133.028749 115.727335)
				(xy 132.863204 115.580795) (xy 132.733917 115.709885) (xy 132.614679 115.823207)
			)
		)
	)
	(zone
		(net 142)
		(net_name "/2xSFP+/PHY0_{RESET}")
		(layer "F.Cu")
		(name "$teardrop_padvia$")
		(hatch none 0.1)
		(priority 31744)
		(attr
			(teardrop
				(type padvia)
			)
		)
		(connect_pads yes
			(clearance 0)
		)
		(min_thickness 0.0254)
		(filled_areas_thickness no)
		(fill yes
			(thermal_gap 0.5)
			(thermal_bridge_width 0.5)
			(island_removal_mode 1)
			(island_area_min 10)
		)
		(polygon
			(pts
				(xy 160.649323 153.2625) (xy 160.718764 153.267318) (xy 160.770088 153.28104) (xy 160.845629 153.327755)
				(xy 160.857769 153.337299) (xy 160.924997 153.387081) (xy 161.051 153.2) (xy 160.924997 153.012919)
				(xy 160.857768 153.062702) (xy 160.774602 153.117106) (xy 160.721748 153.13219) (xy 160.649323 153.1375)
			)
		)
	)
	(zone
		(net 1)
		(net_name "GND")
		(layer "F.Cu")
		(name "$teardrop_padvia$")
		(hatch none 0.1)
		(priority 30617)
		(attr
			(teardrop
				(type padvia)
			)
		)
		(connect_pads yes
			(clearance 0)
		)
		(min_thickness 0.0254)
		(filled_areas_thickness no)
		(fill yes
			(thermal_gap 0.5)
			(thermal_bridge_width 0.5)
			(island_removal_mode 1)
			(island_area_min 10)
		)
		(polygon
			(pts
				(xy 194.425 162.2) (xy 194.428333 162.214486) (xy 194.43119 162.24461) (xy 194.419036 162.255651)
				(xy 194.39 162.26) (xy 194.525 163.136) (xy 194.66 162.26) (xy 194.630666 162.255525) (xy 194.618642 162.244199)
				(xy 194.621667 162.214486) (xy 194.625 162.2)
			)
		)
	)
	(zone
		(net 55)
		(net_name "/USB-C console/USB_D+")
		(layer "F.Cu")
		(name "$teardrop_padvia$")
		(hatch none 0.1)
		(priority 30427)
		(attr
			(teardrop
				(type padvia)
			)
		)
		(connect_pads yes
			(clearance 0)
		)
		(min_thickness 0.0254)
		(filled_areas_thickness no)
		(fill yes
			(thermal_gap 0.5)
			(thermal_bridge_width 0.5)
			(island_removal_mode 1)
			(island_area_min 10)
		)
		(polygon
			(pts
				(xy 109.384721 75.7285) (xy 109.501002 75.698636) (xy 109.648676 75.660447) (xy 109.727448 75.649877)
				(xy 109.807182 75.651) (xy 109.757999 75.356) (xy 109.436999 75.264893) (xy 109.451006 75.382454)
				(xy 109.4477 75.467705) (xy 109.435686 75.505626) (xy 109.4154 75.530737) (xy 109.384721 75.5435)
			)
		)
	)
	(zone
		(net 93)
		(net_name "/Com Express 7 Interfaces/PCIe_{B2Ax4}.RX3+")
		(layer "F.Cu")
		(name "$teardrop_padvia$")
		(hatch none 0.1)
		(priority 31345)
		(attr
			(teardrop
				(type padvia)
			)
		)
		(connect_pads yes
			(clearance 0)
		)
		(min_thickness 0.0254)
		(filled_areas_thickness no)
		(fill yes
			(thermal_gap 0.5)
			(thermal_bridge_width 0.5)
			(island_removal_mode 1)
			(island_area_min 10)
		)
		(polygon
			(pts
				(xy 215.9795 164.332504) (xy 215.974765 164.37929) (xy 215.961621 164.414742) (xy 215.916613 164.462939)
				(xy 215.878393 164.487115) (xy 215.835226 164.514484) (xy 215.793268 164.551147) (xy 215.9565 164.701)
				(xy 216.177177 164.68014) (xy 216.172548 164.579469) (xy 216.17598 164.496102) (xy 216.176105 164.494035)
				(xy 216.1815 164.332504)
			)
		)
	)
	(zone
		(net 44)
		(net_name "/2xUSB3.0+RJ45/USBSS_1.TX+")
		(layer "F.Cu")
		(name "$teardrop_padvia$")
		(hatch none 0.1)
		(priority 31481)
		(attr
			(teardrop
				(type padvia)
			)
		)
		(connect_pads yes
			(clearance 0)
		)
		(min_thickness 0.0254)
		(filled_areas_thickness no)
		(fill yes
			(thermal_gap 0.5)
			(thermal_bridge_width 0.5)
			(island_removal_mode 1)
			(island_area_min 10)
		)
		(polygon
			(pts
				(xy 180.5575 149.909584) (xy 180.56224 149.864972) (xy 180.575418 149.831575) (xy 180.620201 149.78798)
				(xy 180.66282 149.765148) (xy 180.710662 149.73949) (xy 180.756688 149.702895) (xy 180.5975 149.549)
				(xy 180.376823 149.562437) (xy 180.376683 149.745139) (xy 180.3725 149.909584)
			)
		)
	)
	(zone
		(net 425)
		(net_name "/2xSFP+/I2C_{SFP0}.SDA")
		(layer "F.Cu")
		(name "$teardrop_padvia$")
		(hatch none 0.1)
		(priority 30706)
		(attr
			(teardrop
				(type padvia)
			)
		)
		(connect_pads yes
			(clearance 0)
		)
		(min_thickness 0.0254)
		(filled_areas_thickness no)
		(fill yes
			(thermal_gap 0.5)
			(thermal_bridge_width 0.5)
			(island_removal_mode 1)
			(island_area_min 10)
		)
		(polygon
			(pts
				(xy 194.9625 155.75) (xy 194.951563 155.788823) (xy 194.929805 155.803933) (xy 194.89 155.81) (xy 195.025 156.686)
				(xy 195.16 155.81) (xy 195.124719 155.805483) (xy 195.103203 155.793862) (xy 195.088005 155.761039)
				(xy 195.0875 155.75)
			)
		)
	)
	(zone
		(net 593)
		(net_name "Net-(U24-V_{CCP})")
		(layer "F.Cu")
		(name "$teardrop_padvia$")
		(hatch none 0.1)
		(priority 30715)
		(attr
			(teardrop
				(type padvia)
			)
		)
		(connect_pads yes
			(clearance 0)
		)
		(min_thickness 0.0254)
		(filled_areas_thickness no)
		(fill yes
			(thermal_gap 0.5)
			(thermal_bridge_width 0.5)
			(island_removal_mode 1)
			(island_area_min 10)
		)
		(polygon
			(pts
				(xy 254.056 89.009999) (xy 254.060806 89.00997) (xy 254.08628 89.011149) (xy 254.112048 89.020737)
				(xy 254.131993 89.047198) (xy 254.14 89.098999) (xy 254.701 88.91) (xy 254.14 88.720999) (xy 254.13542 88.762301)
				(xy 254.123361 88.788368) (xy 254.088848 88.808426) (xy 254.060806 88.810028) (xy 254.056 88.809999)
			)
		)
	)
	(zone
		(net 76)
		(net_name "Net-(C63-Pad2)")
		(layer "F.Cu")
		(name "$teardrop_padvia$")
		(hatch none 0.1)
		(priority 31545)
		(attr
			(teardrop
				(type padvia)
			)
		)
		(connect_pads yes
			(clearance 0)
		)
		(min_thickness 0.0254)
		(filled_areas_thickness no)
		(fill yes
			(thermal_gap 0.5)
			(thermal_bridge_width 0.5)
			(island_removal_mode 1)
			(island_area_min 10)
		)
		(polygon
			(pts
				(xy 313.089287 137.384599) (xy 313.130889 137.311801) (xy 313.169798 137.274252) (xy 313.218631 137.242614)
				(xy 313.267195 137.222992) (xy 313.321312 137.212501) (xy 313.076206 136.939293) (xy 312.846553 137.223772)
				(xy 312.924903 137.232522) (xy 312.976234 137.24937) (xy 312.996311 137.266033) (xy 313.00253 137.286308)
				(xy 313.0009 137.296212)
			)
		)
	)
	(zone
		(net 66)
		(net_name "Net-(U18-BST)")
		(layer "F.Cu")
		(name "$teardrop_padvia$")
		(hatch none 0.1)
		(priority 32140)
		(attr
			(teardrop
				(type padvia)
			)
		)
		(connect_pads yes
			(clearance 0)
		)
		(min_thickness 0.0254)
		(filled_areas_thickness no)
		(fill yes
			(thermal_gap 0.5)
			(thermal_bridge_width 0.5)
			(island_removal_mode 1)
			(island_area_min 10)
		)
		(polygon
			(pts
				(xy 313.453078 121.399499) (xy 313.434859 121.40104) (xy 313.392335 121.401334) (xy 313.370632 121.392494)
				(xy 313.350639 121.372602) (xy 313.113999 121.463999) (xy 313.357476 121.552564) (xy 313.374853 121.532883)
				(xy 313.394153 121.523573) (xy 313.436352 121.523084) (xy 313.453078 121.524499)
			)
		)
	)
	(zone
		(net 1)
		(net_name "GND")
		(layer "F.Cu")
		(name "$teardrop_padvia$")
		(hatch none 0.1)
		(priority 30773)
		(attr
			(teardrop
				(type padvia)
			)
		)
		(connect_pads yes
			(clearance 0)
		)
		(min_thickness 0.0254)
		(filled_areas_thickness no)
		(fill yes
			(thermal_gap 0.5)
			(thermal_bridge_width 0.5)
			(island_removal_mode 1)
			(island_area_min 10)
		)
		(polygon
			(pts
				(xy 234.640708 76.160677) (xy 234.64764 76.0031) (xy 234.676164 75.889565) (xy 234.693208 75.847778)
				(xy 234.490708 75.759) (xy 234.288208 75.847778) (xy 234.322591 75.943822) (xy 234.337809 76.045702)
				(xy 234.340708 76.160677)
			)
		)
	)
	(zone
		(net 1)
		(net_name "GND")
		(layer "F.Cu")
		(name "$teardrop_padvia$")
		(hatch none 0.1)
		(priority 31241)
		(attr
			(teardrop
				(type padvia)
			)
		)
		(connect_pads yes
			(clearance 0)
		)
		(min_thickness 0.0254)
		(filled_areas_thickness no)
		(fill yes
			(thermal_gap 0.5)
			(thermal_bridge_width 0.5)
			(island_removal_mode 1)
			(island_area_min 10)
		)
		(polygon
			(pts
				(xy 216.925 163.899323) (xy 216.920263 163.990322) (xy 216.907104 164.057411) (xy 216.874583 164.144139)
				(xy 216.842355 164.224641) (xy 217.05 164.301) (xy 217.246458 164.197636) (xy 217.194657 164.114138)
				(xy 217.145166 164.028045) (xy 217.130386 163.97284) (xy 217.125 163.899323)
			)
		)
	)
	(zone
		(net 2)
		(net_name "+3V3")
		(layer "F.Cu")
		(name "$teardrop_padvia$")
		(hatch none 0.1)
		(priority 31753)
		(attr
			(teardrop
				(type padvia)
			)
		)
		(connect_pads yes
			(clearance 0)
		)
		(min_thickness 0.0254)
		(filled_areas_thickness no)
		(fill yes
			(thermal_gap 0.5)
			(thermal_bridge_width 0.5)
			(island_removal_mode 1)
			(island_area_min 10)
		)
		(polygon
			(pts
				(xy 298.799323 84.5525) (xy 298.868764 84.557318) (xy 298.920088 84.57104) (xy 298.995629 84.617755)
				(xy 299.007769 84.627299) (xy 299.074997 84.677081) (xy 299.201 84.49) (xy 299.074997 84.302919)
				(xy 299.007768 84.352702) (xy 298.924602 84.407106) (xy 298.871748 84.42219) (xy 298.799323 84.4275)
			)
		)
	)
	(zone
		(net 371)
		(net_name "/Com Express 7 MGMT/I2C.SCL")
		(layer "F.Cu")
		(name "$teardrop_padvia$")
		(hatch none 0.1)
		(priority 30722)
		(attr
			(teardrop
				(type padvia)
			)
		)
		(connect_pads yes
			(clearance 0)
		)
		(min_thickness 0.0254)
		(filled_areas_thickness no)
		(fill yes
			(thermal_gap 0.5)
			(thermal_bridge_width 0.5)
			(island_removal_mode 1)
			(island_area_min 10)
		)
		(polygon
			(pts
				(xy 304.5895 151.05) (xy 304.594848 151.017909) (xy 304.612282 150.984743) (xy 304.638737 150.958583)
				(xy 304.677163 150.937804) (xy 304.71705 150.92705) (xy 304.525 150.409) (xy 304.33295 150.92705)
				(xy 304.378153 150.939446) (xy 304.412844 150.958095) (xy 304.455426 151.008896) (xy 304.4645 151.05)
			)
		)
	)
	(zone
		(net 1)
		(net_name "GND")
		(layer "F.Cu")
		(name "$teardrop_padvia$")
		(hatch none 0.1)
		(priority 31242)
		(attr
			(teardrop
				(type padvia)
			)
		)
		(connect_pads yes
			(clearance 0)
		)
		(min_thickness 0.0254)
		(filled_areas_thickness no)
		(fill yes
			(thermal_gap 0.5)
			(thermal_bridge_width 0.5)
			(island_removal_mode 1)
			(island_area_min 10)
		)
		(polygon
			(pts
				(xy 211.925 163.949323) (xy 211.920263 164.040322) (xy 211.907104 164.107411) (xy 211.874583 164.194139)
				(xy 211.842355 164.274641) (xy 212.05 164.351) (xy 212.246458 164.247636) (xy 212.194657 164.164138)
				(xy 212.145166 164.078045) (xy 212.130386 164.02284) (xy 212.125 163.949323)
			)
		)
	)
	(zone
		(net 2)
		(net_name "+3V3")
		(layer "F.Cu")
		(name "$teardrop_padvia$")
		(hatch none 0.1)
		(priority 31063)
		(attr
			(teardrop
				(type padvia)
			)
		)
		(connect_pads yes
			(clearance 0)
		)
		(min_thickness 0.0254)
		(filled_areas_thickness no)
		(fill yes
			(thermal_gap 0.5)
			(thermal_bridge_width 0.5)
			(island_removal_mode 1)
			(island_area_min 10)
		)
		(polygon
			(pts
				(xy 113.793 148.7975) (xy 113.733588 148.777727) (xy 113.677503 148.714453) (xy 113.655801 148.665828)
				(xy 113.641127 148.606468) (xy 113.639347 148.5945) (xy 113.379 148.86) (xy 113.639347 149.1255)
				(xy 113.652197 149.065361) (xy 113.672131 149.015477) (xy 113.698056 148.975358) (xy 113.727876 148.946345)
				(xy 113.759294 148.928854) (xy 113.791105 148.922521) (xy 113.793 148.9225)
			)
		)
	)
	(zone
		(net 207)
		(net_name "/Backplane/UART.TX")
		(layer "F.Cu")
		(name "$teardrop_padvia$")
		(hatch none 0.1)
		(priority 32124)
		(attr
			(teardrop
				(type padvia)
			)
		)
		(connect_pads yes
			(clearance 0)
		)
		(min_thickness 0.0254)
		(filled_areas_thickness no)
		(fill yes
			(thermal_gap 0.5)
			(thermal_bridge_width 0.5)
			(island_removal_mode 1)
			(island_area_min 10)
		)
		(polygon
			(pts
				(xy 314.688 167.9455) (xy 314.681678 167.945596) (xy 314.642175 167.940011) (xy 314.623953 167.925078)
				(xy 314.611005 167.8955) (xy 314.362 168.008) (xy 314.611005 168.1205) (xy 314.622121 168.093506)
				(xy 314.637648 168.078405) (xy 314.681678 168.070404) (xy 314.688 168.0705)
			)
		)
	)
	(zone
		(net 596)
		(net_name "/Misc/PWM2")
		(layer "F.Cu")
		(name "$teardrop_padvia$")
		(hatch none 0.1)
		(priority 30981)
		(attr
			(teardrop
				(type padvia)
			)
		)
		(connect_pads yes
			(clearance 0)
		)
		(min_thickness 0.0254)
		(filled_areas_thickness no)
		(fill yes
			(thermal_gap 0.5)
			(thermal_bridge_width 0.5)
			(island_removal_mode 1)
			(island_area_min 10)
		)
		(polygon
			(pts
				(xy 261.102 83.892499) (xy 261.164866 83.912468) (xy 261.196844 83.93892) (xy 261.225358 83.976331)
				(xy 261.247882 84.023526) (xy 261.263093 84.081166) (xy 261.263202 84.081797) (xy 261.541 83.829999)
				(xy 261.263202 83.578201) (xy 261.248905 83.633634) (xy 261.227825 83.679519) (xy 261.20046 83.7172)
				(xy 261.169552 83.744433) (xy 261.136265 83.761471) (xy 261.103434 83.767488) (xy 261.102 83.767499)
			)
		)
	)
	(zone
		(net 303)
		(net_name "/Com Express 7 MGMT/~{SUS_S5}")
		(layer "F.Cu")
		(name "$teardrop_padvia$")
		(hatch none 0.1)
		(priority 30650)
		(attr
			(teardrop
				(type padvia)
			)
		)
		(connect_pads yes
			(clearance 0)
		)
		(min_thickness 0.0254)
		(filled_areas_thickness no)
		(fill yes
			(thermal_gap 0.5)
			(thermal_bridge_width 0.5)
			(island_removal_mode 1)
			(island_area_min 10)
		)
		(polygon
			(pts
				(xy 187.5875 169.62) (xy 187.598438 169.581177) (xy 187.620195 169.566067) (xy 187.66 169.56) (xy 187.525 168.684)
				(xy 187.39 169.56) (xy 187.425281 169.564517) (xy 187.446797 169.576138) (xy 187.461995 169.608961)
				(xy 187.4625 169.62)
			)
		)
	)
	(zone
		(net 237)
		(net_name "/Com Express 7 Interfaces/PCIe_{B2Bx4}.RX3-")
		(layer "F.Cu")
		(name "$teardrop_padvia$")
		(hatch none 0.1)
		(priority 31378)
		(attr
			(teardrop
				(type padvia)
			)
		)
		(connect_pads yes
			(clearance 0)
		)
		(min_thickness 0.0254)
		(filled_areas_thickness no)
		(fill yes
			(thermal_gap 0.5)
			(thermal_bridge_width 0.5)
			(island_removal_mode 1)
			(island_area_min 10)
		)
		(polygon
			(pts
				(xy 173.232504 94.4055) (xy 173.27929 94.410235) (xy 173.314742 94.423379) (xy 173.362939 94.468387)
				(xy 173.387116 94.506608) (xy 173.414485 94.549773) (xy 173.451147 94.591731) (xy 173.601 94.4285)
				(xy 173.58014 94.207823) (xy 173.479466 94.212452) (xy 173.396096 94.209019) (xy 173.394035 94.208895)
				(xy 173.232504 94.2035)
			)
		)
	)
	(zone
		(net 606)
		(net_name "Net-(U37-~{OE4})")
		(layer "F.Cu")
		(name "$teardrop_padvia$")
		(hatch none 0.1)
		(priority 30930)
		(attr
			(teardrop
				(type padvia)
			)
		)
		(connect_pads yes
			(clearance 0)
		)
		(min_thickness 0.0254)
		(filled_areas_thickness no)
		(fill yes
			(thermal_gap 0.5)
			(thermal_bridge_width 0.5)
			(island_removal_mode 1)
			(island_area_min 10)
		)
		(polygon
			(pts
				(xy 222.2625 127.633) (xy 222.282469 127.570134) (xy 222.308921 127.538156) (xy 222.346332 127.509642)
				(xy 222.393527 127.487118) (xy 222.451167 127.471907) (xy 222.451798 127.471798) (xy 222.2 127.194)
				(xy 221.948202 127.471798) (xy 222.003635 127.486095) (xy 222.04952 127.507175) (xy 222.087201 127.53454)
				(xy 222.114434 127.565448) (xy 222.131472 127.598735) (xy 222.137489 127.631566) (xy 222.1375 127.633)
			)
		)
	)
	(zone
		(net 1)
		(net_name "GND")
		(layer "F.Cu")
		(name "$teardrop_padvia$")
		(hatch none 0.1)
		(priority 31326)
		(attr
			(teardrop
				(type padvia)
			)
		)
		(connect_pads yes
			(clearance 0)
		)
		(min_thickness 0.0254)
		(filled_areas_thickness no)
		(fill yes
			(thermal_gap 0.5)
			(thermal_bridge_width 0.5)
			(island_removal_mode 1)
			(island_area_min 10)
		)
		(polygon
			(pts
				(xy 230.425 151.912207) (xy 230.418795 152.073627) (xy 230.395362 152.197262) (xy 230.385187 152.238795)
				(xy 230.383268 152.246578) (xy 230.6 152.301) (xy 230.780694 152.16861) (xy 230.711703 152.09461)
				(xy 230.650487 152.025302) (xy 230.631848 151.977706) (xy 230.625 151.912207)
			)
		)
	)
	(zone
		(net 1)
		(net_name "GND")
		(layer "F.Cu")
		(name "$teardrop_padvia$")
		(hatch none 0.1)
		(priority 30975)
		(attr
			(teardrop
				(type padvia)
			)
		)
		(connect_pads yes
			(clearance 0)
		)
		(min_thickness 0.0254)
		(filled_areas_thickness no)
		(fill yes
			(thermal_gap 0.5)
			(thermal_bridge_width 0.5)
			(island_removal_mode 1)
			(island_area_min 10)
		)
		(polygon
			(pts
				(xy 242.188 127.7675) (xy 242.125134 127.747531) (xy 242.093156 127.721079) (xy 242.064642 127.683668)
				(xy 242.042118 127.636473) (xy 242.026907 127.578833) (xy 242.026798 127.578202) (xy 241.749 127.83)
				(xy 242.026798 128.081798) (xy 242.041095 128.026365) (xy 242.062175 127.98048) (xy 242.08954 127.942799)
				(xy 242.120448 127.915566) (xy 242.153735 127.898528) (xy 242.186566 127.892511) (xy 242.188 127.8925)
			)
		)
	)
	(zone
		(net 2)
		(net_name "+3V3")
		(layer "F.Cu")
		(name "$teardrop_padvia$")
		(hatch none 0.1)
		(priority 30227)
		(attr
			(teardrop
				(type padvia)
			)
		)
		(connect_pads yes
			(clearance 0)
		)
		(min_thickness 0.0254)
		(filled_areas_thickness no)
		(fill yes
			(thermal_gap 0.5)
			(thermal_bridge_width 0.5)
			(island_removal_mode 1)
			(island_area_min 10)
		)
		(polygon
			(pts
				(xy 232.007707 78.573) (xy 232.038315 78.56465) (xy 232.0913 78.554039) (xy 232.114432 78.567044)
				(xy 232.130898 78.603) (xy 232.823707 78.423) (xy 232.130898 78.243) (xy 232.118964 78.272959) (xy 232.102643 78.288272)
				(xy 232.064969 78.290108) (xy 232.038315 78.28135) (xy 232.007707 78.273)
			)
		)
	)
	(zone
		(net 1)
		(net_name "GND")
		(layer "F.Cu")
		(name "$teardrop_padvia$")
		(hatch none 0.1)
		(priority 31206)
		(attr
			(teardrop
				(type padvia)
			)
		)
		(connect_pads yes
			(clearance 0)
		)
		(min_thickness 0.0254)
		(filled_areas_thickness no)
		(fill yes
			(thermal_gap 0.5)
			(thermal_bridge_width 0.5)
			(island_removal_mode 1)
			(island_area_min 10)
		)
		(polygon
			(pts
				(xy 182.425 157.499323) (xy 182.42028 157.568646) (xy 182.407244 157.621549) (xy 182.355344 157.714135)
				(xy 182.303541 157.797636) (xy 182.5 157.901) (xy 182.707644 157.824641) (xy 182.675418 157.744142)
				(xy 182.639035 157.642683) (xy 182.625 157.499323)
			)
		)
	)
	(zone
		(net 51)
		(net_name "Net-(C13-Pad1)")
		(layer "F.Cu")
		(name "$teardrop_padvia$")
		(hatch none 0.1)
		(priority 30094)
		(attr
			(teardrop
				(type padvia)
			)
		)
		(connect_pads yes
			(clearance 0)
		)
		(min_thickness 0.0254)
		(filled_areas_thickness no)
		(fill yes
			(thermal_gap 0.5)
			(thermal_bridge_width 0.5)
			(island_removal_mode 1)
			(island_area_min 10)
		)
		(polygon
			(pts
				(xy 131.374 99.1) (xy 131.317939 99.092567) (xy 131.262329 99.060538) (xy 131.238554 99.029894)
				(xy 131.220421 98.98702) (xy 131.208103 98.9035) (xy 130.769 99.25) (xy 131.208103 99.5965) (xy 131.214918 99.535202)
				(xy 131.229503 99.487953) (xy 131.249612 99.453687) (xy 131.273934 99.42947) (xy 131.334458 99.403449)
				(xy 131.374 99.4)
			)
		)
	)
	(zone
		(net 533)
		(net_name "/Com Express 7 MGMT/PSON")
		(layer "F.Cu")
		(name "$teardrop_padvia$")
		(hatch none 0.1)
		(priority 30184)
		(attr
			(teardrop
				(type padvia)
			)
		)
		(connect_pads yes
			(clearance 0)
		)
		(min_thickness 0.0254)
		(filled_areas_thickness no)
		(fill yes
			(thermal_gap 0.5)
			(thermal_bridge_width 0.5)
			(island_removal_mode 1)
			(island_area_min 10)
		)
		(polygon
			(pts
				(xy 303.255 137.905) (xy 303.29306 137.910658) (xy 303.331567 137.930261) (xy 303.358094 137.957094)
				(xy 303.379569 137.996138) (xy 303.396869 138.075919) (xy 303.876 137.809) (xy 303.400975 137.535935)
				(xy 303.391033 137.590141) (xy 303.37411 137.632078) (xy 303.325871 137.684805) (xy 303.264404 137.704675)
				(xy 303.255 137.705)
			)
		)
	)
	(zone
		(net 197)
		(net_name "/OCuLink/PCIe_{x4}.RX3-")
		(layer "F.Cu")
		(name "$teardrop_padvia$")
		(hatch none 0.1)
		(priority 31390)
		(attr
			(teardrop
				(type padvia)
			)
		)
		(connect_pads yes
			(clearance 0)
		)
		(min_thickness 0.0254)
		(filled_areas_thickness no)
		(fill yes
			(thermal_gap 0.5)
			(thermal_bridge_width 0.5)
			(island_removal_mode 1)
			(island_area_min 10)
		)
		(polygon
			(pts
				(xy 106.7585 151.167496) (xy 106.753105 151.005964) (xy 106.749555 150.921553) (xy 106.754177 150.819859)
				(xy 106.5335 150.799) (xy 106.370268 150.948852) (xy 106.438936 151.002992) (xy 106.455392 151.012884)
				(xy 106.494064 151.037384) (xy 106.526279 151.06689) (xy 106.548327 151.108046) (xy 106.5565 151.167496)
			)
		)
	)
	(zone
		(net 541)
		(net_name "Net-(Q9-B)")
		(layer "F.Cu")
		(name "$teardrop_padvia$")
		(hatch none 0.1)
		(priority 30186)
		(attr
			(teardrop
				(type padvia)
			)
		)
		(connect_pads yes
			(clearance 0)
		)
		(min_thickness 0.0254)
		(filled_areas_thickness no)
		(fill yes
			(thermal_gap 0.5)
			(thermal_bridge_width 0.5)
			(island_removal_mode 1)
			(island_area_min 10)
		)
		(polygon
			(pts
				(xy 118.97 141.7605) (xy 118.931486 141.754825) (xy 118.892381 141.735097) (xy 118.865531 141.708219)
				(xy 118.843718 141.669111) (xy 118.826072 141.5905) (xy 118.349 141.8605) (xy 118.826072 142.1305)
				(xy 118.835617 142.075894) (xy 118.852225 142.033658) (xy 118.899911 141.980693) (xy 118.960814 141.960816)
				(xy 118.97 141.9605)
			)
		)
	)
	(zone
		(net 371)
		(net_name "/Com Express 7 MGMT/I2C.SCL")
		(layer "F.Cu")
		(name "$teardrop_padvia$")
		(hatch none 0.1)
		(priority 30705)
		(attr
			(teardrop
				(type padvia)
			)
		)
		(connect_pads yes
			(clearance 0)
		)
		(min_thickness 0.0254)
		(filled_areas_thickness no)
		(fill yes
			(thermal_gap 0.5)
			(thermal_bridge_width 0.5)
			(island_removal_mode 1)
			(island_area_min 10)
		)
		(polygon
			(pts
				(xy 191.9625 162.2) (xy 191.951563 162.238823) (xy 191.929805 162.253933) (xy 191.89 162.26) (xy 192.025 163.136)
				(xy 192.16 162.26) (xy 192.124719 162.255483) (xy 192.103203 162.243862) (xy 192.088005 162.211039)
				(xy 192.0875 162.2)
			)
		)
	)
	(zone
		(net 345)
		(net_name "/Com Express 7 MGMT/SER0.RX")
		(layer "F.Cu")
		(name "$teardrop_padvia$")
		(hatch none 0.1)
		(priority 31055)
		(attr
			(teardrop
				(type padvia)
			)
		)
		(connect_pads yes
			(clearance 0)
		)
		(min_thickness 0.0254)
		(filled_areas_thickness no)
		(fill yes
			(thermal_gap 0.5)
			(thermal_bridge_width 0.5)
			(island_removal_mode 1)
			(island_area_min 10)
		)
		(polygon
			(pts
				(xy 123.4425 76.703) (xy 123.462273 76.643588) (xy 123.525547 76.587503) (xy 123.574172 76.565801)
				(xy 123.633532 76.551127) (xy 123.6455 76.549347) (xy 123.38 76.289) (xy 123.1145 76.549347) (xy 123.174639 76.562197)
				(xy 123.224523 76.582131) (xy 123.264642 76.608056) (xy 123.293655 76.637876) (xy 123.311146 76.669294)
				(xy 123.317479 76.701105) (xy 123.3175 76.703)
			)
		)
	)
	(zone
		(net 23)
		(net_name "/M.2 key E/~{PERST_D}")
		(layer "F.Cu")
		(name "$teardrop_padvia$")
		(hatch none 0.1)
		(priority 31065)
		(attr
			(teardrop
				(type padvia)
			)
		)
		(connect_pads yes
			(clearance 0)
		)
		(min_thickness 0.0254)
		(filled_areas_thickness no)
		(fill yes
			(thermal_gap 0.5)
			(thermal_bridge_width 0.5)
			(island_removal_mode 1)
			(island_area_min 10)
		)
		(polygon
			(pts
				(xy 144.343 83.9975) (xy 144.283588 83.977727) (xy 144.227503 83.914453) (xy 144.205801 83.865828)
				(xy 144.191127 83.806468) (xy 144.189347 83.7945) (xy 143.929 84.06) (xy 144.189347 84.3255) (xy 144.202197 84.265361)
				(xy 144.222131 84.215477) (xy 144.248056 84.175358) (xy 144.277876 84.146345) (xy 144.309294 84.128854)
				(xy 144.341105 84.122521) (xy 144.343 84.1225)
			)
		)
	)
	(zone
		(net 1)
		(net_name "GND")
		(layer "F.Cu")
		(name "$teardrop_padvia$")
		(hatch none 0.1)
		(priority 30191)
		(attr
			(teardrop
				(type padvia)
			)
		)
		(connect_pads yes
			(clearance 0)
		)
		(min_thickness 0.0254)
		(filled_areas_thickness no)
		(fill yes
			(thermal_gap 0.5)
			(thermal_bridge_width 0.5)
			(island_removal_mode 1)
			(island_area_min 10)
		)
		(polygon
			(pts
				(xy 203.499 82.47) (xy 203.504675 82.431486) (xy 203.524403 82.392381) (xy 203.551281 82.365531)
				(xy 203.590389 82.343718) (xy 203.669 82.326072) (xy 203.399 81.849) (xy 203.129 82.326072) (xy 203.183606 82.335617)
				(xy 203.225842 82.352225) (xy 203.278807 82.399911) (xy 203.298684 82.460814) (xy 203.299 82.47)
			)
		)
	)
	(zone
		(net 283)
		(net_name "/Misc/TACH_{C5V}")
		(layer "F.Cu")
		(name "$teardrop_padvia$")
		(hatch none 0.1)
		(priority 30011)
		(attr
			(teardrop
				(type padvia)
			)
		)
		(connect_pads yes
			(clearance 0)
		)
		(min_thickness 0.0254)
		(filled_areas_thickness no)
		(fill yes
			(thermal_gap 0.5)
			(thermal_bridge_width 0.5)
			(island_removal_mode 1)
			(island_area_min 10)
		)
		(polygon
			(pts
				(xy 234.664455 72.735359) (xy 234.593804 72.637539) (xy 234.540679 72.495936) (xy 234.510677 72.30263)
				(xy 234.512335 72.05536) (xy 234.553611 71.765372) (xy 234.565707 71.71) (xy 233.7 71.859293) (xy 233.86946 72.858379)
				(xy 234.022567 72.782683) (xy 234.192635 72.740142) (xy 234.278586 72.733309) (xy 234.359801 72.736611)
				(xy 234.432474 72.749312) (xy 234.496586 72.771083) (xy 234.576066 72.823748)
			)
		)
	)
	(zone
		(net 243)
		(net_name "/Com Express 7 Interfaces/PCIe_{B2Bx4}.RX2-")
		(layer "F.Cu")
		(name "$teardrop_padvia$")
		(hatch none 0.1)
		(priority 31381)
		(attr
			(teardrop
				(type padvia)
			)
		)
		(connect_pads yes
			(clearance 0)
		)
		(min_thickness 0.0254)
		(filled_areas_thickness no)
		(fill yes
			(thermal_gap 0.5)
			(thermal_bridge_width 0.5)
			(island_removal_mode 1)
			(island_area_min 10)
		)
		(polygon
			(pts
				(xy 191.632504 161.1955) (xy 191.67929 161.200235) (xy 191.714742 161.213379) (xy 191.762939 161.258387)
				(xy 191.787116 161.296608) (xy 191.814485 161.339773) (xy 191.851147 161.381731) (xy 192.001 161.2185)
				(xy 191.98014 160.997823) (xy 191.879466 161.002452) (xy 191.796096 160.999019) (xy 191.794035 160.998895)
				(xy 191.632504 160.9935)
			)
		)
	)
	(zone
		(net 161)
		(net_name "/2xUSB3.0+RJ45/USBSS_2.RX+")
		(layer "F.Cu")
		(name "$teardrop_padvia$")
		(hatch none 0.1)
		(priority 30284)
		(attr
			(teardrop
				(type padvia)
			)
		)
		(connect_pads yes
			(clearance 0)
		)
		(min_thickness 0.0254)
		(filled_areas_thickness no)
		(fill yes
			(thermal_gap 0.5)
			(thermal_bridge_width 0.5)
			(island_removal_mode 1)
			(island_area_min 10)
		)
		(polygon
			(pts
				(xy 182.0575 157.62) (xy 182.055915 157.607811) (xy 182.057296 157.576262) (xy 182.072069 157.564604)
				(xy 182.104123 157.56) (xy 182.025 156.684) (xy 181.875 156.913685) (xy 181.894285 157.1731) (xy 181.881903 157.446083)
				(xy 181.8725 157.62)
			)
		)
	)
	(zone
		(net 1)
		(net_name "GND")
		(layer "F.Cu")
		(name "$teardrop_padvia$")
		(hatch none 0.1)
		(priority 30839)
		(attr
			(teardrop
				(type padvia)
			)
		)
		(connect_pads yes
			(clearance 0)
		)
		(min_thickness 0.0254)
		(filled_areas_thickness no)
		(fill yes
			(thermal_gap 0.5)
			(thermal_bridge_width 0.5)
			(island_removal_mode 1)
			(island_area_min 10)
		)
		(polygon
			(pts
				(xy 237.138 154.84) (xy 237.091789 154.83379) (xy 237.04339 154.810323) (xy 237.015034 154.782416)
				(xy 236.991988 154.74219) (xy 236.976798 154.688202) (xy 236.699 154.94) (xy 236.976798 155.191798)
				(xy 236.989931 155.142946) (xy 237.009335 155.105436) (xy 237.061945 155.058013) (xy 237.128446 155.040257)
				(xy 237.138 155.04)
			)
		)
	)
	(zone
		(net 1)
		(net_name "GND")
		(layer "F.Cu")
		(name "$teardrop_padvia$")
		(hatch none 0.1)
		(priority 31198)
		(attr
			(teardrop
				(type padvia)
			)
		)
		(connect_pads yes
			(clearance 0)
		)
		(min_thickness 0.0254)
		(filled_areas_thickness no)
		(fill yes
			(thermal_gap 0.5)
			(thermal_bridge_width 0.5)
			(island_removal_mode 1)
			(island_area_min 10)
		)
		(polygon
			(pts
				(xy 210.425 151.899323) (xy 210.42028 151.968646) (xy 210.407244 152.021549) (xy 210.355344 152.114135)
				(xy 210.303541 152.197636) (xy 210.5 152.301) (xy 210.707644 152.224641) (xy 210.675418 152.144142)
				(xy 210.639035 152.042683) (xy 210.625 151.899323)
			)
		)
	)
	(zone
		(net 51)
		(net_name "Net-(C13-Pad1)")
		(layer "F.Cu")
		(name "$teardrop_padvia$")
		(hatch none 0.1)
		(priority 30142)
		(attr
			(teardrop
				(type padvia)
			)
		)
		(connect_pads yes
			(clearance 0)
		)
		(min_thickness 0.0254)
		(filled_areas_thickness no)
		(fill yes
			(thermal_gap 0.5)
			(thermal_bridge_width 0.5)
			(island_removal_mode 1)
			(island_area_min 10)
		)
		(polygon
			(pts
				(xy 130.066964 103.229095) (xy 130.122924 103.241039) (xy 130.185844 103.26655) (xy 130.236481 103.299075)
				(xy 130.280113 103.342912) (xy 130.305358 103.384461) (xy 130.321088 103.433508) (xy 130.325207 103.474182)
				(xy 130.770707 103.140707) (xy 130.325861 102.802533) (xy 130.325165 102.877411) (xy 130.318981 102.990239)
				(xy 130.305389 103.012778) (xy 130.279095 103.016964)
			)
		)
	)
	(zone
		(net 555)
		(net_name "/2xUSB3.0+RJ45/EN_1B")
		(layer "F.Cu")
		(name "$teardrop_padvia$")
		(hatch none 0.1)
		(priority 31029)
		(attr
			(teardrop
				(type padvia)
			)
		)
		(connect_pads yes
			(clearance 0)
		)
		(min_thickness 0.0254)
		(filled_areas_thickness no)
		(fill yes
			(thermal_gap 0.5)
			(thermal_bridge_width 0.5)
			(island_removal_mode 1)
			(island_area_min 10)
		)
		(polygon
			(pts
				(xy 121.632499 85.497999) (xy 121.652468 85.435134) (xy 121.67892 85.403156) (xy 121.716331 85.374641)
				(xy 121.763527 85.352117) (xy 121.821167 85.336907) (xy 121.821797 85.336798) (xy 121.569999 85.059001)
				(xy 121.318201 85.336798) (xy 121.373634 85.351095) (xy 121.419519 85.372175) (xy 121.457201 85.39954)
				(xy 121.484434 85.430449) (xy 121.501472 85.463735) (xy 121.507489 85.496566) (xy 121.5075 85.498)
			)
		)
	)
	(zone
		(net 377)
		(net_name "/Com Express 7 Interfaces/USB1.D-")
		(layer "F.Cu")
		(name "$teardrop_padvia$")
		(hatch none 0.1)
		(priority 30491)
		(attr
			(teardrop
				(type padvia)
			)
		)
		(connect_pads yes
			(clearance 0)
		)
		(min_thickness 0.0254)
		(filled_areas_thickness no)
		(fill yes
			(thermal_gap 0.5)
			(thermal_bridge_width 0.5)
			(island_removal_mode 1)
			(island_area_min 10)
		)
		(polygon
			(pts
				(xy 157.318657 71.9075) (xy 157.259038 71.942089) (xy 157.184647 71.972566) (xy 157.107526 71.992491)
				(xy 157.024874 72.000953) (xy 156.920508 71.99) (xy 156.954 72.31) (xy 157.25 72.406839) (xy 157.246947 72.277478)
				(xy 157.260113 72.181437) (xy 157.277533 72.13811) (xy 157.303085 72.105054) (xy 157.318657 72.0925)
			)
		)
	)
	(zone
		(net 1)
		(net_name "GND")
		(layer "F.Cu")
		(name "$teardrop_padvia$")
		(hatch none 0.1)
		(priority 30202)
		(attr
			(teardrop
				(type padvia)
			)
		)
		(connect_pads yes
			(clearance 0)
		)
		(min_thickness 0.0254)
		(filled_areas_thickness no)
		(fill yes
			(thermal_gap 0.5)
			(thermal_bridge_width 0.5)
			(island_removal_mode 1)
			(island_area_min 10)
		)
		(polygon
			(pts
				(xy 303.05 104.046508) (xy 303.044674 104.018679) (xy 303.038273 103.987179) (xy 303.044484 103.957363)
				(xy 303.076996 103.934942) (xy 303.149496 103.925624) (xy 302.980001 103.609) (xy 302.685001 103.646627)
				(xy 302.703142 103.723339) (xy 302.687512 103.812341) (xy 302.644929 103.913128) (xy 302.613693 103.984135)
				(xy 302.6 104.046508)
			)
		)
	)
	(zone
		(net 626)
		(net_name "/PCIe redriver/TX_FG0")
		(layer "F.Cu")
		(name "$teardrop_padvia$")
		(hatch none 0.1)
		(priority 30971)
		(attr
			(teardrop
				(type padvia)
			)
		)
		(connect_pads yes
			(clearance 0)
		)
		(min_thickness 0.0254)
		(filled_areas_thickness no)
		(fill yes
			(thermal_gap 0.5)
			(thermal_bridge_width 0.5)
			(island_removal_mode 1)
			(island_area_min 10)
		)
		(polygon
			(pts
				(xy 113.838 150.7775) (xy 113.775134 150.757531) (xy 113.743156 150.731079) (xy 113.714642 150.693668)
				(xy 113.692118 150.646473) (xy 113.676907 150.588833) (xy 113.676798 150.588202) (xy 113.399 150.84)
				(xy 113.676798 151.091798) (xy 113.691095 151.036365) (xy 113.712175 150.99048) (xy 113.73954 150.952799)
				(xy 113.770448 150.925566) (xy 113.803735 150.908528) (xy 113.836566 150.902511) (xy 113.838 150.9025)
			)
		)
	)
	(zone
		(net 331)
		(net_name "/Com Express 7 Interfaces/PCIe_{B2Ax4}.TX3-")
		(layer "F.Cu")
		(name "$teardrop_padvia$")
		(hatch none 0.1)
		(priority 31903)
		(attr
			(teardrop
				(type padvia)
			)
		)
		(connect_pads yes
			(clearance 0)
		)
		(min_thickness 0.0254)
		(filled_areas_thickness no)
		(fill yes
			(thermal_gap 0.5)
			(thermal_bridge_width 0.5)
			(island_removal_mode 1)
			(island_area_min 10)
		)
		(polygon
			(pts
				(xy 216.596417 167.301081) (xy 216.585315 167.283352) (xy 216.592016 167.271948) (xy 216.642918 167.258833)
				(xy 216.683945 167.250885) (xy 216.718503 167.237081) (xy 216.592793 167.049293) (xy 216.375284 167.099838)
				(xy 216.38327 167.200749) (xy 216.381595 167.231327) (xy 216.379686 167.283169) (xy 216.385828 167.334112)
				(xy 216.40785 167.386809) (xy 216.453582 167.443916)
			)
		)
	)
	(zone
		(net 2)
		(net_name "+3V3")
		(layer "F.Cu")
		(name "$teardrop_padvia$")
		(hatch none 0.1)
		(priority 32043)
		(attr
			(teardrop
				(type padvia)
			)
		)
		(connect_pads yes
			(clearance 0)
		)
		(min_thickness 0.0254)
		(filled_areas_thickness no)
		(fill yes
			(thermal_gap 0.5)
			(thermal_bridge_width 0.5)
			(island_removal_mode 1)
			(island_area_min 10)
		)
		(polygon
			(pts
				(xy 193.020427 129.579993) (xy 193.044677 129.597545) (xy 193.070397 129.604662) (xy 193.125035 129.591644)
				(xy 193.18274 129.539764) (xy 193.206251 129.499903) (xy 193.219121 129.457955) (xy 193.219465 129.42313)
				(xy 193.207813 129.392612) (xy 193.036565 129.507742) (xy 192.921429 129.678986) (xy 192.972854 129.691738)
				(xy 193.042557 129.670572) (xy 193.080468 129.644391) (xy 193.110871 129.611465) (xy 193.128746 129.57748)
				(xy 193.133544 129.542287) (xy 193.126531 129.516196) (xy 193.108815 129.491604)
			)
		)
	)
	(zone
		(net 2)
		(net_name "+3V3")
		(layer "F.Cu")
		(name "$teardrop_padvia$")
		(hatch none 0.1)
		(priority 31044)
		(attr
			(teardrop
				(type padvia)
			)
		)
		(connect_pads yes
			(clearance 0)
		)
		(min_thickness 0.0254)
		(filled_areas_thickness no)
		(fill yes
			(thermal_gap 0.5)
			(thermal_bridge_width 0.5)
			(island_removal_mode 1)
			(island_area_min 10)
		)
		(polygon
			(pts
				(xy 113.962 148.9225) (xy 114.019753 148.942113) (xy 114.073778 149.004882) (xy 114.095921 149.054976)
				(xy 114.111533 149.116095) (xy 114.1153 149.140973) (xy 114.401 148.901) (xy 114.123202 148.649202)
				(xy 114.089338 148.727535) (xy 114.030959 148.778593) (xy 113.962 148.7975)
			)
		)
	)
	(zone
		(net 356)
		(net_name "/Com Express 7 MGMT/~{CW_PWRBTN}")
		(layer "F.Cu")
		(name "$teardrop_padvia$")
		(hatch none 0.1)
		(priority 31696)
		(attr
			(teardrop
				(type padvia)
			)
		)
		(connect_pads yes
			(clearance 0)
		)
		(min_thickness 0.0254)
		(filled_areas_thickness no)
		(fill yes
			(thermal_gap 0.5)
			(thermal_bridge_width 0.5)
			(island_removal_mode 1)
			(island_area_min 10)
		)
		(polygon
			(pts
				(xy 241.7375 133.199323) (xy 241.732682 133.268763) (xy 241.71896 133.320087) (xy 241.672245 133.395628)
				(xy 241.662702 133.407768) (xy 241.612919 133.474997) (xy 241.8 133.601) (xy 241.987081 133.474997)
				(xy 241.937299 133.407769) (xy 241.882894 133.324603) (xy 241.86781 133.271748) (xy 241.8625 133.199323)
			)
		)
	)
	(zone
		(net 490)
		(net_name "/2xSFP+/MDIO1.MDIO")
		(layer "F.Cu")
		(name "$teardrop_padvia$")
		(hatch none 0.1)
		(priority 30342)
		(attr
			(teardrop
				(type padvia)
			)
		)
		(connect_pads yes
			(clearance 0)
		)
		(min_thickness 0.0254)
		(filled_areas_thickness no)
		(fill yes
			(thermal_gap 0.5)
			(thermal_bridge_width 0.5)
			(island_removal_mode 1)
			(island_area_min 10)
		)
		(polygon
			(pts
				(xy 125.7445 152.226) (xy 125.750281 152.192137) (xy 125.770745 152.157516) (xy 125.797811 152.135694)
				(xy 125.83715 152.12) (xy 125.852711 152.116711) (xy 125.682 151.41) (xy 125.511289 152.116711)
				(xy 125.55151 152.1283) (xy 125.580984 152.145885) (xy 125.614173 152.193467) (xy 125.6195 152.226)
			)
		)
	)
	(zone
		(net 338)
		(net_name "/Com Express 7 MGMT/SPI.MISO")
		(layer "F.Cu")
		(name "$teardrop_padvia$")
		(hatch none 0.1)
		(priority 30070)
		(attr
			(teardrop
				(type padvia)
			)
		)
		(connect_pads yes
			(clearance 0)
		)
		(min_thickness 0.0254)
		(filled_areas_thickness no)
		(fill yes
			(thermal_gap 0.5)
			(thermal_bridge_width 0.5)
			(island_removal_mode 1)
			(island_area_min 10)
		)
		(polygon
			(pts
				(xy 257.505612 162.563689) (xy 257.421857 162.508259) (xy 257.380178 162.462412) (xy 257.345345 162.40676)
				(xy 257.315405 162.309827) (xy 256.522438 162.564293) (xy 257.30055 162.842405) (xy 257.321197 162.751662)
				(xy 257.347177 162.689151) (xy 257.368784 162.662799) (xy 257.392864 162.652275) (xy 257.413689 162.655612)
			)
		)
	)
	(zone
		(net 1)
		(net_name "GND")
		(layer "F.Cu")
		(name "$teardrop_padvia$")
		(hatch none 0.1)
		(priority 30543)
		(attr
			(teardrop
				(type padvia)
			)
		)
		(connect_pads yes
			(clearance 0)
		)
		(min_thickness 0.0254)
		(filled_areas_thickness no)
		(fill yes
			(thermal_gap 0.5)
			(thermal_bridge_width 0.5)
			(island_removal_mode 1)
			(island_area_min 10)
		)
		(polygon
			(pts
				(xy 223.625 152.07) (xy 223.621667 152.055514) (xy 223.61881 152.02539) (xy 223.630964 152.014349)
				(xy 223.66 152.01) (xy 223.525 151.134) (xy 223.39 152.01) (xy 223.419334 152.014475) (xy 223.431358 152.025801)
				(xy 223.428333 152.055514) (xy 223.425 152.07)
			)
		)
	)
	(zone
		(net 313)
		(net_name "/2xUSB3.0+RJ45/USB_1.D+")
		(layer "F.Cu")
		(name "$teardrop_padvia$")
		(hatch none 0.1)
		(priority 31480)
		(attr
			(teardrop
				(type padvia)
			)
		)
		(connect_pads yes
			(clearance 0)
		)
		(min_thickness 0.0254)
		(filled_areas_thickness no)
		(fill yes
			(thermal_gap 0.5)
			(thermal_bridge_width 0.5)
			(island_removal_mode 1)
			(island_area_min 10)
		)
		(polygon
			(pts
				(xy 197.0575 167.359584) (xy 197.06224 167.314972) (xy 197.075418 167.281575) (xy 197.120201 167.23798)
				(xy 197.16282 167.215148) (xy 197.210662 167.18949) (xy 197.256688 167.152895) (xy 197.0975 166.999)
				(xy 196.876823 167.012437) (xy 196.876683 167.195139) (xy 196.8725 167.359584)
			)
		)
	)
	(zone
		(net 1)
		(net_name "GND")
		(layer "F.Cu")
		(name "$teardrop_padvia$")
		(hatch none 0.1)
		(priority 32152)
		(attr
			(teardrop
				(type padvia)
			)
		)
		(connect_pads yes
			(clearance 0)
		)
		(min_thickness 0.0254)
		(filled_areas_thickness no)
		(fill yes
			(thermal_gap 0.5)
			(thermal_bridge_width 0.5)
			(island_removal_mode 1)
			(island_area_min 10)
		)
		(polygon
			(pts
				(xy 142.5825 133.339323) (xy 142.577764 133.311184) (xy 142.564615 133.290239) (xy 142.518158 133.267664)
				(xy 142.441044 133.272043) (xy 142.394681 133.288623) (xy 142.354927 133.313459) (xy 142.329691 133.340944)
				(xy 142.317903 133.372268) (xy 142.3175 133.379) (xy 142.52 133.379) (xy 142.3175 133.379) (xy 142.322082 133.390036)
				(xy 142.334541 133.388577) (xy 142.380632 133.358082) (xy 142.432991 133.323768) (xy 142.450711 133.322013)
				(xy 142.4575 133.339323)
			)
		)
	)
	(zone
		(net 73)
		(net_name "+3V3_AON")
		(layer "F.Cu")
		(name "$teardrop_padvia$")
		(hatch none 0.1)
		(priority 30479)
		(attr
			(teardrop
				(type padvia)
			)
		)
		(connect_pads yes
			(clearance 0)
		)
		(min_thickness 0.0254)
		(filled_areas_thickness no)
		(fill yes
			(thermal_gap 0.5)
			(thermal_bridge_width 0.5)
			(island_removal_mode 1)
			(island_area_min 10)
		)
		(polygon
			(pts
				(xy 247.101056 132.450556) (xy 247.017713 132.505935) (xy 246.887724 132.542154) (xy 246.807134 132.548517)
				(xy 246.719526 132.545) (xy 246.799293 132.840707) (xy 247.12 132.895474) (xy 247.110982 132.744316)
				(xy 247.120826 132.676785) (xy 247.139091 132.617974) (xy 247.189444 132.538944)
			)
		)
	)
	(zone
		(net 976)
		(net_name "/PCIe redriver/RX_EQ2")
		(layer "F.Cu")
		(name "$teardrop_padvia$")
		(hatch none 0.1)
		(priority 31025)
		(attr
			(teardrop
				(type padvia)
			)
		)
		(connect_pads yes
			(clearance 0)
		)
		(min_thickness 0.0254)
		(filled_areas_thickness no)
		(fill yes
			(thermal_gap 0.5)
			(thermal_bridge_width 0.5)
			(island_removal_mode 1)
			(island_area_min 10)
		)
		(polygon
			(pts
				(xy 193.06379 130.981) (xy 193.094122 131.039573) (xy 193.098029 131.080889) (xy 193.091738 131.127505)
				(xy 193.074293 131.176804) (xy 193.044291 131.228317) (xy 193.043922 131.22884) (xy 193.418403 131.247225)
				(xy 193.400018 130.872744) (xy 193.350712 130.901832) (xy 193.303361 130.919371) (xy 193.257366 130.926666)
				(xy 193.216254 130.924067) (xy 193.180669 130.912578) (xy 193.1532 130.893618) (xy 193.152178 130.892612)
			)
		)
	)
	(zone
		(net 1)
		(net_name "GND")
		(layer "F.Cu")
		(name "$teardrop_padvia$")
		(hatch none 0.1)
		(priority 30613)
		(attr
			(teardrop
				(type padvia)
			)
		)
		(connect_pads yes
			(clearance 0)
		)
		(min_thickness 0.0254)
		(filled_areas_thickness no)
		(fill yes
			(thermal_gap 0.5)
			(thermal_bridge_width 0.5)
			(island_removal_mode 1)
			(island_area_min 10)
		)
		(polygon
			(pts
				(xy 205.425 155.75) (xy 205.428333 155.764486) (xy 205.43119 155.79461) (xy 205.419036 155.805651)
				(xy 205.39 155.81) (xy 205.525 156.686) (xy 205.66 155.81) (xy 205.630666 155.805525) (xy 205.618642 155.794199)
				(xy 205.621667 155.764486) (xy 205.625 155.75)
			)
		)
	)
	(zone
		(net 771)
		(net_name "/Backplane/PCIe_{x2}.RX1+")
		(layer "F.Cu")
		(name "$teardrop_padvia$")
		(hatch none 0.1)
		(priority 31354)
		(attr
			(teardrop
				(type padvia)
			)
		)
		(connect_pads yes
			(clearance 0)
		)
		(min_thickness 0.0254)
		(filled_areas_thickness no)
		(fill yes
			(thermal_gap 0.5)
			(thermal_bridge_width 0.5)
			(island_removal_mode 1)
			(island_area_min 10)
		)
		(polygon
			(pts
				(xy 270.567496 159.7045) (xy 270.52071 159.699765) (xy 270.485258 159.686621) (xy 270.43706 159.641613)
				(xy 270.412884 159.603392) (xy 270.385514 159.560225) (xy 270.348852 159.518268) (xy 270.199 159.6815)
				(xy 270.21986 159.902177) (xy 270.320531 159.897548) (xy 270.403897 159.90098) (xy 270.405964 159.901105)
				(xy 270.567496 159.9065)
			)
		)
	)
	(zone
		(net 946)
		(net_name "/2xSFP+/KR to SFI #1/BYP_RX+")
		(layer "F.Cu")
		(name "$teardrop_padvia$")
		(hatch none 0.1)
		(priority 31963)
		(attr
			(teardrop
				(type padvia)
			)
		)
		(connect_pads yes
			(clearance 0)
		)
		(min_thickness 0.0254)
		(filled_areas_thickness no)
		(fill yes
			(thermal_gap 0.5)
			(thermal_bridge_width 0.5)
			(island_removal_mode 1)
			(island_area_min 10)
		)
		(polygon
			(pts
				(xy 149.84 148.553721) (xy 149.815938 148.484348) (xy 149.779423 148.374401) (xy 149.769113 148.314313)
				(xy 149.77 148.252463) (xy 149.57 148.28) (xy 149.511231 148.511) (xy 149.592579 148.505702) (xy 149.644596 148.514493)
				(xy 149.666116 148.528345) (xy 149.678354 148.548403) (xy 149.68 148.553721)
			)
		)
	)
	(zone
		(net 528)
		(net_name "/Backplane/~{PERST}")
		(layer "F.Cu")
		(name "$teardrop_padvia$")
		(hatch none 0.1)
		(priority 30032)
		(attr
			(teardrop
				(type padvia)
			)
		)
		(connect_pads yes
			(clearance 0)
		)
		(min_thickness 0.0254)
		(filled_areas_thickness no)
		(fill yes
			(thermal_gap 0.5)
			(thermal_bridge_width 0.5)
			(island_removal_mode 1)
			(island_area_min 10)
		)
		(polygon
			(pts
				(xy 317.84 164.1725) (xy 317.902625 164.192823) (xy 317.933436 164.219267) (xy 317.960377 164.256912)
				(xy 317.990273 164.344727) (xy 319.451 164.11) (xy 317.990273 163.875273) (xy 317.976502 163.927739)
				(xy 317.956084 163.970431) (xy 317.929557 164.004843) (xy 317.89976 164.029005) (xy 317.84 164.0475)
			)
		)
	)
	(zone
		(net 86)
		(net_name "/Com Express 7 Interfaces/PCIe_{B2Ax4}.RX0-")
		(layer "F.Cu")
		(name "$teardrop_padvia$")
		(hatch none 0.1)
		(priority 30513)
		(attr
			(teardrop
				(type padvia)
			)
		)
		(connect_pads yes
			(clearance 0)
		)
		(min_thickness 0.0254)
		(filled_areas_thickness no)
		(fill yes
			(thermal_gap 0.5)
			(thermal_bridge_width 0.5)
			(island_removal_mode 1)
			(island_area_min 10)
		)
		(polygon
			(pts
				(xy 211.626 164.07) (xy 211.622463 164.055322) (xy 211.619192 164.025315) (xy 211.631143 164.014327)
				(xy 211.66 164.01) (xy 211.525 163.134) (xy 211.39 164.01) (xy 211.419204 164.014475) (xy 211.430997 164.025797)
				(xy 211.427537 164.055322) (xy 211.424 164.07)
			)
		)
	)
	(zone
		(net 311)
		(net_name "Net-(J12D-~{THRMTRIP})")
		(layer "F.Cu")
		(name "$teardrop_padvia$")
		(hatch none 0.1)
		(priority 30656)
		(attr
			(teardrop
				(type padvia)
			)
		)
		(connect_pads yes
			(clearance 0)
		)
		(min_thickness 0.0254)
		(filled_areas_thickness no)
		(fill yes
			(thermal_gap 0.5)
			(thermal_bridge_width 0.5)
			(island_removal_mode 1)
			(island_area_min 10)
		)
		(polygon
			(pts
				(xy 193.0875 169.62) (xy 193.098438 169.581177) (xy 193.120195 169.566067) (xy 193.16 169.56) (xy 193.025 168.684)
				(xy 192.89 169.56) (xy 192.925281 169.564517) (xy 192.946797 169.576138) (xy 192.961995 169.608961)
				(xy 192.9625 169.62)
			)
		)
	)
	(zone
		(net 84)
		(net_name "/Com Express 7 MGMT/PWRBTN")
		(layer "F.Cu")
		(name "$teardrop_padvia$")
		(hatch none 0.1)
		(priority 31027)
		(attr
			(teardrop
				(type padvia)
			)
		)
		(connect_pads yes
			(clearance 0)
		)
		(min_thickness 0.0254)
		(filled_areas_thickness no)
		(fill yes
			(thermal_gap 0.5)
			(thermal_bridge_width 0.5)
			(island_removal_mode 1)
			(island_area_min 10)
		)
		(polygon
			(pts
				(xy 246.912001 128.8525) (xy 246.974866 128.872469) (xy 247.006844 128.898921) (xy 247.035359 128.936332)
				(xy 247.057883 128.983527) (xy 247.073094 129.041167) (xy 247.073203 129.041799) (xy 247.351 128.790001)
				(xy 247.073203 128.538203) (xy 247.058906 128.593636) (xy 247.037826 128.639521) (xy 247.010461 128.677202)
				(xy 246.979553 128.704435) (xy 246.946266 128.721473) (xy 246.913436 128.72749) (xy 246.912002 128.727501)
			)
		)
	)
	(zone
		(net 195)
		(net_name "/OCuLink/PCIe_{x4}.RX2-")
		(layer "F.Cu")
		(name "$teardrop_padvia$")
		(hatch none 0.1)
		(priority 32050)
		(attr
			(teardrop
				(type padvia)
			)
		)
		(connect_pads yes
			(clearance 0)
		)
		(min_thickness 0.0254)
		(filled_areas_thickness no)
		(fill yes
			(thermal_gap 0.5)
			(thermal_bridge_width 0.5)
			(island_removal_mode 1)
			(island_area_min 10)
		)
		(polygon
			(pts
				(xy 108.201 152.138) (xy 108.193802 152.117352) (xy 108.184208 152.085016) (xy 108.191035 152.070993)
				(xy 108.2125 152.061004) (xy 108.1 151.812) (xy 107.9875 152.061004) (xy 108.008676 152.070729)
				(xy 108.015731 152.084357) (xy 108.006198 152.117352) (xy 107.999 152.138)
			)
		)
	)
	(zone
		(net 161)
		(net_name "/2xUSB3.0+RJ45/USBSS_2.RX+")
		(layer "F.Cu")
		(name "$teardrop_padvia$")
		(hatch none 0.1)
		(priority 31501)
		(attr
			(teardrop
				(type padvia)
			)
		)
		(connect_pads yes
			(clearance 0)
		)
		(min_thickness 0.0254)
		(filled_areas_thickness no)
		(fill yes
			(thermal_gap 0.5)
			(thermal_bridge_width 0.5)
			(island_removal_mode 1)
			(island_area_min 10)
		)
		(polygon
			(pts
				(xy 181.8725 157.965416) (xy 181.876684 158.129858) (xy 181.876823 158.312562) (xy 182.0975 158.326)
				(xy 182.256688 158.172104) (xy 182.189162 158.123225) (xy 182.162819 158.109851) (xy 182.122556 158.088476)
				(xy 182.088998 158.061768) (xy 182.06602 158.022992) (xy 182.0575 157.965416)
			)
		)
	)
	(zone
		(net 730)
		(net_name "Net-(U43C-CLKOUTA+)")
		(layer "F.Cu")
		(name "$teardrop_padvia$")
		(hatch none 0.1)
		(priority 30115)
		(attr
			(teardrop
				(type padvia)
			)
		)
		(connect_pads yes
			(clearance 0)
		)
		(min_thickness 0.0254)
		(filled_areas_thickness no)
		(fill yes
			(thermal_gap 0.5)
			(thermal_bridge_width 0.5)
			(island_removal_mode 1)
			(island_area_min 10)
		)
		(polygon
			(pts
				(xy 155.1125 130.227794) (xy 155.117315 130.145733) (xy 155.131019 130.080388) (xy 155.177576 129.98712)
				(xy 155.245787 129.908657) (xy 155.301942 129.847158) (xy 155.361801 129.768339) (xy 155.05 129.559)
				(xy 154.738199 129.768339) (xy 154.835219 129.888517) (xy 154.854214 129.908658) (xy 154.907366 129.967541)
				(xy 154.949591 130.031624) (xy 154.977449 130.114008) (xy 154.9875 130.227794)
			)
		)
	)
	(zone
		(net 690)
		(net_name "/2xUSB3.0+RJ45/DA_FL-")
		(layer "F.Cu")
		(name "$teardrop_padvia$")
		(hatch none 0.1)
		(priority 31156)
		(attr
			(teardrop
				(type padvia)
			)
		)
		(connect_pads yes
			(clearance 0)
		)
		(min_thickness 0.0254)
		(filled_areas_thickness no)
		(fill yes
			(thermal_gap 0.5)
			(thermal_bridge_width 0.5)
			(island_removal_mode 1)
			(island_area_min 10)
		)
		(polygon
			(pts
				(xy 128.632927 113.066861) (xy 128.587939 113.011829) (xy 128.552832 112.934702) (xy 128.544807 112.885901)
				(xy 128.5475 112.831575) (xy 128.209293 112.849293) (xy 128.173057 113.0875) (xy 128.260646 113.083374)
				(xy 128.338104 113.089239) (xy 128.404339 113.103738) (xy 128.460384 113.125855) (xy 128.526861 113.172927)
			)
		)
	)
	(zone
		(net 633)
		(net_name "Net-(U41-A0)")
		(layer "F.Cu")
		(name "$teardrop_padvia$")
		(hatch none 0.1)
		(priority 31013)
		(attr
			(teardrop
				(type padvia)
			)
		)
		(connect_pads yes
			(clearance 0)
		)
		(min_thickness 0.0254)
		(filled_areas_thickness no)
		(fill yes
			(thermal_gap 0.5)
			(thermal_bridge_width 0.5)
			(island_removal_mode 1)
			(island_area_min 10)
		)
		(polygon
			(pts
				(xy 134.0075 83.748001) (xy 134.027469 83.685136) (xy 134.053921 83.653158) (xy 134.091332 83.624643)
				(xy 134.138527 83.602119) (xy 134.196167 83.586908) (xy 134.196799 83.586799) (xy 133.945001 83.309001)
				(xy 133.693203 83.586799) (xy 133.748636 83.601095) (xy 133.79452 83.622176) (xy 133.832201 83.649541)
				(xy 133.859434 83.680449) (xy 133.876472 83.713736) (xy 133.882489 83.746566) (xy 133.8825 83.748001)
			)
		)
	)
	(zone
		(net 378)
		(net_name "/Com Express 7 Interfaces/USB1.D+")
		(layer "F.Cu")
		(name "$teardrop_padvia$")
		(hatch none 0.1)
		(priority 30285)
		(attr
			(teardrop
				(type padvia)
			)
		)
		(connect_pads yes
			(clearance 0)
		)
		(min_thickness 0.0254)
		(filled_areas_thickness no)
		(fill yes
			(thermal_gap 0.5)
			(thermal_bridge_width 0.5)
			(island_removal_mode 1)
			(island_area_min 10)
		)
		(polygon
			(pts
				(xy 198.5575 164.07) (xy 198.555915 164.057811) (xy 198.557296 164.026262) (xy 198.572069 164.014604)
				(xy 198.604123 164.01) (xy 198.525 163.134) (xy 198.375 163.363685) (xy 198.394285 163.6231) (xy 198.381903 163.896083)
				(xy 198.3725 164.07)
			)
		)
	)
	(zone
		(net 626)
		(net_name "/PCIe redriver/TX_FG0")
		(layer "F.Cu")
		(name "$teardrop_padvia$")
		(hatch none 0.1)
		(priority 31572)
		(attr
			(teardrop
				(type padvia)
			)
		)
		(connect_pads yes
			(clearance 0)
		)
		(min_thickness 0.0254)
		(filled_areas_thickness no)
		(fill yes
			(thermal_gap 0.5)
			(thermal_bridge_width 0.5)
			(island_removal_mode 1)
			(island_area_min 10)
		)
		(polygon
			(pts
				(xy 114.297148 150.7775) (xy 114.241375 150.772762) (xy 114.198937 150.759598) (xy 114.138854 150.714675)
				(xy 114.114668 150.687582) (xy 114.075941 150.645366) (xy 114.024003 150.602919) (xy 113.898 150.79)
				(xy 113.963229 151.002254) (xy 114.080874 150.953974) (xy 114.168504 150.917706) (xy 114.297148 150.9025)
			)
		)
	)
	(zone
		(net 385)
		(net_name "/Com Express 7 Interfaces/SDIO.CMD")
		(layer "F.Cu")
		(name "$teardrop_padvia$")
		(hatch none 0.1)
		(priority 31525)
		(attr
			(teardrop
				(type padvia)
			)
		)
		(connect_pads yes
			(clearance 0)
		)
		(min_thickness 0.0254)
		(filled_areas_thickness no)
		(fill yes
			(thermal_gap 0.5)
			(thermal_bridge_width 0.5)
			(island_removal_mode 1)
			(island_area_min 10)
		)
		(polygon
			(pts
				(xy 113.198735 136.991) (xy 113.267422 136.986391) (xy 113.320974 136.974132) (xy 113.405509 136.935074)
				(xy 113.465535 136.904745) (xy 113.543895 136.880677) (xy 113.501 136.66) (xy 113.303185 136.558495)
				(xy 113.285266 136.627923) (xy 113.283526 136.682472) (xy 113.282011 136.730934) (xy 113.272629 136.77124)
				(xy 113.247498 136.798794) (xy 113.198735 136.809)
			)
		)
	)
	(zone
		(net 46)
		(net_name "Net-(U34-OFFT)")
		(layer "F.Cu")
		(name "$teardrop_padvia$")
		(hatch none 0.1)
		(priority 30719)
		(attr
			(teardrop
				(type padvia)
			)
		)
		(connect_pads yes
			(clearance 0)
		)
		(min_thickness 0.0254)
		(filled_areas_thickness no)
		(fill yes
			(thermal_gap 0.5)
			(thermal_bridge_width 0.5)
			(island_removal_mode 1)
			(island_area_min 10)
		)
		(polygon
			(pts
				(xy 244.4395 131.2) (xy 244.444848 131.167909) (xy 244.462282 131.134743) (xy 244.488737 131.108583)
				(xy 244.527163 131.087804) (xy 244.56705 131.07705) (xy 244.375 130.559) (xy 244.18295 131.07705)
				(xy 244.228153 131.089446) (xy 244.262844 131.108095) (xy 244.305426 131.158896) (xy 244.3145 131.2)
			)
		)
	)
	(zone
		(net 1)
		(net_name "GND")
		(layer "F.Cu")
		(name "$teardrop_padvia$")
		(hatch none 0.1)
		(priority 31203)
		(attr
			(teardrop
				(type padvia)
			)
		)
		(connect_pads yes
			(clearance 0)
		)
		(min_thickness 0.0254)
		(filled_areas_thickness no)
		(fill yes
			(thermal_gap 0.5)
			(thermal_bridge_width 0.5)
			(island_removal_mode 1)
			(island_area_min 10)
		)
		(polygon
			(pts
				(xy 210.425 163.949323) (xy 210.42028 164.018646) (xy 210.407244 164.071549) (xy 210.355344 164.164135)
				(xy 210.303541 164.247636) (xy 210.5 164.351) (xy 210.707644 164.274641) (xy 210.675418 164.194142)
				(xy 210.639035 164.092683) (xy 210.625 163.949323)
			)
		)
	)
	(zone
		(net 639)
		(net_name "Net-(U41-IO0_0)")
		(layer "F.Cu")
		(name "$teardrop_padvia$")
		(hatch none 0.1)
		(priority 32020)
		(attr
			(teardrop
				(type padvia)
			)
		)
		(connect_pads yes
			(clearance 0)
		)
		(min_thickness 0.0254)
		(filled_areas_thickness no)
		(fill yes
			(thermal_gap 0.5)
			(thermal_bridge_width 0.5)
			(island_removal_mode 1)
			(island_area_min 10)
		)
		(polygon
			(pts
				(xy 128.2495 84.372501) (xy 128.255822 84.372405) (xy 128.295325 84.37799) (xy 128.313548 84.392922)
				(xy 128.326496 84.4225) (xy 128.713 84.31) (xy 128.326494 84.1975) (xy 128.315378 84.224494) (xy 128.299851 84.239596)
				(xy 128.255821 84.247597) (xy 128.2495 84.247501)
			)
		)
	)
	(zone
		(net 297)
		(net_name "Net-(J12D-~{SUS_S3})")
		(layer "F.Cu")
		(name "$teardrop_padvia$")
		(hatch none 0.1)
		(priority 31855)
		(attr
			(teardrop
				(type padvia)
			)
		)
		(connect_pads yes
			(clearance 0)
		)
		(min_thickness 0.0254)
		(filled_areas_thickness no)
		(fill yes
			(thermal_gap 0.5)
			(thermal_bridge_width 0.5)
			(island_removal_mode 1)
			(island_area_min 10)
		)
		(polygon
			(pts
				(xy 182.739127 170.472485) (xy 182.686618 170.518181) (xy 182.640623 170.544768) (xy 182.554174 170.565152)
				(xy 182.538841 170.566988) (xy 182.456105 170.579323) (xy 182.499293 170.800707) (xy 182.720677 170.843895)
				(xy 182.733011 170.76116) (xy 182.753349 170.663881) (xy 182.780057 170.615841) (xy 182.827515 170.560873)
			)
		)
	)
	(zone
		(net 116)
		(net_name "/2xSFP+/KR to SFI #2/REFCLK+")
		(layer "F.Cu")
		(name "$teardrop_padvia$")
		(hatch none 0.1)
		(priority 30630)
		(attr
			(teardrop
				(type padvia)
			)
		)
		(connect_pads yes
			(clearance 0)
		)
		(min_thickness 0.0254)
		(filled_areas_thickness no)
		(fill yes
			(thermal_gap 0.5)
			(thermal_bridge_width 0.5)
			(island_removal_mode 1)
			(island_area_min 10)
		)
		(polygon
			(pts
				(xy 125.683657 141.09) (xy 125.63805 141.034807) (xy 125.614544 140.940672) (xy 125.615 140.76316)
				(xy 125.319 140.86) (xy 125.285508 141.18) (xy 125.413895 141.167745) (xy 125.551767 141.190112)
				(xy 125.674974 141.244238) (xy 125.683657 141.25)
			)
		)
	)
	(zone
		(net 2)
		(net_name "+3V3")
		(layer "F.Cu")
		(name "$teardrop_padvia$")
		(hatch none 0.1)
		(priority 30403)
		(attr
			(teardrop
				(type padvia)
			)
		)
		(connect_pads yes
			(clearance 0)
		)
		(min_thickness 0.0254)
		(filled_areas_thickness no)
		(fill yes
			(thermal_gap 0.5)
			(thermal_bridge_width 0.5)
			(island_removal_mode 1)
			(island_area_min 10)
		)
		(polygon
			(pts
				(xy 117.65 149.314) (xy 117.629597 149.269355) (xy 117.610779 149.235808) (xy 117.602205 149.203345)
				(xy 117.616303 149.176635) (xy 117.6655 149.160347) (xy 117.4 148.9) (xy 117.1345 149.160347) (xy 117.172593 149.170167)
				(xy 117.192358 149.185574) (xy 117.195352 149.2199) (xy 117.170403 149.269355) (xy 117.15 149.314)
			)
		)
	)
	(zone
		(net 627)
		(net_name "/PCIe redriver/TX_FG1")
		(layer "F.Cu")
		(name "$teardrop_padvia$")
		(hatch none 0.1)
		(priority 31058)
		(attr
			(teardrop
				(type padvia)
			)
		)
		(connect_pads yes
			(clearance 0)
		)
		(min_thickness 0.0254)
		(filled_areas_thickness no)
		(fill yes
			(thermal_gap 0.5)
			(thermal_bridge_width 0.5)
			(island_removal_mode 1)
			(island_area_min 10)
		)
		(polygon
			(pts
				(xy 112.4625 151.253) (xy 112.482273 151.193588) (xy 112.545547 151.137503) (xy 112.594172 151.115801)
				(xy 112.653532 151.101127) (xy 112.6655 151.099347) (xy 112.4 150.839) (xy 112.1345 151.099347)
				(xy 112.194639 151.112197) (xy 112.244523 151.132131) (xy 112.284642 151.158056) (xy 112.313655 151.187876)
				(xy 112.331146 151.219294) (xy 112.337479 151.251105) (xy 112.3375 151.253)
			)
		)
	)
	(zone
		(net 291)
		(net_name "/2xUSB3.0+RJ45/~{GBE0_LINK}")
		(layer "F.Cu")
		(name "$teardrop_padvia$")
		(hatch none 0.1)
		(priority 31612)
		(attr
			(teardrop
				(type padvia)
			)
		)
		(connect_pads yes
			(clearance 0)
		)
		(min_thickness 0.0254)
		(filled_areas_thickness no)
		(fill yes
			(thermal_gap 0.5)
			(thermal_bridge_width 0.5)
			(island_removal_mode 1)
			(island_area_min 10)
		)
		(polygon
			(pts
				(xy 179.4625 169.599323) (xy 179.457747 169.660452) (xy 179.44448 169.706552) (xy 179.399229 169.773244)
				(xy 179.38137 169.792341) (xy 179.312919 169.874997) (xy 179.5 170.001) (xy 179.707644 169.924641)
				(xy 179.649334 169.809581) (xy 179.605855 169.72547) (xy 179.592451 169.671061) (xy 179.5875 169.599323)
			)
		)
	)
	(zone
		(net 295)
		(net_name "/2xUSB3.0+RJ45/GbE.MDI0+")
		(layer "F.Cu")
		(name "$teardrop_padvia$")
		(hatch none 0.1)
		(priority 31642)
		(attr
			(teardrop
				(type padvia)
			)
		)
		(connect_pads yes
			(clearance 0)
		)
		(min_thickness 0.0254)
		(filled_areas_thickness no)
		(fill yes
			(thermal_gap 0.5)
			(thermal_bridge_width 0.5)
			(island_removal_mode 1)
			(island_area_min 10)
		)
		(polygon
			(pts
				(xy 163.95 149.457916) (xy 163.945244 149.497838) (xy 163.93195 149.526255) (xy 163.887871 149.558671)
				(xy 163.842738 149.573949) (xy 163.796459 149.589244) (xy 163.749997 149.612919) (xy 163.875 149.801)
				(xy 164.095677 149.801757) (xy 164.097797 149.663281) (xy 164.1 149.457916)
			)
		)
	)
	(zone
		(net 78)
		(net_name "+1V8")
		(layer "F.Cu")
		(name "$teardrop_padvia$")
		(hatch none 0.1)
		(priority 30215)
		(attr
			(teardrop
				(type padvia)
			)
		)
		(connect_pads yes
			(clearance 0)
		)
		(min_thickness 0.0254)
		(filled_areas_thickness no)
		(fill yes
			(thermal_gap 0.5)
			(thermal_bridge_width 0.5)
			(island_removal_mode 1)
			(island_area_min 10)
		)
		(polygon
			(pts
				(xy 142.689 147.925) (xy 142.68065 147.894391) (xy 142.670039 147.841406) (xy 142.683044 147.818274)
				(xy 142.719 147.801808) (xy 142.539 147.109) (xy 142.359 147.801808) (xy 142.388959 147.813742)
				(xy 142.404272 147.830064) (xy 142.406108 147.867738) (xy 142.39735 147.894391) (xy 142.389 147.925)
			)
		)
	)
	(zone
		(net 196)
		(net_name "/OCuLink/PCIe_{x4}.RX3+")
		(layer "F.Cu")
		(name "$teardrop_padvia$")
		(hatch none 0.1)
		(priority 32077)
		(attr
			(teardrop
				(type padvia)
			)
		)
		(connect_pads yes
			(clearance 0)
		)
		(min_thickness 0.0254)
		(filled_areas_thickness no)
		(fill yes
			(thermal_gap 0.5)
			(thermal_bridge_width 0.5)
			(island_removal_mode 1)
			(island_area_min 10)
		)
		(polygon
			(pts
				(xy 107.001 151.488) (xy 107.008198 151.508648) (xy 107.017792 151.540984) (xy 107.010965 151.555007)
				(xy 106.9895 151.564995) (xy 107.102 151.814) (xy 107.2145 151.564995) (xy 107.193324 151.555271)
				(xy 107.186269 151.541643) (xy 107.195802 151.508648) (xy 107.203 151.488)
			)
		)
	)
	(zone
		(net 705)
		(net_name "Net-(U24-GPIO1)")
		(layer "F.Cu")
		(name "$teardrop_padvia$")
		(hatch none 0.1)
		(priority 30812)
		(attr
			(teardrop
				(type padvia)
			)
		)
		(connect_pads yes
			(clearance 0)
		)
		(min_thickness 0.0254)
		(filled_areas_thickness no)
		(fill yes
			(thermal_gap 0.5)
			(thermal_bridge_width 0.5)
			(island_removal_mode 1)
			(island_area_min 10)
		)
		(polygon
			(pts
				(xy 260.624 86.307499) (xy 260.597391 86.302136) (xy 260.572117 86.284599) (xy 260.554478 86.258305)
				(xy 260.54305 86.220159) (xy 260.54 86.180999) (xy 259.979 86.37) (xy 260.54 86.558999) (xy 260.544627 86.511636)
				(xy 260.557018 86.476588) (xy 260.574877 86.45265) (xy 260.596015 86.438453) (xy 260.624 86.432499)
			)
		)
	)
	(zone
		(net 1)
		(net_name "GND")
		(layer "F.Cu")
		(name "$teardrop_padvia$")
		(hatch none 0.1)
		(priority 30200)
		(attr
			(teardrop
				(type padvia)
			)
		)
		(connect_pads yes
			(clearance 0)
		)
		(min_thickness 0.0254)
		(filled_areas_thickness no)
		(fill yes
			(thermal_gap 0.5)
			(thermal_bridge_width 0.5)
			(island_removal_mode 1)
			(island_area_min 10)
		)
		(polygon
			(pts
				(xy 303.05 90.496508) (xy 303.044674 90.468679) (xy 303.038273 90.437179) (xy 303.044484 90.407363)
				(xy 303.076996 90.384942) (xy 303.149496 90.375624) (xy 302.980002 90.059) (xy 302.685002 90.096625)
				(xy 302.703142 90.173338) (xy 302.687512 90.26234) (xy 302.64493 90.363127) (xy 302.613693 90.434134)
				(xy 302.6 90.496508)
			)
		)
	)
	(zone
		(net 790)
		(net_name "Net-(U38-1A)")
		(layer "F.Cu")
		(name "$teardrop_padvia$")
		(hatch none 0.1)
		(priority 31680)
		(attr
			(teardrop
				(type padvia)
			)
		)
		(connect_pads yes
			(clearance 0)
		)
		(min_thickness 0.0254)
		(filled_areas_thickness no)
		(fill yes
			(thermal_gap 0.5)
			(thermal_bridge_width 0.5)
			(island_removal_mode 1)
			(island_area_min 10)
		)
		(polygon
			(pts
				(xy 308.9545 80.083) (xy 308.948978 80.110072) (xy 308.930322 80.135611) (xy 308.903703 80.15178)
				(xy 308.864962 80.161399) (xy 308.837 80.163) (xy 309.017 80.539) (xy 309.197 80.163) (xy 309.1515 80.158387)
				(xy 309.118532 80.1461) (xy 309.084156 80.107945) (xy 309.0795 80.083)
			)
		)
	)
	(zone
		(net 1)
		(net_name "GND")
		(layer "F.Cu")
		(name "$teardrop_padvia$")
		(hatch none 0.1)
		(priority 31688)
		(attr
			(teardrop
				(type padvia)
			)
		)
		(connect_pads yes
			(clearance 0)
		)
		(min_thickness 0.0254)
		(filled_areas_thickness no)
		(fill yes
			(thermal_gap 0.5)
			(thermal_bridge_width 0.5)
			(island_removal_mode 1)
			(island_area_min 10)
		)
		(polygon
			(pts
				(xy 307.4555 82.886323) (xy 307.450682 82.955763) (xy 307.43696 83.007087) (xy 307.390245 83.082628)
				(xy 307.380702 83.094768) (xy 307.330919 83.161997) (xy 307.518 83.288) (xy 307.705081 83.161997)
				(xy 307.655299 83.094769) (xy 307.600894 83.011603) (xy 307.58581 82.958748) (xy 307.5805 82.886323)
			)
		)
	)
	(zone
		(net 598)
		(net_name "Net-(U31-~{WC})")
		(layer "F.Cu")
		(name "$teardrop_padvia$")
		(hatch none 0.1)
		(priority 31006)
		(attr
			(teardrop
				(type padvia)
			)
		)
		(connect_pads yes
			(clearance 0)
		)
		(min_thickness 0.0254)
		(filled_areas_thickness no)
		(fill yes
			(thermal_gap 0.5)
			(thermal_bridge_width 0.5)
			(island_removal_mode 1)
			(island_area_min 10)
		)
		(polygon
			(pts
				(xy 238.1875 152.492999) (xy 238.167531 152.555865) (xy 238.141079 152.587843) (xy 238.103668 152.616357)
				(xy 238.056473 152.638881) (xy 237.998833 152.654092) (xy 237.998202 152.654201) (xy 238.25 152.931999)
				(xy 238.501798 152.654201) (xy 238.446365 152.639904) (xy 238.40048 152.618824) (xy 238.362799 152.591459)
				(xy 238.335566 152.560551) (xy 238.318528 152.527264) (xy 238.312511 152.494433) (xy 238.3125 152.492999)
			)
		)
	)
	(zone
		(net 345)
		(net_name "/Com Express 7 MGMT/SER0.RX")
		(layer "F.Cu")
		(name "$teardrop_padvia$")
		(hatch none 0.1)
		(priority 31861)
		(attr
			(teardrop
				(type padvia)
			)
		)
		(connect_pads yes
			(clearance 0)
		)
		(min_thickness 0.0254)
		(filled_areas_thickness no)
		(fill yes
			(thermal_gap 0.5)
			(thermal_bridge_width 0.5)
			(island_removal_mode 1)
			(island_area_min 10)
		)
		(polygon
			(pts
				(xy 163.272485 106.660873) (xy 163.318181 106.713382) (xy 163.344768 106.759376) (xy 163.365152 106.845825)
				(xy 163.366988 106.861158) (xy 163.379323 106.943895) (xy 163.600707 106.900707) (xy 163.643895 106.679323)
				(xy 163.561158 106.666988) (xy 163.46388 106.646651) (xy 163.41584 106.619943) (xy 163.360873 106.572485)
			)
		)
	)
	(zone
		(net 665)
		(net_name "/2xSFP+/KR to SFI #1/KR_R.RX-")
		(layer "F.Cu")
		(name "$teardrop_padvia$")
		(hatch none 0.1)
		(priority 31174)
		(attr
			(teardrop
				(type padvia)
			)
		)
		(connect_pads yes
			(clearance 0)
		)
		(min_thickness 0.0254)
		(filled_areas_thickness no)
		(fill yes
			(thermal_gap 0.5)
			(thermal_bridge_width 0.5)
			(island_removal_mode 1)
			(island_area_min 10)
		)
		(polygon
			(pts
				(xy 152.84 143.17679) (xy 152.835347 143.112802) (xy 152.822777 143.062121) (xy 152.778645 142.980204)
				(xy 152.767609 142.964616) (xy 152.726024 142.899819) (xy 152.695196 142.811227) (xy 152.45 142.859)
				(xy 152.401227 143.105196) (xy 152.488185 143.107002) (xy 152.531073 143.101889) (xy 152.588443 143.095867)
				(xy 152.635848 143.099993) (xy 152.668097 143.123792) (xy 152.68 143.17679)
			)
		)
	)
	(zone
		(net 187)
		(net_name "/OCuLink/PCIe_{x4}.RX0-")
		(layer "F.Cu")
		(name "$teardrop_padvia$")
		(hatch none 0.1)
		(priority 31407)
		(attr
			(teardrop
				(type padvia)
			)
		)
		(connect_pads yes
			(clearance 0)
		)
		(min_thickness 0.0254)
		(filled_areas_thickness no)
		(fill yes
			(thermal_gap 0.5)
			(thermal_bridge_width 0.5)
			(island_removal_mode 1)
			(island_area_min 10)
		)
		(polygon
			(pts
				(xy 98.662504 165.7615) (xy 98.824035 165.756105) (xy 98.908445 165.752554) (xy 99.01014 165.757177)
				(xy 99.031 165.5365) (xy 98.881147 165.373268) (xy 98.827007 165.441935) (xy 98.817115 165.458393)
				(xy 98.792615 165.497065) (xy 98.763109 165.529279) (xy 98.721953 165.551327) (xy 98.662504 165.5595)
			)
		)
	)
	(zone
		(net 73)
		(net_name "+3V3_AON")
		(layer "F.Cu")
		(name "$teardrop_padvia$")
		(hatch none 0.1)
		(priority 30750)
		(attr
			(teardrop
				(type padvia)
			)
		)
		(connect_pads yes
			(clearance 0)
		)
		(min_thickness 0.0254)
		(filled_areas_thickness no)
		(fill yes
			(thermal_gap 0.5)
			(thermal_bridge_width 0.5)
			(island_removal_mode 1)
			(island_area_min 10)
		)
		(polygon
			(pts
				(xy 236.55 153.567) (xy 236.550337 153.58209) (xy 236.54976 153.622326) (xy 236.537946 153.66387)
				(xy 236.503367 153.699164) (xy 236.4345 153.720652) (xy 236.7 153.981) (xy 236.9655 153.720652)
				(xy 236.919062 153.709708) (xy 236.886865 153.692609) (xy 236.855422 153.648144) (xy 236.849663 153.58209)
				(xy 236.85 153.567)
			)
		)
	)
	(zone
		(net 643)
		(net_name "Net-(U41-IO0_4)")
		(layer "F.Cu")
		(name "$teardrop_padvia$")
		(hatch none 0.1)
		(priority 31080)
		(attr
			(teardrop
				(type padvia)
			)
		)
		(connect_pads yes
			(clearance 0)
		)
		(min_thickness 0.0254)
		(filled_areas_thickness no)
		(fill yes
			(thermal_gap 0.5)
			(thermal_bridge_width 0.5)
			(island_removal_mode 1)
			(island_area_min 10)
		)
		(polygon
			(pts
				(xy 127.318 86.997501) (xy 127.258588 86.977728) (xy 127.202503 86.914454) (xy 127.180801 86.865829)
				(xy 127.166127 86.806469) (xy 127.164347 86.794501) (xy 126.904 87.060001) (xy 127.164347 87.325501)
				(xy 127.177197 87.265362) (xy 127.197131 87.215478) (xy 127.223056 87.175359) (xy 127.252876 87.146346)
				(xy 127.284294 87.128855) (xy 127.316105 87.122522) (xy 127.318 87.122501)
			)
		)
	)
	(zone
		(net 344)
		(net_name "/Com Express 7 MGMT/SER0.TX")
		(layer "F.Cu")
		(name "$teardrop_padvia$")
		(hatch none 0.1)
		(priority 31057)
		(attr
			(teardrop
				(type padvia)
			)
		)
		(connect_pads yes
			(clearance 0)
		)
		(min_thickness 0.0254)
		(filled_areas_thickness no)
		(fill yes
			(thermal_gap 0.5)
			(thermal_bridge_width 0.5)
			(island_removal_mode 1)
			(island_area_min 10)
		)
		(polygon
			(pts
				(xy 124.4625 76.703) (xy 124.482273 76.643588) (xy 124.545547 76.587503) (xy 124.594172 76.565801)
				(xy 124.653532 76.551127) (xy 124.6655 76.549347) (xy 124.4 76.289) (xy 124.1345 76.549347) (xy 124.194639 76.562197)
				(xy 124.244523 76.582131) (xy 124.284642 76.608056) (xy 124.313655 76.637876) (xy 124.331146 76.669294)
				(xy 124.337479 76.701105) (xy 124.3375 76.703)
			)
		)
	)
	(zone
		(net 1)
		(net_name "GND")
		(layer "F.Cu")
		(name "$teardrop_padvia$")
		(hatch none 0.1)
		(priority 31476)
		(attr
			(teardrop
				(type padvia)
			)
		)
		(connect_pads yes
			(clearance 0)
		)
		(min_thickness 0.0254)
		(filled_areas_thickness no)
		(fill yes
			(thermal_gap 0.5)
			(thermal_bridge_width 0.5)
			(island_removal_mode 1)
			(island_area_min 10)
		)
		(polygon
			(pts
				(xy 219.125 150.107479) (xy 219.120402 150.036306) (xy 219.108218 149.980766) (xy 219.071583 149.895923)
				(xy 219.043225 149.8355) (xy 219.020677 149.757915) (xy 218.8 149.799) (xy 218.691538 149.993932)
				(xy 218.759839 150.01424) (xy 218.804663 150.018112) (xy 218.850619 150.022362) (xy 218.888968 150.033767)
				(xy 218.915249 150.059686) (xy 218.925 150.107479)
			)
		)
	)
	(zone
		(net 1)
		(net_name "GND")
		(layer "F.Cu")
		(name "$teardrop_padvia$")
		(hatch none 0.1)
		(priority 31142)
		(attr
			(teardrop
				(type padvia)
			)
		)
		(connect_pads yes
			(clearance 0)
		)
		(min_thickness 0.0254)
		(filled_areas_thickness no)
		(fill yes
			(thermal_gap 0.5)
			(thermal_bridge_width 0.5)
			(island_removal_mode 1)
			(island_area_min 10)
		)
		(polygon
			(pts
				(xy 113.4425 145.253) (xy 113.462191 145.195973) (xy 113.524971 145.143597) (xy 113.574244 145.123316)
				(xy 113.634393 145.110031) (xy 113.652823 145.107817) (xy 113.4 144.839) (xy 113.123202 145.091798)
				(xy 113.180265 145.106187) (xy 113.227553 145.127385) (xy 113.266159 145.154726) (xy 113.294077 145.18566)
				(xy 113.311331 145.218625) (xy 113.317485 145.251371) (xy 113.3175 145.253)
			)
		)
	)
	(zone
		(net 137)
		(net_name "/Com Express 7 MGMT/~{TYPE2}")
		(layer "F.Cu")
		(name "$teardrop_padvia$")
		(hatch none 0.1)
		(priority 30958)
		(attr
			(teardrop
				(type padvia)
			)
		)
		(connect_pads yes
			(clearance 0)
		)
		(min_thickness 0.0254)
		(filled_areas_thickness no)
		(fill yes
			(thermal_gap 0.5)
			(thermal_bridge_width 0.5)
			(island_removal_mode 1)
			(island_area_min 10)
		)
		(polygon
			(pts
				(xy 255.537 132.9025) (xy 255.599866 132.922469) (xy 255.631844 132.948921) (xy 255.660358 132.986332)
				(xy 255.682882 133.033527) (xy 255.698093 133.091167) (xy 255.698202 133.091798) (xy 255.976 132.84)
				(xy 255.698202 132.588202) (xy 255.683905 132.643635) (xy 255.662825 132.68952) (xy 255.63546 132.727201)
				(xy 255.604552 132.754434) (xy 255.571265 132.771472) (xy 255.538434 132.777489) (xy 255.537 132.7775)
			)
		)
	)
	(zone
		(net 980)
		(net_name "Net-(D27-C)")
		(layer "F.Cu")
		(name "$teardrop_padvia$")
		(hatch none 0.1)
		(priority 30153)
		(attr
			(teardrop
				(type padvia)
			)
		)
		(connect_pads yes
			(clearance 0)
		)
		(min_thickness 0.0254)
		(filled_areas_thickness no)
		(fill yes
			(thermal_gap 0.5)
			(thermal_bridge_width 0.5)
			(island_removal_mode 1)
			(island_area_min 10)
		)
		(polygon
			(pts
				(xy 199.80861 76.062163) (xy 199.81367 76.028644) (xy 199.829091 75.995738) (xy 199.854873 75.965425)
				(xy 199.891483 75.938919) (xy 199.938658 75.918016) (xy 199.997093 75.90393) (xy 200.06861 75.898184)
				(xy 199.70861 75.501163) (xy 199.34861 75.898184) (xy 199.418681 75.903704) (xy 199.477217 75.917567)
				(xy 199.524564 75.938253) (xy 199.561037 75.964231) (xy 199.58712 75.9942) (xy 199.602852 76.026426)
				(xy 199.60861 76.062163)
			)
		)
	)
	(zone
		(net 286)
		(net_name "/2xUSB3.0+RJ45/GbE.MDI3+")
		(layer "F.Cu")
		(name "$teardrop_padvia$")
		(hatch none 0.1)
		(priority 31637)
		(attr
			(teardrop
				(type padvia)
			)
		)
		(connect_pads yes
			(clearance 0)
		)
		(min_thickness 0.0254)
		(filled_areas_thickness no)
		(fill yes
			(thermal_gap 0.5)
			(thermal_bridge_width 0.5)
			(island_removal_mode 1)
			(island_area_min 10)
		)
		(polygon
			(pts
				(xy 135.368952 99.5525) (xy 135.253776 99.607571) (xy 135.085865 99.641171) (xy 134.907954 99.645)
				(xy 134.894 99.815) (xy 135.32 99.811316) (xy 135.323336 99.765729) (xy 135.334432 99.735779) (xy 135.368952 99.7025)
			)
		)
	)
	(zone
		(net 1)
		(net_name "GND")
		(layer "F.Cu")
		(name "$teardrop_padvia$")
		(hatch none 0.1)
		(priority 31291)
		(attr
			(teardrop
				(type padvia)
			)
		)
		(connect_pads yes
			(clearance 0)
		)
		(min_thickness 0.0254)
		(filled_areas_thickness no)
		(fill yes
			(thermal_gap 0.5)
			(thermal_bridge_width 0.5)
			(island_removal_mode 1)
			(island_area_min 10)
		)
		(polygon
			(pts
				(xy 200.88761 169.845969) (xy 200.829186 169.897728) (xy 200.778436 169.93011) (xy 200.684299 169.964708)
				(xy 200.59388 169.994741) (xy 200.674293 170.200707) (xy 200.880257 170.281121) (xy 200.91029 170.190703)
				(xy 200.945762 170.094889) (xy 200.977979 170.044885) (xy 201.029031 169.98739)
			)
		)
	)
	(zone
		(net 592)
		(net_name "Net-(U24-+5V_{IN})")
		(layer "F.Cu")
		(name "$teardrop_padvia$")
		(hatch none 0.1)
		(priority 31153)
		(attr
			(teardrop
				(type padvia)
			)
		)
		(connect_pads yes
			(clearance 0)
		)
		(min_thickness 0.0254)
		(filled_areas_thickness no)
		(fill yes
			(thermal_gap 0.5)
			(thermal_bridge_width 0.5)
			(island_removal_mode 1)
			(island_area_min 10)
		)
		(polygon
			(pts
				(xy 253.616116 86.409694) (xy 253.558589 86.386959) (xy 253.496966 86.347016) (xy 253.459327 86.30845)
				(xy 253.431216 86.260379) (xy 253.417501 86.204186) (xy 253.144293 86.449292) (xy 253.396798 86.726797)
				(xy 253.426536 86.582063) (xy 253.446087 86.553485) (xy 253.474695 86.551115)
			)
		)
	)
	(zone
		(net 51)
		(net_name "Net-(C13-Pad1)")
		(layer "F.Cu")
		(name "$teardrop_padvia$")
		(hatch none 0.1)
		(priority 30167)
		(attr
			(teardrop
				(type padvia)
			)
		)
		(connect_pads yes
			(clearance 0)
		)
		(min_thickness 0.0254)
		(filled_areas_thickness no)
		(fill yes
			(thermal_gap 0.5)
			(thermal_bridge_width 0.5)
			(island_removal_mode 1)
			(island_area_min 10)
		)
		(polygon
			(pts
				(xy 130.62 98.711) (xy 130.612567 98.765088) (xy 130.580538 98.817817) (xy 130.549909 98.83977)
				(xy 130.507061 98.855863) (xy 130.4235 98.865) (xy 130.77 99.251) (xy 131.1165 98.865) (xy 131.054264 98.860296)
				(xy 131.006539 98.847372) (xy 130.972413 98.828712) (xy 130.948436 98.805632) (xy 130.923151 98.747661)
				(xy 130.92 98.711)
			)
		)
	)
	(zone
		(net 2)
		(net_name "+3V3")
		(layer "F.Cu")
		(name "$teardrop_padvia$")
		(hatch none 0.1)
		(priority 30931)
		(attr
			(teardrop
				(type padvia)
			)
		)
		(connect_pads yes
			(clearance 0)
		)
		(min_thickness 0.0254)
		(filled_areas_thickness no)
		(fill yes
			(thermal_gap 0.5)
			(thermal_bridge_width 0.5)
			(island_removal_mode 1)
			(island_area_min 10)
		)
		(polygon
			(pts
				(xy 113.4425 148.298) (xy 113.462469 148.235134) (xy 113.488921 148.203156) (xy 113.526332 148.174642)
				(xy 113.573527 148.152118) (xy 113.631167 148.136907) (xy 113.631798 148.136798) (xy 113.38 147.859)
				(xy 113.128202 148.136798) (xy 113.183635 148.151095) (xy 113.22952 148.172175) (xy 113.267201 148.19954)
				(xy 113.294434 148.230448) (xy 113.311472 148.263735) (xy 113.317489 148.296566) (xy 113.3175 148.298)
			)
		)
	)
	(zone
		(net 51)
		(net_name "Net-(C13-Pad1)")
		(layer "F.Cu")
		(name "$teardrop_padvia$")
		(hatch none 0.1)
		(priority 30095)
		(attr
			(teardrop
				(type padvia)
			)
		)
		(connect_pads yes
			(clearance 0)
		)
		(min_thickness 0.0254)
		(filled_areas_thickness no)
		(fill yes
			(thermal_gap 0.5)
			(thermal_bridge_width 0.5)
			(island_removal_mode 1)
			(island_area_min 10)
		)
		(polygon
			(pts
				(xy 131.374 102.99) (xy 131.317939 102.982567) (xy 131.262329 102.950538) (xy 131.238554 102.919894)
				(xy 131.220421 102.87702) (xy 131.208103 102.7935) (xy 130.769 103.14) (xy 131.208103 103.4865)
				(xy 131.214918 103.425202) (xy 131.229503 103.377953) (xy 131.249612 103.343687) (xy 131.273934 103.31947)
				(xy 131.334458 103.293449) (xy 131.374 103.29)
			)
		)
	)
	(zone
		(net 526)
		(net_name "/Backplane/~{PRSNT}")
		(layer "F.Cu")
		(name "$teardrop_padvia$")
		(hatch none 0.1)
		(priority 31002)
		(attr
			(teardrop
				(type padvia)
			)
		)
		(connect_pads yes
			(clearance 0)
		)
		(min_thickness 0.0254)
		(filled_areas_thickness no)
		(fill yes
			(thermal_gap 0.5)
			(thermal_bridge_width 0.5)
			(island_removal_mode 1)
			(island_area_min 10)
		)
		(polygon
			(pts
				(xy 219.870501 133.5175) (xy 219.807635 133.497531) (xy 219.775657 133.471079) (xy 219.747143 133.433668)
				(xy 219.724619 133.386473) (xy 219.709408 133.328833) (xy 219.709299 133.328202) (xy 219.431501 133.58)
				(xy 219.709299 133.831798) (xy 219.723596 133.776365) (xy 219.744676 133.73048) (xy 219.772041 133.692799)
				(xy 219.802949 133.665566) (xy 219.836236 133.648528) (xy 219.869067 133.642511) (xy 219.870501 133.6425)
			)
		)
	)
	(zone
		(net 136)
		(net_name "/Com Express 7 MGMT/~{TYPE0}")
		(layer "F.Cu")
		(name "$teardrop_padvia$")
		(hatch none 0.1)
		(priority 30827)
		(attr
			(teardrop
				(type padvia)
			)
		)
		(connect_pads yes
			(clearance 0)
		)
		(min_thickness 0.0254)
		(filled_areas_thickness no)
		(fill yes
			(thermal_gap 0.5)
			(thermal_bridge_width 0.5)
			(island_removal_mode 1)
			(island_area_min 10)
		)
		(polygon
			(pts
				(xy 252.404 132.9025) (xy 252.465633 132.922897) (xy 252.495171 132.949048) (xy 252.519909 132.98624)
				(xy 252.54256 133.071967) (xy 252.825 132.61) (xy 252.524 132.466775) (xy 252.518905 132.576931)
				(xy 252.503241 132.666495) (xy 252.483754 132.718913) (xy 252.457485 132.75557) (xy 252.432923 132.771862)
				(xy 252.404215 132.7775) (xy 252.404 132.7775)
			)
		)
	)
	(zone
		(net 2)
		(net_name "+3V3")
		(layer "F.Cu")
		(hatch edge 0.5)
		(priority 25)
		(connect_pads yes
			(clearance 0.15)
		)
		(min_thickness 0.25)
		(filled_areas_thickness no)
		(fill yes
			(thermal_gap 0.2)
			(thermal_bridge_width 0.5)
			(smoothing fillet)
			(radius 0.2)
		)
		(polygon
			(pts
				(xy 303.75 98.9) (xy 299.7 98.9) (xy 299.7 102.62) (xy 303.75 102.62)
			)
		)
	)
	(zone
		(net 310)
		(net_name "/Com Express 7 MGMT/~{BIOS_DIS0}")
		(layer "F.Cu")
		(name "$teardrop_padvia$")
		(hatch none 0.1)
		(priority 31299)
		(attr
			(teardrop
				(type padvia)
			)
		)
		(connect_pads yes
			(clearance 0)
		)
		(min_thickness 0.0254)
		(filled_areas_thickness no)
		(fill yes
			(thermal_gap 0.5)
			(thermal_bridge_width 0.5)
			(island_removal_mode 1)
			(island_area_min 10)
		)
		(polygon
			(pts
				(xy 216.295969 82.09739) (xy 216.347728 82.155814) (xy 216.380111 82.206564) (xy 216.414709 82.300702)
				(xy 216.444742 82.39112) (xy 216.650707 82.310707) (xy 216.73112 82.104742) (xy 216.640702 82.074709)
				(xy 216.544888 82.039237) (xy 216.494885 82.007021) (xy 216.43739 81.955969)
			)
		)
	)
	(zone
		(net 69)
		(net_name "Net-(C48-Pad2)")
		(layer "F.Cu")
		(name "$teardrop_padvia$")
		(hatch none 0.1)
		(priority 32133)
		(attr
			(teardrop
				(type padvia)
			)
		)
		(connect_pads yes
			(clearance 0)
		)
		(min_thickness 0.0254)
		(filled_areas_thickness no)
		(fill yes
			(thermal_gap 0.5)
			(thermal_bridge_width 0.5)
			(island_removal_mode 1)
			(island_area_min 10)
		)
		(polygon
			(pts
				(xy 312.680499 103.687078) (xy 312.679084 103.670352) (xy 312.679109 103.630027) (xy 312.688236 103.609733)
				(xy 312.708564 103.591476) (xy 312.619999 103.347999) (xy 312.528602 103.584639) (xy 312.547759 103.603529)
				(xy 312.556813 103.624025) (xy 312.55704 103.668859) (xy 312.555499 103.687078)
			)
		)
	)
	(zone
		(net 532)
		(net_name "/Backplane/PCIe_{x2}.RX0+")
		(layer "F.Cu")
		(name "$teardrop_padvia$")
		(hatch none 0.1)
		(priority 32069)
		(attr
			(teardrop
				(type padvia)
			)
		)
		(connect_pads yes
			(clearance 0)
		)
		(min_thickness 0.0254)
		(filled_areas_thickness no)
		(fill yes
			(thermal_gap 0.5)
			(thermal_bridge_width 0.5)
			(island_removal_mode 1)
			(island_area_min 10)
		)
		(polygon
			(pts
				(xy 314.81 160.011) (xy 314.830648 160.003802) (xy 314.862984 159.994208) (xy 314.877007 160.001035)
				(xy 314.886995 160.0225) (xy 315.136 159.91) (xy 314.886995 159.7975) (xy 314.877271 159.818676)
				(xy 314.863643 159.825731) (xy 314.830648 159.816198) (xy 314.81 159.809)
			)
		)
	)
	(zone
		(net 684)
		(net_name "Net-(U45C-ST)")
		(layer "F.Cu")
		(name "$teardrop_padvia$")
		(hatch none 0.1)
		(priority 30943)
		(attr
			(teardrop
				(type padvia)
			)
		)
		(connect_pads yes
			(clearance 0)
		)
		(min_thickness 0.0254)
		(filled_areas_thickness no)
		(fill yes
			(thermal_gap 0.5)
			(thermal_bridge_width 0.5)
			(island_removal_mode 1)
			(island_area_min 10)
		)
		(polygon
			(pts
				(xy 125.2575 134.442) (xy 125.237531 134.504866) (xy 125.211079 134.536844) (xy 125.173668 134.565358)
				(xy 125.126473 134.587882) (xy 125.068833 134.603093) (xy 125.068202 134.603202) (xy 125.32 134.881)
				(xy 125.571798 134.603202) (xy 125.516365 134.588905) (xy 125.47048 134.567825) (xy 125.432799 134.54046)
				(xy 125.405566 134.509552) (xy 125.388528 134.476265) (xy 125.382511 134.443434) (xy 125.3825 134.442)
			)
		)
	)
	(zone
		(net 781)
		(net_name "/Misc/TACH_{B3V3}")
		(layer "F.Cu")
		(name "$teardrop_padvia$")
		(hatch none 0.1)
		(priority 30810)
		(attr
			(teardrop
				(type padvia)
			)
		)
		(connect_pads yes
			(clearance 0)
		)
		(min_thickness 0.0254)
		(filled_areas_thickness no)
		(fill yes
			(thermal_gap 0.5)
			(thermal_bridge_width 0.5)
			(island_removal_mode 1)
			(island_area_min 10)
		)
		(polygon
			(pts
				(xy 259.336 82.6225) (xy 259.362609 82.627863) (xy 259.387883 82.6454) (xy 259.405522 82.671694)
				(xy 259.41695 82.70984) (xy 259.42 82.749) (xy 259.981 82.56) (xy 259.42 82.371) (xy 259.415373 82.418363)
				(xy 259.402982 82.453411) (xy 259.385123 82.477349) (xy 259.363985 82.491546) (xy 259.336 82.4975)
			)
		)
	)
	(zone
		(net 1)
		(net_name "GND")
		(layer "F.Cu")
		(name "$teardrop_padvia$")
		(hatch none 0.1)
		(priority 30550)
		(attr
			(teardrop
				(type padvia)
			)
		)
		(connect_pads yes
			(clearance 0)
		)
		(min_thickness 0.0254)
		(filled_areas_thickness no)
		(fill yes
			(thermal_gap 0.5)
			(thermal_bridge_width 0.5)
			(island_removal_mode 1)
			(island_area_min 10)
		)
		(polygon
			(pts
				(xy 188.125 152.07) (xy 188.121667 152.055514) (xy 188.11881 152.02539) (xy 188.130964 152.014349)
				(xy 188.16 152.01) (xy 188.025 151.134) (xy 187.89 152.01) (xy 187.919334 152.014475) (xy 187.931358 152.025801)
				(xy 187.928333 152.055514) (xy 187.925 152.07)
			)
		)
	)
	(zone
		(net 429)
		(net_name "/2xSFP+/MDIO1.MDC")
		(layer "F.Cu")
		(name "$teardrop_padvia$")
		(hatch none 0.1)
		(priority 30717)
		(attr
			(teardrop
				(type padvia)
			)
		)
		(connect_pads yes
			(clearance 0)
		)
		(min_thickness 0.0254)
		(filled_areas_thickness no)
		(fill yes
			(thermal_gap 0.5)
			(thermal_bridge_width 0.5)
			(island_removal_mode 1)
			(island_area_min 10)
		)
		(polygon
			(pts
				(xy 197.9375 155.75) (xy 197.929688 155.788122) (xy 197.911133 155.803671) (xy 197.875 155.81) (xy 198.025 156.686)
				(xy 198.136651 155.81) (xy 198.100724 155.80548) (xy 198.078718 155.793837) (xy 198.063037 155.760971)
				(xy 198.0625 155.75)
			)
		)
	)
	(zone
		(net 2)
		(net_name "+3V3")
		(layer "F.Cu")
		(name "$teardrop_padvia$")
		(hatch none 0.1)
		(priority 31509)
		(attr
			(teardrop
				(type padvia)
			)
		)
		(connect_pads yes
			(clearance 0)
		)
		(min_thickness 0.0254)
		(filled_areas_thickness no)
		(fill yes
			(thermal_gap 0.5)
			(thermal_bridge_width 0.5)
			(island_removal_mode 1)
			(island_area_min 10)
		)
		(polygon
			(pts
				(xy 212.946591 127.224) (xy 212.910253 127.219249) (xy 212.885214 127.205995) (xy 212.859893 127.162659)
				(xy 212.850176 127.109185) (xy 212.84075 127.054682) (xy 212.819835 127.002646) (xy 212.629 127.121)
				(xy 212.598249 127.341677) (xy 212.714918 127.373057) (xy 212.736457 127.381584) (xy 212.822626 127.410868)
				(xy 212.946591 127.424)
			)
		)
	)
	(zone
		(net 372)
		(net_name "/Com Express 7 MGMT/I2C.SDA")
		(layer "F.Cu")
		(name "$teardrop_padvia$")
		(hatch none 0.1)
		(priority 32144)
		(attr
			(teardrop
				(type padvia)
			)
		)
		(connect_pads yes
			(clearance 0)
		)
		(min_thickness 0.0254)
		(filled_areas_thickness no)
		(fill yes
			(thermal_gap 0.5)
			(thermal_bridge_width 0.5)
			(island_removal_mode 1)
			(island_area_min 10)
		)
		(polygon
			(pts
				(xy 239.46 153.8995) (xy 239.421177 153.888563) (xy 239.406067 153.866805) (xy 239.4 153.827) (xy 239.249 153.962)
				(xy 239.4 154.097) (xy 239.404517 154.061719) (xy 239.416138 154.040203) (xy 239.448961 154.025005)
				(xy 239.46 154.0245)
			)
		)
	)
	(zone
		(net 1)
		(net_name "GND")
		(layer "F.Cu")
		(name "$teardrop_padvia$")
		(hatch none 0.1)
		(priority 30579)
		(attr
			(teardrop
				(type padvia)
			)
		)
		(connect_pads yes
			(clearance 0)
		)
		(min_thickness 0.0254)
		(filled_areas_thickness no)
		(fill yes
			(thermal_gap 0.5)
			(thermal_bridge_width 0.5)
			(island_removal_mode 1)
			(island_area_min 10)
		)
		(polygon
			(pts
				(xy 217.625 157.62) (xy 217.621667 157.605514) (xy 217.61881 157.57539) (xy 217.630964 157.564349)
				(xy 217.66 157.56) (xy 217.525 156.684) (xy 217.39 157.56) (xy 217.419334 157.564475) (xy 217.431358 157.575801)
				(xy 217.428333 157.605514) (xy 217.425 157.62)
			)
		)
	)
	(zone
		(net 295)
		(net_name "/2xUSB3.0+RJ45/GbE.MDI0+")
		(layer "F.Cu")
		(name "$teardrop_padvia$")
		(hatch none 0.1)
		(priority 31665)
		(attr
			(teardrop
				(type padvia)
			)
		)
		(connect_pads yes
			(clearance 0)
		)
		(min_thickness 0.0254)
		(filled_areas_thickness no)
		(fill yes
			(thermal_gap 0.5)
			(thermal_bridge_width 0.5)
			(island_removal_mode 1)
			(island_area_min 10)
		)
		(polygon
			(pts
				(xy 135.315051 111.278884) (xy 135.239237 111.326638) (xy 135.123703 111.349903) (xy 134.911303 111.345)
				(xy 134.894293 111.515707) (xy 135.32 111.514677) (xy 135.336762 111.46183) (xy 135.393994 111.407296)
				(xy 135.421116 111.384949)
			)
		)
	)
	(zone
		(net 247)
		(net_name "/Com Express 7 Interfaces/PCIe_{B2Bx4}.TX2-")
		(layer "F.Cu")
		(name "$teardrop_padvia$")
		(hatch none 0.1)
		(priority 30279)
		(attr
			(teardrop
				(type padvia)
			)
		)
		(connect_pads yes
			(clearance 0)
		)
		(min_thickness 0.0254)
		(filled_areas_thickness no)
		(fill yes
			(thermal_gap 0.5)
			(thermal_bridge_width 0.5)
			(island_removal_mode 1)
			(island_area_min 10)
		)
		(polygon
			(pts
				(xy 188.3685 167.75) (xy 188.379599 167.923112) (xy 188.394216 168.15051) (xy 188.391181 168.285138)
				(xy 188.375 168.437021) (xy 188.525 168.686) (xy 188.608295 167.81) (xy 188.577864 167.805523) (xy 188.565097 167.794185)
				(xy 188.56742 167.764227) (xy 188.5705 167.75)
			)
		)
	)
	(zone
		(net 1)
		(net_name "GND")
		(layer "F.Cu")
		(name "$teardrop_padvia$")
		(hatch none 0.1)
		(priority 31188)
		(attr
			(teardrop
				(type padvia)
			)
		)
		(connect_pads yes
			(clearance 0)
		)
		(min_thickness 0.0254)
		(filled_areas_thickness no)
		(fill yes
			(thermal_gap 0.5)
			(thermal_bridge_width 0.5)
			(island_removal_mode 1)
			(island_area_min 10)
		)
		(polygon
			(pts
				(xy 215.625 150.321677) (xy 215.62972 150.252353) (xy 215.642756 150.199449) (xy 215.694658 150.10686)
				(xy 215.746458 150.023363) (xy 215.55 149.92) (xy 215.342355 149.996358) (xy 215.374583 150.076861)
				(xy 215.410965 150.178318) (xy 215.425 150.321677)
			)
		)
	)
	(zone
		(net 1)
		(net_name "GND")
		(layer "F.Cu")
		(name "$teardrop_padvia$")
		(hatch none 0.1)
		(priority 30728)
		(attr
			(teardrop
				(type padvia)
			)
		)
		(connect_pads yes
			(clearance 0)
		)
		(min_thickness 0.0254)
		(filled_areas_thickness no)
		(fill yes
			(thermal_gap 0.5)
			(thermal_bridge_width 0.5)
			(island_removal_mode 1)
			(island_area_min 10)
		)
		(polygon
			(pts
				(xy 304.0625 93.22) (xy 304.057179 93.251735) (xy 304.039931 93.284435) (xy 304.013462 93.310626)
				(xy 303.975036 93.331555) (xy 303.93295 93.34295) (xy 304.125 93.861) (xy 304.31705 93.34295) (xy 304.272526 93.330591)
				(xy 304.2384 93.311992) (xy 304.196464 93.261197) (xy 304.1875 93.22)
			)
		)
	)
	(zone
		(net 1)
		(net_name "GND")
		(layer "F.Cu")
		(name "$teardrop_padvia$")
		(hatch none 0.1)
		(priority 30555)
		(attr
			(teardrop
				(type padvia)
			)
		)
		(connect_pads yes
			(clearance 0)
		)
		(min_thickness 0.0254)
		(filled_areas_thickness no)
		(fill yes
			(thermal_gap 0.5)
			(thermal_bridge_width 0.5)
			(island_removal_mode 1)
			(island_area_min 10)
		)
		(polygon
			(pts
				(xy 185.925 162.2) (xy 185.928333 162.214486) (xy 185.93119 162.24461) (xy 185.919036 162.255651)
				(xy 185.89 162.26) (xy 186.025 163.136) (xy 186.16 162.26) (xy 186.130666 162.255525) (xy 186.118642 162.244199)
				(xy 186.121667 162.214486) (xy 186.125 162.2)
			)
		)
	)
	(zone
		(net 85)
		(net_name "/Com Express 7 MGMT/MAFS_POWER")
		(layer "F.Cu")
		(name "$teardrop_padvia$")
		(hatch none 0.1)
		(priority 30231)
		(attr
			(teardrop
				(type padvia)
			)
		)
		(connect_pads yes
			(clearance 0)
		)
		(min_thickness 0.0254)
		(filled_areas_thickness no)
		(fill yes
			(thermal_gap 0.5)
			(thermal_bridge_width 0.5)
			(island_removal_mode 1)
			(island_area_min 10)
		)
		(polygon
			(pts
				(xy 252.88731 165.775179) (xy 252.870071 165.758259) (xy 252.819784 165.70661) (xy 252.772348 165.641405)
				(xy 252.740006 165.558223) (xy 252.735 165.452643) (xy 252.439293 165.529293) (xy 252.38071 165.85)
				(xy 252.434091 165.845991) (xy 252.481248 165.851406) (xy 252.564581 165.8865) (xy 252.655579 165.967041)
				(xy 252.675179 165.98731)
			)
		)
	)
	(zone
		(net 1)
		(net_name "GND")
		(layer "F.Cu")
		(name "$teardrop_padvia$")
		(hatch none 0.1)
		(priority 30528)
		(attr
			(teardrop
				(type padvia)
			)
		)
		(connect_pads yes
			(clearance 0)
		)
		(min_thickness 0.0254)
		(filled_areas_thickness no)
		(fill yes
			(thermal_gap 0.5)
			(thermal_bridge_width 0.5)
			(island_removal_mode 1)
			(island_area_min 10)
		)
		(polygon
			(pts
				(xy 220.625 157.62) (xy 220.621667 157.605514) (xy 220.61881 157.57539) (xy 220.630964 157.564349)
				(xy 220.66 157.56) (xy 220.525 156.684) (xy 220.39 157.56) (xy 220.419334 157.564475) (xy 220.431358 157.575801)
				(xy 220.428333 157.605514) (xy 220.425 157.62)
			)
		)
	)
	(zone
		(net 88)
		(net_name "/Com Express 7 Interfaces/PCIe_{B2Ax4}.RX2-")
		(layer "F.Cu")
		(name "$teardrop_padvia$")
		(hatch none 0.1)
		(priority 31425)
		(attr
			(teardrop
				(type padvia)
			)
		)
		(connect_pads yes
			(clearance 0)
		)
		(min_thickness 0.0254)
		(filled_areas_thickness no)
		(fill yes
			(thermal_gap 0.5)
			(thermal_bridge_width 0.5)
			(island_removal_mode 1)
			(island_area_min 10)
		)
		(polygon
			(pts
				(xy 290.542 75.019852) (xy 290.547395 75.181383) (xy 290.550945 75.265794) (xy 290.546323 75.367488)
				(xy 290.767 75.388348) (xy 290.930231 75.238495) (xy 290.861562 75.184355) (xy 290.845108 75.174464)
				(xy 290.806435 75.149964) (xy 290.774221 75.120457) (xy 290.752173 75.079301) (xy 290.744 75.019852)
			)
		)
	)
	(zone
		(net 423)
		(net_name "/2xSFP+/I2C_{LED}.SCL")
		(layer "F.Cu")
		(name "$teardrop_padvia$")
		(hatch none 0.1)
		(priority 31098)
		(attr
			(teardrop
				(type padvia)
			)
		)
		(connect_pads yes
			(clearance 0)
		)
		(min_thickness 0.0254)
		(filled_areas_thickness no)
		(fill yes
			(thermal_gap 0.5)
			(thermal_bridge_width 0.5)
			(island_removal_mode 1)
			(island_area_min 10)
		)
		(polygon
			(pts
				(xy 161.4875 155.917) (xy 161.467727 155.976412) (xy 161.404453 156.032496) (xy 161.355828 156.054198)
				(xy 161.296469 156.068872) (xy 161.2845 156.070652) (xy 161.55 156.331) (xy 161.8155 156.070652)
				(xy 161.755362 156.057803) (xy 161.705478 156.037869) (xy 161.665358 156.011944) (xy 161.636345 155.982124)
				(xy 161.618854 155.950706) (xy 161.612521 155.918895) (xy 161.6125 155.917)
			)
		)
	)
	(zone
		(net 1)
		(net_name "GND")
		(layer "F.Cu")
		(name "$teardrop_padvia$")
		(hatch none 0.1)
		(priority 31202)
		(attr
			(teardrop
				(type padvia)
			)
		)
		(connect_pads yes
			(clearance 0)
		)
		(min_thickness 0.0254)
		(filled_areas_thickness no)
		(fill yes
			(thermal_gap 0.5)
			(thermal_bridge_width 0.5)
			(island_removal_mode 1)
			(island_area_min 10)
		)
		(polygon
			(pts
				(xy 190.925 157.499323) (xy 190.92028 157.568646) (xy 190.907244 157.621549) (xy 190.855344 157.714135)
				(xy 190.803541 157.797636) (xy 191 157.901) (xy 191.207644 157.824641) (xy 191.175418 157.744142)
				(xy 191.139035 157.642683) (xy 191.125 157.499323)
			)
		)
	)
	(zone
		(net 78)
		(net_name "+1V8")
		(layer "F.Cu")
		(name "$teardrop_padvia$")
		(hatch none 0.1)
		(priority 31878)
		(attr
			(teardrop
				(type padvia)
			)
		)
		(connect_pads yes
			(clearance 0)
		)
		(min_thickness 0.0254)
		(filled_areas_thickness no)
		(fill yes
			(thermal_gap 0.5)
			(thermal_bridge_width 0.5)
			(island_removal_mode 1)
			(island_area_min 10)
		)
		(polygon
			(pts
				(xy 123.980873 149.107515) (xy 124.033382 149.061819) (xy 124.079376 149.035231) (xy 124.165824 149.014847)
				(xy 124.18116 149.013011) (xy 124.263895 149.000677) (xy 124.220707 148.779293) (xy 123.999323 148.736105)
				(xy 123.986988 148.818841) (xy 123.966651 148.916119) (xy 123.939943 148.964159) (xy 123.892485 149.019127)
			)
		)
	)
	(zone
		(net 52)
		(net_name "+5V")
		(layer "F.Cu")
		(name "$teardrop_padvia$")
		(hatch none 0.1)
		(priority 31276)
		(attr
			(teardrop
				(type padvia)
			)
		)
		(connect_pads yes
			(clearance 0)
		)
		(min_thickness 0.0254)
		(filled_areas_thickness no)
		(fill yes
			(thermal_gap 0.5)
			(thermal_bridge_width 0.5)
			(island_removal_mode 1)
			(island_area_min 10)
		)
		(polygon
			(pts
				(xy 195.60861 73.701486) (xy 195.603897 73.779397) (xy 195.59091 73.838181) (xy 195.548809 73.929211)
				(xy 195.50611 74.014384) (xy 195.70861 74.103163) (xy 195.91111 74.014384) (xy 195.868411 73.929213)
				(xy 195.825743 73.83638) (xy 195.813166 73.778241) (xy 195.80861 73.701486)
			)
		)
	)
	(zone
		(net 1)
		(net_name "GND")
		(layer "F.Cu")
		(name "$teardrop_padvia$")
		(hatch none 0.1)
		(priority 31236)
		(attr
			(teardrop
				(type padvia)
			)
		)
		(connect_pads yes
			(clearance 0)
		)
		(min_thickness 0.0254)
		(filled_areas_thickness no)
		(fill yes
			(thermal_gap 0.5)
			(thermal_bridge_width 0.5)
			(island_removal_mode 1)
			(island_area_min 10)
		)
		(polygon
			(pts
				(xy 178.125 150.325677) (xy 178.129737 150.234676) (xy 178.142896 150.167587) (xy 178.175418 150.080855)
				(xy 178.207644 150.000358) (xy 178 149.924) (xy 177.803541 150.027363) (xy 177.855343 150.110863)
				(xy 177.904833 150.196955) (xy 177.919614 150.25216) (xy 177.925 150.325677)
			)
		)
	)
	(zone
		(net 594)
		(net_name "Net-(U24-GPIO4)")
		(layer "F.Cu")
		(name "$teardrop_padvia$")
		(hatch none 0.1)
		(priority 30485)
		(attr
			(teardrop
				(type padvia)
			)
		)
		(connect_pads yes
			(clearance 0)
		)
		(min_thickness 0.0254)
		(filled_areas_thickness no)
		(fill yes
			(thermal_gap 0.5)
			(thermal_bridge_width 0.5)
			(island_removal_mode 1)
			(island_area_min 10)
		)
		(polygon
			(pts
				(xy 253.539445 85.751056) (xy 253.484067 85.667714) (xy 253.447848 85.537725) (xy 253.441485 85.457135)
				(xy 253.445002 85.369526) (xy 253.149295 85.449292) (xy 253.094528 85.769999) (xy 253.245687 85.760982)
				(xy 253.313218 85.770826) (xy 253.372029 85.789091) (xy 253.451057 85.839444)
			)
		)
	)
	(zone
		(net 107)
		(net_name "/2xSFP+/KR to SFI #1/CLK+")
		(layer "F.Cu")
		(name "$teardrop_padvia$")
		(hatch none 0.1)
		(priority 30036)
		(attr
			(teardrop
				(type padvia)
			)
		)
		(connect_pads yes
			(clearance 0)
		)
		(min_thickness 0.0254)
		(filled_areas_thickness no)
		(fill yes
			(thermal_gap 0.5)
			(thermal_bridge_width 0.5)
			(island_removal_mode 1)
			(island_area_min 10)
		)
		(polygon
			(pts
				(xy 141.145 139.644) (xy 141.128974 139.454959) (xy 141.113201 139.345519) (xy 141.083178 139.122038)
				(xy 141.07 138.884507) (xy 140.61 138.934) (xy 140.455368 139.46) (xy 140.623489 139.465389) (xy 140.766914 139.483115)
				(xy 140.849429 139.504203) (xy 140.914344 139.533341) (xy 140.950086 139.560915) (xy 140.973772 139.593797)
				(xy 140.985 139.644)
			)
		)
	)
	(zone
		(net 1)
		(net_name "GND")
		(layer "F.Cu")
		(name "$teardrop_padvia$")
		(hatch none 0.1)
		(priority 30618)
		(attr
			(teardrop
				(type padvia)
			)
		)
		(connect_pads yes
			(clearance 0)
		)
		(min_thickness 0.0254)
		(filled_areas_thickness no)
		(fill yes
			(thermal_gap 0.5)
			(thermal_bridge_width 0.5)
			(island_removal_mode 1)
			(island_area_min 10)
		)
		(polygon
			(pts
				(xy 215.625 164.07) (xy 215.621667 164.055514) (xy 215.61881 164.02539) (xy 215.630964 164.014349)
				(xy 215.66 164.01) (xy 215.525 163.134) (xy 215.39 164.01) (xy 215.419334 164.014475) (xy 215.431358 164.025801)
				(xy 215.428333 164.055514) (xy 215.425 164.07)
			)
		)
	)
	(zone
		(net 118)
		(net_name "/2xSFP+/KR to SFI #2/REFCLK-")
		(layer "F.Cu")
		(name "$teardrop_padvia$")
		(hatch none 0.1)
		(priority 31162)
		(attr
			(teardrop
				(type padvia)
			)
		)
		(connect_pads yes
			(clearance 0)
		)
		(min_thickness 0.0254)
		(filled_areas_thickness no)
		(fill yes
			(thermal_gap 0.5)
			(thermal_bridge_width 0.5)
			(island_removal_mode 1)
			(island_area_min 10)
		)
		(polygon
			(pts
				(xy 126.97321 141.63) (xy 127.010305 141.634788) (xy 127.034569 141.648304) (xy 127.053295 141.690007)
				(xy 127.04811 141.778926) (xy 127.041285 141.844222) (xy 127.044804 141.908773) (xy 127.291 141.86)
				(xy 127.338773 141.614804) (xy 127.240798 141.578876) (xy 127.185383 141.54239) (xy 127.101398 141.492365)
				(xy 127.045772 141.476125) (xy 126.97321 141.47)
			)
		)
	)
	(zone
		(net 541)
		(net_name "Net-(Q9-B)")
		(layer "F.Cu")
		(name "$teardrop_padvia$")
		(hatch none 0.1)
		(priority 30166)
		(attr
			(teardrop
				(type padvia)
			)
		)
		(connect_pads yes
			(clearance 0)
		)
		(min_thickness 0.0254)
		(filled_areas_thickness no)
		(fill yes
			(thermal_gap 0.5)
			(thermal_bridge_width 0.5)
			(island_removal_mode 1)
			(island_area_min 10)
		)
		(polygon
			(pts
				(xy 119.917192 142.528613) (xy 119.963144 142.577894) (xy 120.008841 142.642008) (xy 120.041916 142.721236)
				(xy 120.05 142.815859) (xy 120.550707 142.811707) (xy 120.579678 142.511) (xy 120.455399 142.513833)
				(xy 120.345498 142.506089) (xy 120.25744 142.490024) (xy 120.181318 142.465656) (xy 120.122 142.436264)
				(xy 120.072616 142.40033) (xy 120.058613 142.387192)
			)
		)
	)
	(zone
		(net 382)
		(net_name "Net-(J12D-~{CB_RESET})")
		(layer "F.Cu")
		(name "$teardrop_padvia$")
		(hatch none 0.1)
		(priority 31982)
		(attr
			(teardrop
				(type padvia)
			)
		)
		(connect_pads yes
			(clearance 0)
		)
		(min_thickness 0.0254)
		(filled_areas_thickness no)
		(fill yes
			(thermal_gap 0.5)
			(thermal_bridge_width 0.5)
			(island_removal_mode 1)
			(island_area_min 10)
		)
		(polygon
			(pts
				(xy 308.3185 155.617) (xy 308.329438 155.578177) (xy 308.351195 155.563067) (xy 308.391 155.557)
				(xy 308.256 155.181) (xy 308.121 155.557) (xy 308.156281 155.561517) (xy 308.177797 155.573138)
				(xy 308.192995 155.605961) (xy 308.1935 155.617)
			)
		)
	)
	(zone
		(net 153)
		(net_name "/2xUSB3.0+RJ45/DD-")
		(layer "F.Cu")
		(name "$teardrop_padvia$")
		(hatch none 0.1)
		(priority 31145)
		(attr
			(teardrop
				(type padvia)
			)
		)
		(connect_pads yes
			(clearance 0)
		)
		(min_thickness 0.0254)
		(filled_areas_thickness no)
		(fill yes
			(thermal_gap 0.5)
			(thermal_bridge_width 0.5)
			(island_removal_mode 1)
			(island_area_min 10)
		)
		(polygon
			(pts
				(xy 125.973139 101.472927) (xy 126.057997 101.417339) (xy 126.116278 101.398091) (xy 126.184276 101.386472)
				(xy 126.326943 101.3875) (xy 126.290707 101.149293) (xy 125.9525 101.131575) (xy 125.949601 101.224947)
				(xy 125.913761 101.309194) (xy 125.867073 101.366861)
			)
		)
	)
	(zone
		(net 333)
		(net_name "/Com Express 7 Interfaces/SDIO.DAT3")
		(layer "F.Cu")
		(name "$teardrop_padvia$")
		(hatch none 0.1)
		(priority 31329)
		(attr
			(teardrop
				(type padvia)
			)
		)
		(connect_pads yes
			(clearance 0)
		)
		(min_thickness 0.0254)
		(filled_areas_thickness no)
		(fill yes
			(thermal_gap 0.5)
			(thermal_bridge_width 0.5)
			(island_removal_mode 1)
			(island_area_min 10)
		)
		(polygon
			(pts
				(xy 113.099323 137.491) (xy 113.169681 137.495704) (xy 113.223332 137.508629) (xy 113.314163 137.557123)
				(xy 113.406705 137.610214) (xy 113.501 137.41) (xy 113.417397 137.205356) (xy 113.323397 137.250861)
				(xy 113.2323 137.292191) (xy 113.174923 137.304513) (xy 113.099323 137.309)
			)
		)
	)
	(zone
		(net 2)
		(net_name "+3V3")
		(layer "F.Cu")
		(name "$teardrop_padvia$")
		(hatch none 0.1)
		(priority 30898)
		(attr
			(teardrop
				(type padvia)
			)
		)
		(connect_pads yes
			(clearance 0)
		)
		(min_thickness 0.0254)
		(filled_areas_thickness no)
		(fill yes
			(thermal_gap 0.5)
			(thermal_bridge_width 0.5)
			(island_removal_mode 1)
			(island_area_min 10)
		)
		(polygon
			(pts
				(xy 121.488 74.423574) (xy 121.492697 74.384317) (xy 121.505573 74.354538) (xy 121.550599 74.313273)
				(xy 121.583985 74.295242) (xy 121.642291 74.259792) (xy 121.5 74.089) (xy 121.279323 74.080093)
				(xy 121.259236 74.16942) (xy 121.239489 74.213954) (xy 121.204508 74.301259) (xy 121.188 74.423574)
			)
		)
	)
	(zone
		(net 400)
		(net_name "/Com Express 7 MGMT/FAN_PWM")
		(layer "F.Cu")
		(name "$teardrop_padvia$")
		(hatch none 0.1)
		(priority 30338)
		(attr
			(teardrop
				(type padvia)
			)
		)
		(connect_pads yes
			(clearance 0)
		)
		(min_thickness 0.0254)
		(filled_areas_thickness no)
		(fill yes
			(thermal_gap 0.5)
			(thermal_bridge_width 0.5)
			(island_removal_mode 1)
			(island_area_min 10)
		)
		(polygon
			(pts
				(xy 233.637707 79.0095) (xy 233.603844 79.003719) (xy 233.569222 78.983254) (xy 233.5474 78.956188)
				(xy 233.531707 78.916848) (xy 233.528418 78.901289) (xy 232.821707 79.072) (xy 233.528418 79.242711)
				(xy 233.540008 79.20249) (xy 233.557592 79.173016) (xy 233.605175 79.139827) (xy 233.637707 79.1345)
			)
		)
	)
	(zone
		(net 686)
		(net_name "/2xSFP+/KR to SFI #1/SFI_R.RX-")
		(layer "F.Cu")
		(name "$teardrop_padvia$")
		(hatch none 0.1)
		(priority 31169)
		(attr
			(teardrop
				(type padvia)
			)
		)
		(connect_pads yes
			(clearance 0)
		)
		(min_thickness 0.0254)
		(filled_areas_thickness no)
		(fill yes
			(thermal_gap 0.5)
			(thermal_bridge_width 0.5)
			(island_removal_mode 1)
			(island_area_min 10)
		)
		(polygon
			(pts
				(xy 150.22 143.17679) (xy 150.224788 143.139695) (xy 150.238304 143.115431) (xy 150.280007 143.096705)
				(xy 150.368927 143.101889) (xy 150.434222 143.108714) (xy 150.498773 143.105196) (xy 150.45 142.859)
				(xy 150.204804 142.811227) (xy 150.168876 142.909201) (xy 150.132391 142.964616) (xy 150.082365 143.048601)
				(xy 150.066125 143.104227) (xy 150.06 143.17679)
			)
		)
	)
	(zone
		(net 269)
		(net_name "/Com Express 7 Interfaces/PCIe_{B2Bx4}.TX0+")
		(layer "F.Cu")
		(name "$teardrop_padvia$")
		(hatch none 0.1)
		(priority 30247)
		(attr
			(teardrop
				(type padvia)
			)
		)
		(connect_pads yes
			(clearance 0)
		)
		(min_thickness 0.0254)
		(filled_areas_thickness no)
		(fill yes
			(thermal_gap 0.5)
			(thermal_bridge_width 0.5)
			(island_removal_mode 1)
			(island_area_min 10)
		)
		(polygon
			(pts
				(xy 194.9795 167.75) (xy 194.98258 167.764227) (xy 194.984749 167.794527) (xy 194.971877 167.805628)
				(xy 194.941705 167.81) (xy 195.025 168.686) (xy 195.175 168.437021) (xy 195.155644 168.195818) (xy 195.170401 167.923112)
				(xy 195.1815 167.75)
			)
		)
	)
	(zone
		(net 270)
		(net_name "/M.2 key M #2/~{PERST_D}")
		(layer "F.Cu")
		(name "$teardrop_padvia$")
		(hatch none 0.1)
		(priority 30917)
		(attr
			(teardrop
				(type padvia)
			)
		)
		(connect_pads yes
			(clearance 0)
		)
		(min_thickness 0.0254)
		(filled_areas_thickness no)
		(fill yes
			(thermal_gap 0.5)
			(thermal_bridge_width 0.5)
			(island_removal_mode 1)
			(island_area_min 10)
		)
		(polygon
			(pts
				(xy 297.638 83.4675) (xy 297.571172 83.447099) (xy 297.537676 83.42064) (xy 297.508265 83.38292)
				(xy 297.476798 83.298202) (xy 297.199 83.55) (xy 297.476798 83.801798) (xy 297.491481 83.739637)
				(xy 297.513058 83.687996) (xy 297.54032 83.646685) (xy 297.571342 83.616794) (xy 297.603406 83.599015)
				(xy 297.635905 83.592525) (xy 297.638 83.5925)
			)
		)
	)
	(zone
		(net 124)
		(net_name "/2xUSB3.0+RJ45/P1_D+")
		(layer "F.Cu")
		(name "$teardrop_padvia$")
		(hatch none 0.1)
		(priority 30456)
		(attr
			(teardrop
				(type padvia)
			)
		)
		(connect_pads yes
			(clearance 0)
		)
		(min_thickness 0.0254)
		(filled_areas_thickness no)
		(fill yes
			(thermal_gap 0.5)
			(thermal_bridge_width 0.5)
			(island_removal_mode 1)
			(island_area_min 10)
		)
		(polygon
			(pts
				(xy 129.278941 118.252) (xy 129.438368 118.188279) (xy 129.535843 118.167165) (xy 129.638132 118.164733)
				(xy 129.674641 118.17) (xy 129.64 117.85) (xy 129.344 117.754036) (xy 129.350873 117.892782) (xy 129.338157 117.991737)
				(xy 129.321385 118.029138) (xy 129.296554 118.056244) (xy 129.278941 118.067)
			)
		)
	)
	(zone
		(net 289)
		(net_name "/2xUSB3.0+RJ45/GbE.MDI2-")
		(layer "F.Cu")
		(name "$teardrop_padvia$")
		(hatch none 0.1)
		(priority 31651)
		(attr
			(teardrop
				(type padvia)
			)
		)
		(connect_pads yes
			(clearance 0)
		)
		(min_thickness 0.0254)
		(filled_areas_thickness no)
		(fill yes
			(thermal_gap 0.5)
			(thermal_bridge_width 0.5)
			(island_removal_mode 1)
			(island_area_min 10)
		)
		(polygon
			(pts
				(xy 166.5 149.457916) (xy 166.502203 149.6633) (xy 166.504323 149.801757) (xy 166.725 149.801) (xy 166.850003 149.612919)
				(xy 166.773862 149.579004) (xy 166.757261 149.573949) (xy 166.715719 149.560156) (xy 166.681601 149.540737)
				(xy 166.658499 149.508917) (xy 166.65 149.457916)
			)
		)
	)
	(zone
		(net 1)
		(net_name "GND")
		(layer "F.Cu")
		(name "$teardrop_padvia$")
		(hatch none 0.1)
		(priority 31325)
		(attr
			(teardrop
				(type padvia)
			)
		)
		(connect_pads yes
			(clearance 0)
		)
		(min_thickness 0.0254)
		(filled_areas_thickness no)
		(fill yes
			(thermal_gap 0.5)
			(thermal_bridge_width 0.5)
			(island_removal_mode 1)
			(island_area_min 10)
		)
		(polygon
			(pts
				(xy 208.625 167.887793) (xy 208.631205 167.726365) (xy 208.654641 167.602721) (xy 208.664815 167.561192)
				(xy 208.666731 167.553421) (xy 208.45 167.499) (xy 208.269305 167.631389) (xy 208.338296 167.70539)
				(xy 208.399512 167.774698) (xy 208.418152 167.822293) (xy 208.425 167.887793)
			)
		)
	)
	(zone
		(net 90)
		(net_name "/Com Express 7 Interfaces/PCIe_{B2Ax4}.RX0+")
		(layer "F.Cu")
		(name "$teardrop_padvia$")
		(hatch none 0.1)
		(priority 31912)
		(attr
			(teardrop
				(type padvia)
			)
		)
		(connect_pads yes
			(clearance 0)
		)
		(min_thickness 0.0254)
		(filled_areas_thickness no)
		(fill yes
			(thermal_gap 0.5)
			(thermal_bridge_width 0.5)
			(island_removal_mode 1)
			(island_area_min 10)
		)
		(polygon
			(pts
				(xy 210.953583 164.518919) (xy 210.963597 164.535551) (xy 210.953738 164.543736) (xy 210.913323 164.547628)
				(xy 210.868801 164.550921) (xy 210.831497 164.562919) (xy 210.957207 164.750707) (xy 211.175554 164.702189)
				(xy 211.167835 164.600474) (xy 211.168607 164.580384) (xy 211.16944 164.530493) (xy 211.162658 164.48164)
				(xy 211.140803 164.431084) (xy 211.096418 164.376084)
			)
		)
	)
	(zone
		(net 982)
		(net_name "Net-(D30-C)")
		(layer "F.Cu")
		(name "$teardrop_padvia$")
		(hatch none 0.1)
		(priority 30155)
		(attr
			(teardrop
				(type padvia)
			)
		)
		(connect_pads yes
			(clearance 0)
		)
		(min_thickness 0.0254)
		(filled_areas_thickness no)
		(fill yes
			(thermal_gap 0.5)
			(thermal_bridge_width 0.5)
			(island_removal_mode 1)
			(island_area_min 10)
		)
		(polygon
			(pts
				(xy 190.80861 76.062163) (xy 190.81367 76.028644) (xy 190.829091 75.995738) (xy 190.854873 75.965425)
				(xy 190.891483 75.938919) (xy 190.938658 75.918016) (xy 190.997093 75.90393) (xy 191.06861 75.898184)
				(xy 190.70861 75.501163) (xy 190.34861 75.898184) (xy 190.418681 75.903704) (xy 190.477217 75.917567)
				(xy 190.524564 75.938253) (xy 190.561037 75.964231) (xy 190.58712 75.9942) (xy 190.602852 76.026426)
				(xy 190.60861 76.062163)
			)
		)
	)
	(zone
		(net 2)
		(net_name "+3V3")
		(layer "F.Cu")
		(name "$teardrop_padvia$")
		(hatch none 0.1)
		(priority 31307)
		(attr
			(teardrop
				(type padvia)
			)
		)
		(connect_pads yes
			(clearance 0)
		)
		(min_thickness 0.0254)
		(filled_areas_thickness no)
		(fill yes
			(thermal_gap 0.5)
			(thermal_bridge_width 0.5)
			(island_removal_mode 1)
			(island_area_min 10)
		)
		(polygon
			(pts
				(xy 261.791463 93.857149) (xy 261.768807 93.927256) (xy 261.739818 93.968118) (xy 261.700459 94.005536)
				(xy 261.65438 94.034896) (xy 261.60077 94.055311) (xy 261.578202 94.060202) (xy 261.829293 94.337707)
				(xy 262.081798 94.060202) (xy 261.987811 94.038665) (xy 261.920547 94.009535) (xy 261.893577 93.986256)
				(xy 261.880719 93.959005) (xy 261.879851 93.945537)
			)
		)
	)
	(zone
		(net 371)
		(net_name "/Com Express 7 MGMT/I2C.SCL")
		(layer "F.Cu")
		(name "$teardrop_padvia$")
		(hatch none 0.1)
		(priority 30814)
		(attr
			(teardrop
				(type padvia)
			)
		)
		(connect_pads yes
			(clearance 0)
		)
		(min_thickness 0.0254)
		(filled_areas_thickness no)
		(fill yes
			(thermal_gap 0.5)
			(thermal_bridge_width 0.5)
			(island_removal_mode 1)
			(island_area_min 10)
		)
		(polygon
			(pts
				(xy 259.336 88.972499) (xy 259.362609 88.977862) (xy 259.387883 88.995399) (xy 259.405522 89.021693)
				(xy 259.41695 89.059839) (xy 259.42 89.098999) (xy 259.981 88.91) (xy 259.42 88.720999) (xy 259.415373 88.768362)
				(xy 259.402982 88.80341) (xy 259.385123 88.827348) (xy 259.363985 88.841545) (xy 259.336 88.847499)
			)
		)
	)
	(zone
		(net 4)
		(net_name "/M.2 key E/WIFI_BT_USB_D_N")
		(layer "F.Cu")
		(name "$teardrop_padvia$")
		(hatch none 0.1)
		(priority 30453)
		(attr
			(teardrop
				(type padvia)
			)
		)
		(connect_pads yes
			(clearance 0)
		)
		(min_thickness 0.0254)
		(filled_areas_thickness no)
		(fill yes
			(thermal_gap 0.5)
			(thermal_bridge_width 0.5)
			(island_removal_mode 1)
			(island_area_min 10)
		)
		(polygon
			(pts
				(xy 155.631964 72.091) (xy 155.658605 72.116039) (xy 155.678522 72.148683) (xy 155.701044 72.244894)
				(xy 155.7 72.406149) (xy 155.996 72.31) (xy 156.030396 71.99) (xy 155.90978 72.000347) (xy 155.778006 71.976161)
				(xy 155.652101 71.919353) (xy 155.631964 71.906)
			)
		)
	)
	(zone
		(net 425)
		(net_name "/2xSFP+/I2C_{SFP0}.SDA")
		(layer "F.Cu")
		(name "$teardrop_padvia$")
		(hatch none 0.1)
		(priority 31875)
		(attr
			(teardrop
				(type padvia)
			)
		)
		(connect_pads yes
			(clearance 0)
		)
		(min_thickness 0.0254)
		(filled_areas_thickness no)
		(fill yes
			(thermal_gap 0.5)
			(thermal_bridge_width 0.5)
			(island_removal_mode 1)
			(island_area_min 10)
		)
		(polygon
			(pts
				(xy 180.360873 143.027515) (xy 180.413382 142.981819) (xy 180.459376 142.955231) (xy 180.545824 142.934847)
				(xy 180.56116 142.933011) (xy 180.643895 142.920677) (xy 180.600707 142.699293) (xy 180.379323 142.656105)
				(xy 180.366988 142.738841) (xy 180.346651 142.836119) (xy 180.319943 142.884159) (xy 180.272485 142.939127)
			)
		)
	)
	(zone
		(net 1)
		(net_name "GND")
		(layer "F.Cu")
		(name "$teardrop_padvia$")
		(hatch none 0.1)
		(priority 30576)
		(attr
			(teardrop
				(type padvia)
			)
		)
		(connect_pads yes
			(clearance 0)
		)
		(min_thickness 0.0254)
		(filled_areas_thickness no)
		(fill yes
			(thermal_gap 0.5)
			(thermal_bridge_width 0.5)
			(island_removal_mode 1)
			(island_area_min 10)
		)
		(polygon
			(pts
				(xy 203.925 167.75) (xy 203.928333 167.764486) (xy 203.93119 167.79461) (xy 203.919036 167.805651)
				(xy 203.89 167.81) (xy 204.025 168.686) (xy 204.16 167.81) (xy 204.130666 167.805525) (xy 204.118642 167.794199)
				(xy 204.121667 167.764486) (xy 204.125 167.75)
			)
		)
	)
	(zone
		(net 572)
		(net_name "Net-(U7-A_{2})")
		(layer "F.Cu")
		(name "$teardrop_padvia$")
		(hatch none 0.1)
		(priority 30351)
		(attr
			(teardrop
				(type padvia)
			)
		)
		(connect_pads yes
			(clearance 0)
		)
		(min_thickness 0.0254)
		(filled_areas_thickness no)
		(fill yes
			(thermal_gap 0.5)
			(thermal_bridge_width 0.5)
			(island_removal_mode 1)
			(island_area_min 10)
		)
		(polygon
			(pts
				(xy 121.9245 74.943) (xy 121.918719 74.976863) (xy 121.898254 75.011486) (xy 121.871188 75.033307)
				(xy 121.831849 75.049) (xy 121.816289 75.052289) (xy 121.987 75.759) (xy 122.157711 75.052289) (xy 122.11749 75.0407)
				(xy 122.088017 75.023116) (xy 122.054827 74.975533) (xy 122.0495 74.943)
			)
		)
	)
	(zone
		(net 366)
		(net_name "Net-(J12D-WDT)")
		(layer "F.Cu")
		(name "$teardrop_padvia$")
		(hatch none 0.1)
		(priority 31591)
		(attr
			(teardrop
				(type padvia)
			)
		)
		(connect_pads yes
			(clearance 0)
		)
		(min_thickness 0.0254)
		(filled_areas_thickness no)
		(fill yes
			(thermal_gap 0.5)
			(thermal_bridge_width 0.5)
			(island_removal_mode 1)
			(island_area_min 10)
		)
		(polygon
			(pts
				(xy 188.9625 163.862207) (xy 188.95789 163.947223) (xy 188.945618 164.0099) (xy 188.921603 164.079068)
				(xy 188.883268 164.196578) (xy 189.1 164.251) (xy 189.280694 164.11861) (xy 189.214238 164.052598)
				(xy 189.185713 164.032143) (xy 189.147848 164.004121) (xy 189.116589 163.97121) (xy 189.095339 163.926281)
				(xy 189.0875 163.862207)
			)
		)
	)
	(zone
		(net 936)
		(net_name "Net-(D14-C)")
		(layer "F.Cu")
		(name "$teardrop_padvia$")
		(hatch none 0.1)
		(priority 30859)
		(attr
			(teardrop
				(type padvia)
			)
		)
		(connect_pads yes
			(clearance 0)
		)
		(min_thickness 0.0254)
		(filled_areas_thickness no)
		(fill yes
			(thermal_gap 0.5)
			(thermal_bridge_width 0.5)
			(island_removal_mode 1)
			(island_area_min 10)
		)
		(polygon
			(pts
				(xy 288.3855 80.748) (xy 288.374563 80.786823) (xy 288.352805 80.801933) (xy 288.313 80.808) (xy 288.448 81.584)
				(xy 288.583 80.808) (xy 288.547719 80.803483) (xy 288.526203 80.791862) (xy 288.511005 80.759039)
				(xy 288.5105 80.748)
			)
		)
	)
	(zone
		(net 133)
		(net_name "Net-(D18-C_{G})")
		(layer "F.Cu")
		(name "$teardrop_padvia$")
		(hatch none 0.1)
		(priority 30024)
		(attr
			(teardrop
				(type padvia)
			)
		)
		(connect_pads yes
			(clearance 0)
		)
		(min_thickness 0.0254)
		(filled_areas_thickness no)
		(fill yes
			(thermal_gap 0.5)
			(thermal_bridge_width 0.5)
			(island_removal_mode 1)
			(island_area_min 10)
		)
		(polygon
			(pts
				(xy 101.7725 72.035) (xy 101.791662 71.968881) (xy 101.851682 71.906425) (xy 101.961369 71.851944)
				(xy 102.122166 71.81881) (xy 102.205 71.815) (xy 101.71 71.064) (xy 101.215 71.815) (xy 101.308055 71.819833)
				(xy 101.393163 71.833664) (xy 101.469111 71.855637) (xy 101.533751 71.884678) (xy 101.582298 71.917153)
				(xy 101.618314 71.954044) (xy 101.63842 71.989079) (xy 101.647181 72.026294) (xy 101.6475 72.035)
			)
		)
	)
	(zone
		(net 73)
		(net_name "+3V3_AON")
		(layer "F.Cu")
		(name "$teardrop_padvia$")
		(hatch none 0.1)
		(priority 31975)
		(attr
			(teardrop
				(type padvia)
			)
		)
		(connect_pads yes
			(clearance 0)
		)
		(min_thickness 0.0254)
		(filled_areas_thickness no)
		(fill yes
			(thermal_gap 0.5)
			(thermal_bridge_width 0.5)
			(island_removal_mode 1)
			(island_area_min 10)
		)
		(polygon
			(pts
				(xy 245.34 127.7675) (xy 245.311149 127.762018) (xy 245.282716 127.743644) (xy 245.264131 127.717694)
				(xy 245.252468 127.680141) (xy 245.25 127.648058) (xy 245.024 127.96) (xy 245.25 128.085991) (xy 245.254807 128.012663)
				(xy 245.268452 127.956562) (xy 245.286563 127.921966) (xy 245.3097 127.900596) (xy 245.34 127.8925)
			)
		)
	)
	(zone
		(net 1)
		(net_name "GND")
		(layer "F.Cu")
		(name "$teardrop_padvia$")
		(hatch none 0.1)
		(priority 31272)
		(attr
			(teardrop
				(type padvia)
			)
		)
		(connect_pads yes
			(clearance 0)
		)
		(min_thickness 0.0254)
		(filled_areas_thickness no)
		(fill yes
			(thermal_gap 0.5)
			(thermal_bridge_width 0.5)
			(island_removal_mode 1)
			(island_area_min 10)
		)
		(polygon
			(pts
				(xy 225.425 157.324323) (xy 225.420287 157.402234) (xy 225.4073 157.461018) (xy 225.365199 157.552048)
				(xy 225.3225 157.637221) (xy 225.525 157.726) (xy 225.7275 157.637221) (xy 225.684801 157.55205)
				(xy 225.642133 157.459217) (xy 225.629556 157.401078) (xy 225.625 157.324323)
			)
		)
	)
	(zone
		(net 636)
		(net_name "Net-(U41-~{INT})")
		(layer "F.Cu")
		(name "$teardrop_padvia$")
		(hatch none 0.1)
		(priority 31477)
		(attr
			(teardrop
				(type padvia)
			)
		)
		(connect_pads yes
			(clearance 0)
		)
		(min_thickness 0.0254)
		(filled_areas_thickness no)
		(fill yes
			(thermal_gap 0.5)
			(thermal_bridge_width 0.5)
			(island_removal_mode 1)
			(island_area_min 10)
		)
		(polygon
			(pts
				(xy 129.992277 82.58889) (xy 129.988079 82.569085) (xy 129.995754 82.551487) (xy 130.044504 82.522175)
				(xy 130.176798 82.491799) (xy 129.899293 82.239294) (xy 129.671054 82.523773) (xy 129.762302 82.545885)
				(xy 129.845754 82.601588) (xy 129.903889 82.677278)
			)
		)
	)
	(zone
		(net 119)
		(net_name "/2xSFP+/10GKR_SFP1.TX+")
		(layer "F.Cu")
		(name "$teardrop_padvia$")
		(hatch none 0.1)
		(priority 31563)
		(attr
			(teardrop
				(type padvia)
			)
		)
		(connect_pads yes
			(clearance 0)
		)
		(min_thickness 0.0254)
		(filled_areas_thickness no)
		(fill yes
			(thermal_gap 0.5)
			(thermal_bridge_width 0.5)
			(island_removal_mode 1)
			(island_area_min 10)
		)
		(polygon
			(pts
				(xy 196.505 152.239958) (xy 196.500236 152.283018) (xy 196.486888 152.314471) (xy 196.442175 152.352895)
				(xy 196.396498 152.372983) (xy 196.314997 152.412919) (xy 196.44 152.601) (xy 196.660677 152.594884)
				(xy 196.661973 152.415783) (xy 196.665 152.239958)
			)
		)
	)
	(zone
		(net 1)
		(net_name "GND")
		(layer "F.Cu")
		(name "$teardrop_padvia$")
		(hatch none 0.1)
		(priority 30534)
		(attr
			(teardrop
				(type padvia)
			)
		)
		(connect_pads yes
			(clearance 0)
		)
		(min_thickness 0.0254)
		(filled_areas_thickness no)
		(fill yes
			(thermal_gap 0.5)
			(thermal_bridge_width 0.5)
			(island_removal_mode 1)
			(island_area_min 10)
		)
		(polygon
			(pts
				(xy 178.125 157.62) (xy 178.121667 157.605514) (xy 178.11881 157.57539) (xy 178.130964 157.564349)
				(xy 178.16 157.56) (xy 178.025 156.684) (xy 177.89 157.56) (xy 177.919334 157.564475) (xy 177.931358 157.575801)
				(xy 177.928333 157.605514) (xy 177.925 157.62)
			)
		)
	)
	(zone
		(net 749)
		(net_name "Net-(U45C-AMUXB)")
		(layer "F.Cu")
		(name "$teardrop_padvia$")
		(hatch none 0.1)
		(priority 31703)
		(attr
			(teardrop
				(type padvia)
			)
		)
		(connect_pads yes
			(clearance 0)
		)
		(min_thickness 0.0254)
		(filled_areas_thickness no)
		(fill yes
			(thermal_gap 0.5)
			(thermal_bridge_width 0.5)
			(island_removal_mode 1)
			(island_area_min 10)
		)
		(polygon
			(pts
				(xy 136.1775 129.739323) (xy 136.172682 129.808763) (xy 136.15896 129.860087) (xy 136.112245 129.935628)
				(xy 136.102702 129.947768) (xy 136.052919 130.014997) (xy 136.24 130.141) (xy 136.427081 130.014997)
				(xy 136.377299 129.947769) (xy 136.322894 129.864603) (xy 136.30781 129.811748) (xy 136.3025 129.739323)
			)
		)
	)
	(zone
		(net 1)
		(net_name "GND")
		(layer "F.Cu")
		(name "$teardrop_padvia$")
		(hatch none 0.1)
		(priority 31231)
		(attr
			(teardrop
				(type padvia)
			)
		)
		(connect_pads yes
			(clearance 0)
		)
		(min_thickness 0.0254)
		(filled_areas_thickness no)
		(fill yes
			(thermal_gap 0.5)
			(thermal_bridge_width 0.5)
			(island_removal_mode 1)
			(island_area_min 10)
		)
		(polygon
			(pts
				(xy 210.625 167.900677) (xy 210.629737 167.809676) (xy 210.642896 167.742587) (xy 210.675418 167.655855)
				(xy 210.707644 167.575358) (xy 210.5 167.499) (xy 210.303541 167.602363) (xy 210.355343 167.685863)
				(xy 210.404833 167.771955) (xy 210.419614 167.82716) (xy 210.425 167.900677)
			)
		)
	)
	(zone
		(net 784)
		(net_name "Net-(U30-1Y)")
		(layer "F.Cu")
		(name "$teardrop_padvia$")
		(hatch none 0.1)
		(priority 31678)
		(attr
			(teardrop
				(type padvia)
			)
		)
		(connect_pads yes
			(clearance 0)
		)
		(min_thickness 0.0254)
		(filled_areas_thickness no)
		(fill yes
			(thermal_gap 0.5)
			(thermal_bridge_width 0.5)
			(island_removal_mode 1)
			(island_area_min 10)
		)
		(polygon
			(pts
				(xy 309.1945 151.978) (xy 309.188978 152.005072) (xy 309.170322 152.030611) (xy 309.143703 152.04678)
				(xy 309.104962 152.056399) (xy 309.077 152.058) (xy 309.257 152.434) (xy 309.437 152.058) (xy 309.3915 152.053387)
				(xy 309.358532 152.0411) (xy 309.324156 152.002945) (xy 309.3195 151.978)
			)
		)
	)
	(zone
		(net 1)
		(net_name "GND")
		(layer "F.Cu")
		(name "$teardrop_padvia$")
		(hatch none 0.1)
		(priority 30539)
		(attr
			(teardrop
				(type padvia)
			)
		)
		(connect_pads yes
			(clearance 0)
		)
		(min_thickness 0.0254)
		(filled_areas_thickness no)
		(fill yes
			(thermal_gap 0.5)
			(thermal_bridge_width 0.5)
			(island_removal_mode 1)
			(island_area_min 10)
		)
		(polygon
			(pts
				(xy 209.125 152.07) (xy 209.121667 152.055514) (xy 209.11881 152.02539) (xy 209.130964 152.014349)
				(xy 209.16 152.01) (xy 209.025 151.134) (xy 208.89 152.01) (xy 208.919334 152.014475) (xy 208.931358 152.025801)
				(xy 208.928333 152.055514) (xy 208.925 152.07)
			)
		)
	)
	(zone
		(net 372)
		(net_name "/Com Express 7 MGMT/I2C.SDA")
		(layer "F.Cu")
		(name "$teardrop_padvia$")
		(hatch none 0.1)
		(priority 30729)
		(attr
			(teardrop
				(type padvia)
			)
		)
		(connect_pads yes
			(clearance 0)
		)
		(min_thickness 0.0254)
		(filled_areas_thickness no)
		(fill yes
			(thermal_gap 0.5)
			(thermal_bridge_width 0.5)
			(island_removal_mode 1)
			(island_area_min 10)
		)
		(polygon
			(pts
				(xy 305.2375 151.05) (xy 305.242821 151.018265) (xy 305.260069 150.985565) (xy 305.286538 150.959374)
				(xy 305.324964 150.938445) (xy 305.36705 150.92705) (xy 305.175 150.409) (xy 304.98295 150.92705)
				(xy 305.027474 150.939409) (xy 305.0616 150.958008) (xy 305.103536 151.008803) (xy 305.1125 151.05)
			)
		)
	)
	(zone
		(net 1)
		(net_name "GND")
		(layer "F.Cu")
		(name "$teardrop_padvia$")
		(hatch none 0.1)
		(priority 30580)
		(attr
			(teardrop
				(type padvia)
			)
		)
		(connect_pads yes
			(clearance 0)
		)
		(min_thickness 0.0254)
		(filled_areas_thickness no)
		(fill yes
			(thermal_gap 0.5)
			(thermal_bridge_width 0.5)
			(island_removal_mode 1)
			(island_area_min 10)
		)
		(polygon
			(pts
				(xy 186.125 152.07) (xy 186.121667 152.055514) (xy 186.11881 152.02539) (xy 186.130964 152.014349)
				(xy 186.16 152.01) (xy 186.025 151.134) (xy 185.89 152.01) (xy 185.919334 152.014475) (xy 185.931358 152.025801)
				(xy 185.928333 152.055514) (xy 185.925 152.07)
			)
		)
	)
	(zone
		(net 644)
		(net_name "Net-(U41-IO0_5)")
		(layer "F.Cu")
		(name "$teardrop_padvia$")
		(hatch none 0.1)
		(priority 32019)
		(attr
			(teardrop
				(type padvia)
			)
		)
		(connect_pads yes
			(clearance 0)
		)
		(min_thickness 0.0254)
		(filled_areas_thickness no)
		(fill yes
			(thermal_gap 0.5)
			(thermal_bridge_width 0.5)
			(island_removal_mode 1)
			(island_area_min 10)
		)
		(polygon
			(pts
				(xy 128.2495 86.871501) (xy 128.255822 86.871405) (xy 128.295325 86.87699) (xy 128.313548 86.891922)
				(xy 128.326496 86.9215) (xy 128.713 86.809) (xy 128.326494 86.6965) (xy 128.315378 86.723494) (xy 128.299851 86.738596)
				(xy 128.255821 86.746597) (xy 128.2495 86.746501)
			)
		)
	)
	(zone
		(net 79)
		(net_name "Net-(U23-VOUT)")
		(layer "F.Cu")
		(hatch edge 0.5)
		(priority 27)
		(connect_pads yes
			(clearance 0.15)
		)
		(min_thickness 0.25)
		(filled_areas_thickness no)
		(fill yes
			(thermal_gap 0.2)
			(thermal_bridge_width 0.5)
			(smoothing fillet)
			(radius 0.2)
		)
		(polygon
			(pts
				(xy 297.3 103.36) (xy 299.45 103.36) (xy 299.45 101.71) (xy 297.3 101.71)
			)
		)
	)
	(zone
		(net 689)
		(net_name "/2xUSB3.0+RJ45/DA_FL+")
		(layer "F.Cu")
		(name "$teardrop_padvia$")
		(hatch none 0.1)
		(priority 31976)
		(attr
			(teardrop
				(type padvia)
			)
		)
		(connect_pads yes
			(clearance 0)
		)
		(min_thickness 0.0254)
		(filled_areas_thickness no)
		(fill yes
			(thermal_gap 0.5)
			(thermal_bridge_width 0.5)
			(island_removal_mode 1)
			(island_area_min 10)
		)
		(polygon
			(pts
				(xy 130.277517 113.543582) (xy 130.292822 113.554385) (xy 130.320844 113.577302) (xy 130.326394 113.59402)
				(xy 130.32 113.615944) (xy 130.800707 113.660707) (xy 130.782762 113.525) (xy 130.617623 113.520477)
				(xy 130.493803 113.499505) (xy 130.4397 113.478145) (xy 130.395485 113.448552) (xy 130.383582 113.437517)
			)
		)
	)
	(zone
		(net 314)
		(net_name "/2xUSB3.0+RJ45/FLG_1")
		(layer "F.Cu")
		(name "$teardrop_padvia$")
		(hatch none 0.1)
		(priority 30566)
		(attr
			(teardrop
				(type padvia)
			)
		)
		(connect_pads yes
			(clearance 0)
		)
		(min_thickness 0.0254)
		(filled_areas_thickness no)
		(fill yes
			(thermal_gap 0.5)
			(thermal_bridge_width 0.5)
			(island_removal_mode 1)
			(island_area_min 10)
		)
		(polygon
			(pts
				(xy 197.425 167.75) (xy 197.428333 167.764486) (xy 197.43119 167.79461) (xy 197.419036 167.805651)
				(xy 197.39 167.81) (xy 197.525 168.686) (xy 197.66 167.81) (xy 197.630666 167.805525) (xy 197.618642 167.794199)
				(xy 197.621667 167.764486) (xy 197.625 167.75)
			)
		)
	)
	(zone
		(net 650)
		(net_name "/2xSFP+/KR to SFI #1/MDC_R")
		(layer "F.Cu")
		(name "$teardrop_padvia$")
		(hatch none 0.1)
		(priority 30968)
		(attr
			(teardrop
				(type padvia)
			)
		)
		(connect_pads yes
			(clearance 0)
		)
		(min_thickness 0.0254)
		(filled_areas_thickness no)
		(fill yes
			(thermal_gap 0.5)
			(thermal_bridge_width 0.5)
			(island_removal_mode 1)
			(island_area_min 10)
		)
		(polygon
			(pts
				(xy 141.9525 145.488) (xy 141.972469 145.425134) (xy 141.998921 145.393156) (xy 142.036332 145.364642)
				(xy 142.083527 145.342118) (xy 142.141167 145.326907) (xy 142.141798 145.326798) (xy 141.89 145.049)
				(xy 141.638202 145.326798) (xy 141.693635 145.341095) (xy 141.73952 145.362175) (xy 141.777201 145.38954)
				(xy 141.804434 145.420448) (xy 141.821472 145.453735) (xy 141.827489 145.486566) (xy 141.8275 145.488)
			)
		)
	)
	(zone
		(net 431)
		(net_name "/2xSFP+/MOD0_ABS")
		(layer "F.Cu")
		(name "$teardrop_padvia$")
		(hatch none 0.1)
		(priority 30678)
		(attr
			(teardrop
				(type padvia)
			)
		)
		(connect_pads yes
			(clearance 0)
		)
		(min_thickness 0.0254)
		(filled_areas_thickness no)
		(fill yes
			(thermal_gap 0.5)
			(thermal_bridge_width 0.5)
			(island_removal_mode 1)
			(island_area_min 10)
		)
		(polygon
			(pts
				(xy 198.9625 155.75) (xy 198.951563 155.788823) (xy 198.929805 155.803933) (xy 198.89 155.81) (xy 199.025 156.686)
				(xy 199.16 155.81) (xy 199.124719 155.805483) (xy 199.103203 155.793862) (xy 199.088005 155.761039)
				(xy 199.0875 155.75)
			)
		)
	)
	(zone
		(net 544)
		(net_name "Net-(Q10-E)")
		(layer "F.Cu")
		(name "$teardrop_padvia$")
		(hatch none 0.1)
		(priority 30819)
		(attr
			(teardrop
				(type padvia)
			)
		)
		(connect_pads yes
			(clearance 0)
		)
		(min_thickness 0.0254)
		(filled_areas_thickness no)
		(fill yes
			(thermal_gap 0.5)
			(thermal_bridge_width 0.5)
			(island_removal_mode 1)
			(island_area_min 10)
		)
		(polygon
			(pts
				(xy 255.344 85.037499) (xy 255.317391 85.032136) (xy 255.292117 85.014599) (xy 255.274478 84.988305)
				(xy 255.26305 84.950159) (xy 255.26 84.910999) (xy 254.699 85.1) (xy 255.26 85.288999) (xy 255.264627 85.241636)
				(xy 255.277018 85.206588) (xy 255.294877 85.18265) (xy 255.316015 85.168453) (xy 255.344 85.162499)
			)
		)
	)
	(zone
		(net 211)
		(net_name "/Com Express 7 Interfaces/PCIe_{B1x4}.TX3-")
		(layer "F.Cu")
		(name "$teardrop_padvia$")
		(hatch none 0.1)
		(priority 31362)
		(attr
			(teardrop
				(type padvia)
			)
		)
		(connect_pads yes
			(clearance 0)
		)
		(min_thickness 0.0254)
		(filled_areas_thickness no)
		(fill yes
			(thermal_gap 0.5)
			(thermal_bridge_width 0.5)
			(island_removal_mode 1)
			(island_area_min 10)
		)
		(polygon
			(pts
				(xy 205.0705 165.667496) (xy 205.075235 165.62071) (xy 205.088379 165.585257) (xy 205.133387 165.53706)
				(xy 205.171608 165.512883) (xy 205.214774 165.485514) (xy 205.256731 165.448852) (xy 205.0935 165.299)
				(xy 204.872823 165.319859) (xy 204.877452 165.420536) (xy 204.874019 165.503908) (xy 204.873895 165.505963)
				(xy 204.8685 165.667496)
			)
		)
	)
	(zone
		(net 1)
		(net_name "GND")
		(layer "F.Cu")
		(name "$teardrop_padvia$")
		(hatch none 0.1)
		(priority 31267)
		(attr
			(teardrop
				(type padvia)
			)
		)
		(connect_pads yes
			(clearance 0)
		)
		(min_thickness 0.0254)
		(filled_areas_thickness no)
		(fill yes
			(thermal_gap 0.5)
			(thermal_bridge_width 0.5)
			(island_removal_mode 1)
			(island_area_min 10)
		)
		(polygon
			(pts
				(xy 314.048677 163.86) (xy 313.970765 163.855287) (xy 313.911981 163.8423) (xy 313.820949 163.800198)
				(xy 313.735778 163.7575) (xy 313.647 163.96) (xy 313.735778 164.1625) (xy 313.820947 164.119802)
				(xy 313.913782 164.077133) (xy 313.971921 164.064556) (xy 314.048677 164.06)
			)
		)
	)
	(zone
		(net 187)
		(net_name "/OCuLink/PCIe_{x4}.RX0-")
		(layer "F.Cu")
		(name "$teardrop_padvia$")
		(hatch none 0.1)
		(priority 32058)
		(attr
			(teardrop
				(type padvia)
			)
		)
		(connect_pads yes
			(clearance 0)
		)
		(min_thickness 0.0254)
		(filled_areas_thickness no)
		(fill yes
			(thermal_gap 0.5)
			(thermal_bridge_width 0.5)
			(island_removal_mode 1)
			(island_area_min 10)
		)
		(polygon
			(pts
				(xy 97.103 151.025) (xy 97.095802 151.004352) (xy 97.086208 150.972016) (xy 97.093035 150.957993)
				(xy 97.1145 150.948004) (xy 97.002 150.699) (xy 96.8895 150.948004) (xy 96.910676 150.957729) (xy 96.917731 150.971357)
				(xy 96.908198 151.004352) (xy 96.901 151.025)
			)
		)
	)
	(zone
		(net 44)
		(net_name "/2xUSB3.0+RJ45/USBSS_1.TX+")
		(layer "F.Cu")
		(name "$teardrop_padvia$")
		(hatch none 0.1)
		(priority 30300)
		(attr
			(teardrop
				(type padvia)
			)
		)
		(connect_pads yes
			(clearance 0)
		)
		(min_thickness 0.0254)
		(filled_areas_thickness no)
		(fill yes
			(thermal_gap 0.5)
			(thermal_bridge_width 0.5)
			(island_removal_mode 1)
			(island_area_min 10)
		)
		(polygon
			(pts
				(xy 180.3725 150.2) (xy 180.381903 150.373917) (xy 180.394286 150.608968) (xy 180.390781 150.748506)
				(xy 180.375 150.906314) (xy 180.525 151.136) (xy 180.604123 150.26) (xy 180.572384 150.255516) (xy 180.557527 150.244131)
				(xy 180.555915 150.212189) (xy 180.5575 150.2)
			)
		)
	)
	(zone
		(net 617)
		(net_name "/PCIe misc/DIF3+")
		(layer "F.Cu")
		(name "$teardrop_padvia$")
		(hatch none 0.1)
		(priority 30425)
		(attr
			(teardrop
				(type padvia)
			)
		)
		(connect_pads yes
			(clearance 0)
		)
		(min_thickness 0.0254)
		(filled_areas_thickness no)
		(fill yes
			(thermal_gap 0.5)
			(thermal_bridge_width 0.5)
			(island_removal_mode 1)
			(island_area_min 10)
		)
		(polygon
			(pts
				(xy 216.1845 132.274479) (xy 216.161242 132.302061) (xy 216.130003 132.322725) (xy 216.038084 132.345599)
				(xy 215.881086 132.345) (xy 215.98 132.641) (xy 216.3 132.671754) (xy 216.290561 132.556622) (xy 216.315334 132.428282)
				(xy 216.373209 132.296717) (xy 216.3865 132.274479)
			)
		)
	)
	(zone
		(net 11)
		(net_name "/Com Express 7 Interfaces/PCIe_{B1x2}.TX0-")
		(layer "F.Cu")
		(name "$teardrop_padvia$")
		(hatch none 0.1)
		(priority 31367)
		(attr
			(teardrop
				(type padvia)
			)
		)
		(connect_pads yes
			(clearance 0)
		)
		(min_thickness 0.0254)
		(filled_areas_thickness no)
		(fill yes
			(thermal_gap 0.5)
			(thermal_bridge_width 0.5)
			(island_removal_mode 1)
			(island_area_min 10)
		)
		(polygon
			(pts
				(xy 203.5705 167.367496) (xy 203.575235 167.32071) (xy 203.588379 167.285257) (xy 203.633387 167.23706)
				(xy 203.671608 167.212883) (xy 203.714774 167.185514) (xy 203.756731 167.148852) (xy 203.5935 166.999)
				(xy 203.372823 167.019859) (xy 203.377452 167.120536) (xy 203.374019 167.203908) (xy 203.373895 167.205963)
				(xy 203.3685 167.367496)
			)
		)
	)
	(zone
		(net 57)
		(net_name "/USB-C console/FTDI_VCCIO")
		(layer "F.Cu")
		(name "$teardrop_padvia$")
		(hatch none 0.1)
		(priority 31835)
		(attr
			(teardrop
				(type padvia)
			)
		)
		(connect_pads yes
			(clearance 0)
		)
		(min_thickness 0.0254)
		(filled_areas_thickness no)
		(fill yes
			(thermal_gap 0.5)
			(thermal_bridge_width 0.5)
			(island_removal_mode 1)
			(island_area_min 10)
		)
		(polygon
			(pts
				(xy 112.859324 76.8625) (xy 112.928764 76.867317) (xy 112.980087 76.88104) (xy 113.055628 76.927754)
				(xy 113.06777 76.937299) (xy 113.134997 76.987081) (xy 113.260999 76.8) (xy 113.134997 76.612919)
				(xy 113.067768 76.662702) (xy 112.984602 76.717106) (xy 112.931748 76.73219) (xy 112.859323 76.737501)
			)
		)
	)
	(zone
		(net 229)
		(net_name "/M.2 key M #1/PCIE_{REF}.CK-")
		(layer "F.Cu")
		(name "$teardrop_padvia$")
		(hatch none 0.1)
		(priority 30422)
		(attr
			(teardrop
				(type padvia)
			)
		)
		(connect_pads yes
			(clearance 0)
		)
		(min_thickness 0.0254)
		(filled_areas_thickness no)
		(fill yes
			(thermal_gap 0.5)
			(thermal_bridge_width 0.5)
			(island_removal_mode 1)
			(island_area_min 10)
		)
		(polygon
			(pts
				(xy 208.534479 128.6155) (xy 208.562061 128.638758) (xy 208.582724 128.669997) (xy 208.605599 128.761916)
				(xy 208.605 128.918914) (xy 208.901 128.82) (xy 208.931754 128.5) (xy 208.816623 128.509439) (xy 208.688284 128.484667)
				(xy 208.556719 128.426792) (xy 208.534479 128.4135)
			)
		)
	)
	(zone
		(net 1)
		(net_name "GND")
		(layer "F.Cu")
		(name "$teardrop_padvia$")
		(hatch none 0.1)
		(priority 31274)
		(attr
			(teardrop
				(type padvia)
			)
		)
		(connect_pads yes
			(clearance 0)
		)
		(min_thickness 0.0254)
		(filled_areas_thickness no)
		(fill yes
			(thermal_gap 0.5)
			(thermal_bridge_width 0.5)
			(island_removal_mode 1)
			(island_area_min 10)
		)
		(polygon
			(pts
				(xy 226.9 157.399323) (xy 226.895287 157.477234) (xy 226.8823 157.536018) (xy 226.840199 157.627048)
				(xy 226.7975 157.712221) (xy 227 157.801) (xy 227.2025 157.712221) (xy 227.159801 157.62705) (xy 227.117133 157.534217)
				(xy 227.104556 157.476078) (xy 227.1 157.399323)
			)
		)
	)
	(zone
		(net 1)
		(net_name "GND")
		(layer "F.Cu")
		(name "$teardrop_padvia$")
		(hatch none 0.1)
		(priority 30607)
		(attr
			(teardrop
				(type padvia)
			)
		)
		(connect_pads yes
			(clearance 0)
		)
		(min_thickness 0.0254)
		(filled_areas_thickness no)
		(fill yes
			(thermal_gap 0.5)
			(thermal_bridge_width 0.5)
			(island_removal_mode 1)
			(island_area_min 10)
		)
		(polygon
			(pts
				(xy 220.425 150.2) (xy 220.428333 150.214486) (xy 220.43119 150.24461) (xy 220.419036 150.255651)
				(xy 220.39 150.26) (xy 220.525 151.136) (xy 220.66 150.26) (xy 220.630666 150.255525) (xy 220.618642 150.244199)
				(xy 220.621667 150.214486) (xy 220.625 150.2)
			)
		)
	)
	(zone
		(net 381)
		(net_name "Net-(J12D-~{SYS_RESET})")
		(layer "F.Cu")
		(name "$teardrop_padvia$")
		(hatch none 0.1)
		(priority 30683)
		(attr
			(teardrop
				(type padvia)
			)
		)
		(connect_pads yes
			(clearance 0)
		)
		(min_thickness 0.0254)
		(filled_areas_thickness no)
		(fill yes
			(thermal_gap 0.5)
			(thermal_bridge_width 0.5)
			(island_removal_mode 1)
			(island_area_min 10)
		)
		(polygon
			(pts
				(xy 199.9625 162.2) (xy 199.951563 162.238823) (xy 199.929805 162.253933) (xy 199.89 162.26) (xy 200.025 163.136)
				(xy 200.16 162.26) (xy 200.124719 162.255483) (xy 200.103203 162.243862) (xy 200.088005 162.211039)
				(xy 200.0875 162.2)
			)
		)
	)
	(zone
		(net 213)
		(net_name "/Com Express 7 Interfaces/PCIe_{B1x4}.RX2-")
		(layer "F.Cu")
		(name "$teardrop_padvia$")
		(hatch none 0.1)
		(priority 31554)
		(attr
			(teardrop
				(type padvia)
			)
		)
		(connect_pads yes
			(clearance 0)
		)
		(min_thickness 0.0254)
		(filled_areas_thickness no)
		(fill yes
			(thermal_gap 0.5)
			(thermal_bridge_width 0.5)
			(island_removal_mode 1)
			(island_area_min 10)
		)
		(polygon
			(pts
				(xy 206.541269 161.695933) (xy 206.525206 161.673162) (xy 206.526868 161.656145) (xy 206.559503 161.636548)
				(xy 206.613463 161.622566) (xy 206.670306 161.608159) (xy 206.718503 161.587081) (xy 206.592793 161.399293)
				(xy 206.372823 161.443895) (xy 206.374 161.533751) (xy 206.355641 161.609671) (xy 206.341185 161.665663)
				(xy 206.337116 161.721042) (xy 206.353007 161.77801) (xy 206.398434 161.838768)
			)
		)
	)
	(zone
		(net 707)
		(net_name "Net-(U24-TACH3)")
		(layer "F.Cu")
		(name "$teardrop_padvia$")
		(hatch none 0.1)
		(priority 30808)
		(attr
			(teardrop
				(type padvia)
			)
		)
		(connect_pads yes
			(clearance 0)
		)
		(min_thickness 0.0254)
		(filled_areas_thickness no)
		(fill yes
			(thermal_gap 0.5)
			(thermal_bridge_width 0.5)
			(island_removal_mode 1)
			(island_area_min 10)
		)
		(polygon
			(pts
				(xy 260.624 84.397499) (xy 260.597391 84.392136) (xy 260.572117 84.374599) (xy 260.554478 84.348305)
				(xy 260.54305 84.310159) (xy 260.54 84.270999) (xy 259.979 84.46) (xy 260.54 84.648999) (xy 260.544627 84.601636)
				(xy 260.557018 84.566588) (xy 260.574877 84.54265) (xy 260.596015 84.528453) (xy 260.624 84.522499)
			)
		)
	)
	(zone
		(net 568)
		(net_name "/USB-C console/FTDI_D+")
		(layer "F.Cu")
		(name "$teardrop_padvia$")
		(hatch none 0.1)
		(priority 31040)
		(attr
			(teardrop
				(type padvia)
			)
		)
		(connect_pads yes
			(clearance 0)
		)
		(min_thickness 0.0254)
		(filled_areas_thickness no)
		(fill yes
			(thermal_gap 0.5)
			(thermal_bridge_width 0.5)
			(island_removal_mode 1)
			(island_area_min 10)
		)
		(polygon
			(pts
				(xy 112.779999 75.7275) (xy 112.90958 75.71178) (xy 113.051905 75.692337) (xy 113.130813 75.690844)
				(xy 113.214522 75.7) (xy 113.260999 75.5) (xy 112.859999 75.425591) (xy 112.855388 75.47653) (xy 112.843107 75.510204)
				(xy 112.807858 75.538829) (xy 112.779999 75.5425)
			)
		)
	)
	(zone
		(net 2)
		(net_name "+3V3")
		(layer "F.Cu")
		(name "$teardrop_padvia$")
		(hatch none 0.1)
		(priority 31017)
		(attr
			(teardrop
				(type padvia)
			)
		)
		(connect_pads yes
			(clearance 0)
		)
		(min_thickness 0.0254)
		(filled_areas_thickness no)
		(fill yes
			(thermal_gap 0.5)
			(thermal_bridge_width 0.5)
			(island_removal_mode 1)
			(island_area_min 10)
		)
		(polygon
			(pts
				(xy 191.454627 139.581397) (xy 191.484959 139.63997) (xy 191.488866 139.681286) (xy 191.482575 139.727902)
				(xy 191.46513 139.777201) (xy 191.435128 139.828714) (xy 191.434759 139.829237) (xy 191.80924 139.847622)
				(xy 191.790855 139.473141) (xy 191.741549 139.502229) (xy 191.694198 139.519768) (xy 191.648203 139.527063)
				(xy 191.607091 139.524464) (xy 191.571506 139.512975) (xy 191.544037 139.494015) (xy 191.543015 139.493009)
			)
		)
	)
	(zone
		(net 52)
		(net_name "+5V")
		(layer "F.Cu")
		(name "$teardrop_padvia$")
		(hatch none 0.1)
		(priority 30765)
		(attr
			(teardrop
				(type padvia)
			)
		)
		(connect_pads yes
			(clearance 0)
		)
		(min_thickness 0.0254)
		(filled_areas_thickness no)
		(fill yes
			(thermal_gap 0.5)
			(thermal_bridge_width 0.5)
			(island_removal_mode 1)
			(island_area_min 10)
		)
		(polygon
			(pts
				(xy 263.060708 76.160677) (xy 263.06764 76.0031) (xy 263.096164 75.889565) (xy 263.113208 75.847778)
				(xy 262.910708 75.759) (xy 262.708208 75.847778) (xy 262.742591 75.943822) (xy 262.757809 76.045702)
				(xy 262.760708 76.160677)
			)
		)
	)
	(zone
		(net 138)
		(net_name "Net-(U33-1A)")
		(layer "F.Cu")
		(name "$teardrop_padvia$")
		(hatch none 0.1)
		(priority 31681)
		(attr
			(teardrop
				(type padvia)
			)
		)
		(connect_pads yes
			(clearance 0)
		)
		(min_thickness 0.0254)
		(filled_areas_thickness no)
		(fill yes
			(thermal_gap 0.5)
			(thermal_bridge_width 0.5)
			(island_removal_mode 1)
			(island_area_min 10)
		)
		(polygon
			(pts
				(xy 250.4045 129.683) (xy 250.398978 129.710072) (xy 250.380322 129.735611) (xy 250.353703 129.75178)
				(xy 250.314962 129.761399) (xy 250.287 129.763) (xy 250.467 130.139) (xy 250.647 129.763) (xy 250.6015 129.758387)
				(xy 250.568532 129.7461) (xy 250.534156 129.707945) (xy 250.5295 129.683)
			)
		)
	)
	(zone
		(net 91)
		(net_name "/Com Express 7 Interfaces/PCIe_{B2Ax4}.RX1+")
		(layer "F.Cu")
		(name "$teardrop_padvia$")
		(hatch none 0.1)
		(priority 30257)
		(attr
			(teardrop
				(type padvia)
			)
		)
		(connect_pads yes
			(clearance 0)
		)
		(min_thickness 0.0254)
		(filled_areas_thickness no)
		(fill yes
			(thermal_gap 0.5)
			(thermal_bridge_width 0.5)
			(island_removal_mode 1)
			(island_area_min 10)
		)
		(polygon
			(pts
				(xy 212.4795 162.2) (xy 212.48258 162.214227) (xy 212.484749 162.244527) (xy 212.471877 162.255628)
				(xy 212.441705 162.26) (xy 212.525 163.136) (xy 212.675 162.887021) (xy 212.655644 162.645818) (xy 212.670401 162.373112)
				(xy 212.6815 162.2)
			)
		)
	)
	(zone
		(net 2)
		(net_name "+3V3")
		(layer "F.Cu")
		(name "$teardrop_padvia$")
		(hatch none 0.1)
		(priority 31513)
		(attr
			(teardrop
				(type padvia)
			)
		)
		(connect_pads yes
			(clearance 0)
		)
		(min_thickness 0.0254)
		(filled_areas_thickness no)
		(fill yes
			(thermal_gap 0.5)
			(thermal_bridge_width 0.5)
			(island_removal_mode 1)
			(island_area_min 10)
		)
		(polygon
			(pts
				(xy 212.949905 128.825) (xy 212.870191 128.829518) (xy 212.809107 128.841146) (xy 212.740723 128.863374)
				(xy 212.679403 128.883789) (xy 212.602212 128.899323) (xy 212.629 129.12) (xy 212.818374 129.24188)
				(xy 212.844362 129.173612) (xy 212.850851 129.137767) (xy 212.859206 129.094636) (xy 212.873923 129.058707)
				(xy 212.901867 129.034116) (xy 212.949905 129.025)
			)
		)
	)
	(zone
		(net 542)
		(net_name "Net-(Q9-E)")
		(layer "F.Cu")
		(name "$teardrop_padvia$")
		(hatch none 0.1)
		(priority 31762)
		(attr
			(teardrop
				(type padvia)
			)
		)
		(connect_pads yes
			(clearance 0)
		)
		(min_thickness 0.0254)
		(filled_areas_thickness no)
		(fill yes
			(thermal_gap 0.5)
			(thermal_bridge_width 0.5)
			(island_removal_mode 1)
			(island_area_min 10)
		)
		(polygon
			(pts
				(xy 255.349323 83.892499) (xy 255.418764 83.897317) (xy 255.470088 83.911039) (xy 255.545629 83.957754)
				(xy 255.557769 83.967298) (xy 255.624997 84.01708) (xy 255.751 83.829999) (xy 255.624997 83.642918)
				(xy 255.557768 83.692701) (xy 255.474602 83.747105) (xy 255.421748 83.762189) (xy 255.349323 83.767499)
			)
		)
	)
	(zone
		(net 710)
		(net_name "Net-(U37-SDAT)")
		(layer "F.Cu")
		(name "$teardrop_padvia$")
		(hatch none 0.1)
		(priority 32101)
		(attr
			(teardrop
				(type padvia)
			)
		)
		(connect_pads yes
			(clearance 0)
		)
		(min_thickness 0.0254)
		(filled_areas_thickness no)
		(fill yes
			(thermal_gap 0.5)
			(thermal_bridge_width 0.5)
			(island_removal_mode 1)
			(island_area_min 10)
		)
		(polygon
			(pts
				(xy 213.8155 125.834) (xy 213.816952 125.845797) (xy 213.817129 125.874081) (xy 213.808153 125.886652)
				(xy 213.788 125.895596) (xy 213.878 126.25) (xy 213.968 125.895596) (xy 213.947044 125.885992) (xy 213.93837 125.872447)
				(xy 213.939048 125.845797) (xy 213.9405 125.834)
			)
		)
	)
	(zone
		(net 742)
		(net_name "/2xSFP+/KR to SFI #2/TDI")
		(layer "F.Cu")
		(name "$teardrop_padvia$")
		(hatch none 0.1)
		(priority 31693)
		(attr
			(teardrop
				(type padvia)
			)
		)
		(connect_pads yes
			(clearance 0)
		)
		(min_thickness 0.0254)
		(filled_areas_thickness no)
		(fill yes
			(thermal_gap 0.5)
			(thermal_bridge_width 0.5)
			(island_removal_mode 1)
			(island_area_min 10)
		)
		(polygon
			(pts
				(xy 134.8775 129.739323) (xy 134.872682 129.808763) (xy 134.85896 129.860087) (xy 134.812245 129.935628)
				(xy 134.802702 129.947768) (xy 134.752919 130.014997) (xy 134.94 130.141) (xy 135.127081 130.014997)
				(xy 135.077299 129.947769) (xy 135.022894 129.864603) (xy 135.00781 129.811748) (xy 135.0025 129.739323)
			)
		)
	)
	(zone
		(net 1)
		(net_name "GND")
		(layer "F.Cu")
		(name "$teardrop_padvia$")
		(hatch none 0.1)
		(priority 31538)
		(attr
			(teardrop
				(type padvia)
			)
		)
		(connect_pads yes
			(clearance 0)
		)
		(min_thickness 0.0254)
		(filled_areas_thickness no)
		(fill yes
			(thermal_gap 0.5)
			(thermal_bridge_width 0.5)
			(island_removal_mode 1)
			(island_area_min 10)
		)
		(polygon
			(pts
				(xy 313.945123 166.91) (xy 313.882399 166.914633) (xy 313.832757 166.927061) (xy 313.742673 166.976045)
				(xy 313.682953 167.012417) (xy 313.604105 167.039323) (xy 313.647 167.26) (xy 313.868677 167.303895)
				(xy 313.872871 167.22711) (xy 313.87345 167.182675) (xy 313.881035 167.145322) (xy 313.902601 167.119586)
				(xy 313.945123 167.11)
			)
		)
	)
	(zone
		(net 86)
		(net_name "/Com Express 7 Interfaces/PCIe_{B2Ax4}.RX0-")
		(layer "F.Cu")
		(name "$teardrop_padvia$")
		(hatch none 0.1)
		(priority 31913)
		(attr
			(teardrop
				(type padvia)
			)
		)
		(connect_pads yes
			(clearance 0)
		)
		(min_thickness 0.0254)
		(filled_areas_thickness no)
		(fill yes
			(thermal_gap 0.5)
			(thermal_bridge_width 0.5)
			(island_removal_mode 1)
			(island_area_min 10)
		)
		(polygon
			(pts
				(xy 211.453582 164.376084) (xy 211.416489 164.419864) (xy 211.394353 164.460526) (xy 211.380371 164.538489)
				(xy 211.381391 164.580386) (xy 211.382283 164.637522) (xy 211.374444 164.702189) (xy 211.592793 164.750707)
				(xy 211.718503 164.562919) (xy 211.67124 164.549717) (xy 211.636676 164.547628) (xy 211.59265 164.542467)
				(xy 211.586423 164.534175) (xy 211.596417 164.518919)
			)
		)
	)
	(zone
		(net 109)
		(net_name "/2xSFP+/KR to SFI #1/CLK-")
		(layer "F.Cu")
		(name "$teardrop_padvia$")
		(hatch none 0.1)
		(priority 30058)
		(attr
			(teardrop
				(type padvia)
			)
		)
		(connect_pads yes
			(clearance 0)
		)
		(min_thickness 0.0254)
		(filled_areas_thickness no)
		(fill yes
			(thermal_gap 0.5)
			(thermal_bridge_width 0.5)
			(island_removal_mode 1)
			(island_area_min 10)
		)
		(polygon
			(pts
				(xy 141.525 139.537218) (xy 141.541955 139.508121) (xy 141.566702 139.485041) (xy 141.643444 139.454015)
				(xy 141.776601 139.444482) (xy 141.954172 139.46) (xy 141.9 138.934) (xy 141.5 138.866481) (xy 141.482258 139.103192)
				(xy 141.429236 139.348707) (xy 141.365 139.537218)
			)
		)
	)
	(zone
		(net 264)
		(net_name "/Com Express 7 Interfaces/PCIe_{B2Bx4}.RX0+")
		(layer "F.Cu")
		(name "$teardrop_padvia$")
		(hatch none 0.1)
		(priority 31439)
		(attr
			(teardrop
				(type padvia)
			)
		)
		(connect_pads yes
			(clearance 0)
		)
		(min_thickness 0.0254)
		(filled_areas_thickness no)
		(fill yes
			(thermal_gap 0.5)
			(thermal_bridge_width 0.5)
			(island_removal_mode 1)
			(island_area_min 10)
		)
		(polygon
			(pts
				(xy 186.436416 123.0955) (xy 186.482219 123.100235) (xy 186.5168 123.113381) (xy 186.563288 123.158329)
				(xy 186.586815 123.19758) (xy 186.613227 123.241575) (xy 186.649081 123.284165) (xy 186.801 123.123)
				(xy 186.784069 122.902323) (xy 186.606649 122.900471) (xy 186.436416 122.8935)
			)
		)
	)
	(zone
		(net 1)
		(net_name "GND")
		(layer "F.Cu")
		(name "$teardrop_padvia$")
		(hatch none 0.1)
		(priority 31919)
		(attr
			(teardrop
				(type padvia)
			)
		)
		(connect_pads yes
			(clearance 0)
		)
		(min_thickness 0.0254)
		(filled_areas_thickness no)
		(fill yes
			(thermal_gap 0.5)
			(thermal_bridge_width 0.5)
			(island_removal_mode 1)
			(island_area_min 10)
		)
		(polygon
			(pts
				(xy 110.8 152.94) (xy 110.799847 152.929885) (xy 110.80046 152.899168) (xy 110.808782 152.86668)
				(xy 110.832675 152.837525) (xy 110.88 152.816808) (xy 110.7 152.584) (xy 110.52 152.816808) (xy 110.555901 152.830167)
				(xy 110.579199 152.848398) (xy 110.598899 152.893724) (xy 110.600153 152.929885) (xy 110.6 152.94)
			)
		)
	)
	(zone
		(net 24)
		(net_name "/M.2 key E/~{CLKREQ}")
		(layer "F.Cu")
		(name "$teardrop_padvia$")
		(hatch none 0.1)
		(priority 31837)
		(attr
			(teardrop
				(type padvia)
			)
		)
		(connect_pads yes
			(clearance 0)
		)
		(min_thickness 0.0254)
		(filled_areas_thickness no)
		(fill yes
			(thermal_gap 0.5)
			(thermal_bridge_width 0.5)
			(island_removal_mode 1)
			(island_area_min 10)
		)
		(polygon
			(pts
				(xy 155.130677 83.9975) (xy 155.061458 83.992685) (xy 155.01027 83.978979) (xy 154.93495 83.932321)
				(xy 154.922656 83.922623) (xy 154.855003 83.872419) (xy 154.729 84.0595) (xy 154.855003 84.246581)
				(xy 154.921795 84.197226) (xy 155.005199 84.142842) (xy 155.058135 84.127793) (xy 155.130677 84.1225)
			)
		)
	)
	(zone
		(net 2)
		(net_name "+3V3")
		(layer "F.Cu")
		(name "$teardrop_padvia$")
		(hatch none 0.1)
		(priority 30359)
		(attr
			(teardrop
				(type padvia)
			)
		)
		(connect_pads yes
			(clearance 0)
		)
		(min_thickness 0.0254)
		(filled_areas_thickness no)
		(fill yes
			(thermal_gap 0.5)
			(thermal_bridge_width 0.5)
			(island_removal_mode 1)
			(island_area_min 10)
		)
		(polygon
			(pts
				(xy 263.766708 78.4855) (xy 263.800571 78.491281) (xy 263.835192 78.511745) (xy 263.857014 78.53881)
				(xy 263.872708 78.57815) (xy 263.875997 78.593711) (xy 264.582708 78.423) (xy 263.875997 78.252289)
				(xy 263.864408 78.29251) (xy 263.846824 78.321984) (xy 263.799242 78.355173) (xy 263.766708 78.3605)
			)
		)
	)
	(zone
		(net 285)
		(net_name "/2xUSB3.0+RJ45/GbE.MDI3-")
		(layer "F.Cu")
		(name "$teardrop_padvia$")
		(hatch none 0.1)
		(priority 31650)
		(attr
			(teardrop
				(type padvia)
			)
		)
		(connect_pads yes
			(clearance 0)
		)
		(min_thickness 0.0254)
		(filled_areas_thickness no)
		(fill yes
			(thermal_gap 0.5)
			(thermal_bridge_width 0.5)
			(island_removal_mode 1)
			(island_area_min 10)
		)
		(polygon
			(pts
				(xy 172.5 160.857916) (xy 172.502203 161.0633) (xy 172.504323 161.201757) (xy 172.725 161.201) (xy 172.850003 161.012919)
				(xy 172.773862 160.979004) (xy 172.757261 160.973949) (xy 172.715719 160.960156) (xy 172.681601 160.940737)
				(xy 172.658499 160.908917) (xy 172.65 160.857916)
			)
		)
	)
	(zone
		(net 312)
		(net_name "/2xUSB3.0+RJ45/USB_1.D-")
		(layer "F.Cu")
		(name "$teardrop_padvia$")
		(hatch none 0.1)
		(priority 31506)
		(attr
			(teardrop
				(type padvia)
			)
		)
		(connect_pads yes
			(clearance 0)
		)
		(min_thickness 0.0254)
		(filled_areas_thickness no)
		(fill yes
			(thermal_gap 0.5)
			(thermal_bridge_width 0.5)
			(island_removal_mode 1)
			(island_area_min 10)
		)
		(polygon
			(pts
				(xy 147.685321 115.773207) (xy 147.566083 115.659886) (xy 147.436795 115.530795) (xy 147.271251 115.677335)
				(xy 147.267509 115.898719) (xy 147.349818 115.885534) (xy 147.377902 115.876363) (xy 147.421487 115.863007)
				(xy 147.464102 115.858163) (xy 147.507768 115.869334) (xy 147.554506 115.904022)
			)
		)
	)
	(zone
		(net 204)
		(net_name "/Backplane/USB.D-")
		(layer "F.Cu")
		(name "$teardrop_padvia$")
		(hatch none 0.1)
		(priority 31507)
		(attr
			(teardrop
				(type padvia)
			)
		)
		(connect_pads yes
			(clearance 0)
		)
		(min_thickness 0.0254)
		(filled_areas_thickness no)
		(fill yes
			(thermal_gap 0.5)
			(thermal_bridge_width 0.5)
			(island_removal_mode 1)
			(island_area_min 10)
		)
		(polygon
			(pts
				(xy 226.085321 145.473207) (xy 225.966083 145.359886) (xy 225.836795 145.230795) (xy 225.671251 145.377335)
				(xy 225.667509 145.598719) (xy 225.749818 145.585534) (xy 225.777902 145.576363) (xy 225.821487 145.563007)
				(xy 225.864102 145.558163) (xy 225.907768 145.569334) (xy 225.954506 145.604022)
			)
		)
	)
	(zone
		(net 318)
		(net_name "Net-(J12D-LPC_SERIRQ{slash}~{ESPI_CS1})")
		(layer "F.Cu")
		(name "$teardrop_padvia$")
		(hatch none 0.1)
		(priority 30655)
		(attr
			(teardrop
				(type padvia)
			)
		)
		(connect_pads yes
			(clearance 0)
		)
		(min_thickness 0.0254)
		(filled_areas_thickness no)
		(fill yes
			(thermal_gap 0.5)
			(thermal_bridge_width 0.5)
			(island_removal_mode 1)
			(island_area_min 10)
		)
		(polygon
			(pts
				(xy 200.5875 169.62) (xy 200.598438 169.581177) (xy 200.620195 169.566067) (xy 200.66 169.56) (xy 200.525 168.684)
				(xy 200.39 169.56) (xy 200.425281 169.564517) (xy 200.446797 169.576138) (xy 200.461995 169.608961)
				(xy 200.4625 169.62)
			)
		)
	)
	(zone
		(net 186)
		(net_name "/OCuLink/PCIe_{x4}.RX0+")
		(layer "F.Cu")
		(name "$teardrop_padvia$")
		(hatch none 0.1)
		(priority 31419)
		(attr
			(teardrop
				(type padvia)
			)
		)
		(connect_pads yes
			(clearance 0)
		)
		(min_thickness 0.0254)
		(filled_areas_thickness no)
		(fill yes
			(thermal_gap 0.5)
			(thermal_bridge_width 0.5)
			(island_removal_mode 1)
			(island_area_min 10)
		)
		(polygon
			(pts
				(xy 97.004027 149.043744) (xy 97.114432 148.925708) (xy 97.171608 148.86351) (xy 97.246785 148.79487)
				(xy 97.105493 148.624079) (xy 96.884109 148.614618) (xy 96.894381 148.701455) (xy 96.899023 148.720088)
				(xy 96.909045 148.764757) (xy 96.91096 148.8084) (xy 96.897448 148.853092) (xy 96.861191 148.900908)
			)
		)
	)
	(zone
		(net 375)
		(net_name "/2xUSB3.0+RJ45/USB_2.D+")
		(layer "F.Cu")
		(name "$teardrop_padvia$")
		(hatch none 0.1)
		(priority 31478)
		(attr
			(teardrop
				(type padvia)
			)
		)
		(connect_pads yes
			(clearance 0)
		)
		(min_thickness 0.0254)
		(filled_areas_thickness no)
		(fill yes
			(thermal_gap 0.5)
			(thermal_bridge_width 0.5)
			(island_removal_mode 1)
			(island_area_min 10)
		)
		(polygon
			(pts
				(xy 197.0575 161.859584) (xy 197.06224 161.814972) (xy 197.075418 161.781575) (xy 197.120201 161.73798)
				(xy 197.16282 161.715148) (xy 197.210662 161.68949) (xy 197.256688 161.652895) (xy 197.0975 161.499)
				(xy 196.876823 161.512437) (xy 196.876683 161.695139) (xy 196.8725 161.859584)
			)
		)
	)
	(zone
		(net 946)
		(net_name "/2xSFP+/KR to SFI #1/BYP_RX+")
		(layer "F.Cu")
		(name "$teardrop_padvia$")
		(hatch none 0.1)
		(priority 31947)
		(attr
			(teardrop
				(type padvia)
			)
		)
		(connect_pads yes
			(clearance 0)
		)
		(min_thickness 0.0254)
		(filled_areas_thickness no)
		(fill yes
			(thermal_gap 0.5)
			(thermal_bridge_width 0.5)
			(island_removal_mode 1)
			(island_area_min 10)
		)
		(polygon
			(pts
				(xy 153.22 148.527721) (xy 153.231736 148.504685) (xy 153.254198 148.488987) (xy 153.330557 148.479864)
				(xy 153.388769 148.485) (xy 153.33 148.254) (xy 153.13 148.226463) (xy 153.125648 148.325256) (xy 153.084062 148.458347)
				(xy 153.06 148.527721)
			)
		)
	)
	(zone
		(net 145)
		(net_name "Net-(D24-C)")
		(layer "F.Cu")
		(hatch edge 0.5)
		(priority 10)
		(connect_pads yes
			(clearance 0.15)
		)
		(min_thickness 0.25)
		(filled_areas_thickness no)
		(fill yes
			(thermal_gap 0.5)
			(thermal_bridge_width 0.5)
		)
		(polygon
			(pts
				(xy 313.025 148.51) (xy 313.025 145.21) (xy 308.55 145.21) (xy 307.45 146.31) (xy 307.45 148.51)
			)
		)
	)
	(zone
		(net 1)
		(net_name "GND")
		(layer "F.Cu")
		(name "$teardrop_padvia$")
		(hatch none 0.1)
		(priority 32001)
		(attr
			(teardrop
				(type padvia)
			)
		)
		(connect_pads yes
			(clearance 0)
		)
		(min_thickness 0.0254)
		(filled_areas_thickness no)
		(fill yes
			(thermal_gap 0.5)
			(thermal_bridge_width 0.5)
			(island_removal_mode 1)
			(island_area_min 10)
		)
		(polygon
			(pts
				(xy 239.187501 156.451) (xy 239.176564 156.489823) (xy 239.154806 156.504933) (xy 239.115001 156.511)
				(xy 239.25 156.862) (xy 239.385001 156.511) (xy 239.34972 156.506483) (xy 239.328204 156.494862)
				(xy 239.313006 156.462039) (xy 239.312501 156.451)
			)
		)
	)
	(zone
		(net 545)
		(net_name "Net-(Q11-G)")
		(layer "F.Cu")
		(name "$teardrop_padvia$")
		(hatch none 0.1)
		(priority 30317)
		(attr
			(teardrop
				(type padvia)
			)
		)
		(connect_pads yes
			(clearance 0)
		)
		(min_thickness 0.0254)
		(filled_areas_thickness no)
		(fill yes
			(thermal_gap 0.5)
			(thermal_bridge_width 0.5)
			(island_removal_mode 1)
			(island_area_min 10)
		)
		(polygon
			(pts
				(xy 252.569656 128.051957) (xy 252.548783 128.049717) (xy 252.531431 128.037413) (xy 252.505717 127.980495)
				(xy 252.493149 127.866558) (xy 251.999293 128.111707) (xy 252.483734 128.369531) (xy 252.507648 128.272917)
				(xy 252.563361 128.192437) (xy 252.600131 128.162976) (xy 252.637704 128.144986) (xy 252.658043 128.140344)
			)
		)
	)
	(zone
		(net 210)
		(net_name "/Com Express 7 Interfaces/PCIe_{B1x4}.RX3+")
		(layer "F.Cu")
		(name "$teardrop_padvia$")
		(hatch none 0.1)
		(priority 31397)
		(attr
			(teardrop
				(type padvia)
			)
		)
		(connect_pads yes
			(clearance 0)
		)
		(min_thickness 0.0254)
		(filled_areas_thickness no)
		(fill yes
			(thermal_gap 0.5)
			(thermal_bridge_width 0.5)
			(island_removal_mode 1)
			(island_area_min 10)
		)
		(polygon
			(pts
				(xy 204.6815 161.767496) (xy 204.676105 161.605964) (xy 204.672555 161.521553) (xy 204.677177 161.419859)
				(xy 204.4565 161.399) (xy 204.293268 161.548852) (xy 204.361936 161.602992) (xy 204.378392 161.612884)
				(xy 204.417064 161.637384) (xy 204.449279 161.66689) (xy 204.471327 161.708046) (xy 204.4795 161.767496)
			)
		)
	)
	(zone
		(net 591)
		(net_name "Net-(U24-+12V_{IN})")
		(layer "F.Cu")
		(name "$teardrop_padvia$")
		(hatch none 0.1)
		(priority 30831)
		(attr
			(teardrop
				(type padvia)
			)
		)
		(connect_pads yes
			(clearance 0)
		)
		(min_thickness 0.0254)
		(filled_areas_thickness no)
		(fill yes
			(thermal_gap 0.5)
			(thermal_bridge_width 0.5)
			(island_removal_mode 1)
			(island_area_min 10)
		)
		(polygon
			(pts
				(xy 253.55452 87.539999) (xy 253.525196 87.534905) (xy 253.499158 87.519244) (xy 253.460901 87.457936)
				(xy 253.440704 87.338111) (xy 253.440001 87.294439) (xy 253.144001 87.45) (xy 253.292501 87.77)
				(xy 253.353777 87.738091) (xy 253.441427 87.731092) (xy 253.499946 87.735964) (xy 253.55452 87.739999)
			)
		)
	)
	(zone
		(net 949)
		(net_name "/2xSFP+/KR to SFI #2/BYP_RX+")
		(layer "F.Cu")
		(name "$teardrop_padvia$")
		(hatch none 0.1)
		(priority 31958)
		(attr
			(teardrop
				(type padvia)
			)
		)
		(connect_pads yes
			(clearance 0)
		)
		(min_thickness 0.0254)
		(filled_areas_thickness no)
		(fill yes
			(thermal_gap 0.5)
			(thermal_bridge_width 0.5)
			(island_removal_mode 1)
			(island_area_min 10)
		)
		(polygon
			(pts
				(xy 131.68 148.553721) (xy 131.655938 148.484348) (xy 131.619423 148.374401) (xy 131.609113 148.314313)
				(xy 131.61 148.252463) (xy 131.41 148.28) (xy 131.351231 148.511) (xy 131.432579 148.505702) (xy 131.484596 148.514493)
				(xy 131.506116 148.528345) (xy 131.518354 148.548403) (xy 131.52 148.553721)
			)
		)
	)
	(zone
		(net 736)
		(net_name "Net-(U43A-LS_OK_{OUT_A})")
		(layer "F.Cu")
		(name "$teardrop_padvia$")
		(hatch none 0.1)
		(priority 30107)
		(attr
			(teardrop
				(type padvia)
			)
		)
		(connect_pads yes
			(clearance 0)
		)
		(min_thickness 0.0254)
		(filled_areas_thickness no)
		(fill yes
			(thermal_gap 0.5)
			(thermal_bridge_width 0.5)
			(island_removal_mode 1)
			(island_area_min 10)
		)
		(polygon
			(pts
				(xy 150.5625 129.377794) (xy 150.567315 129.295733) (xy 150.581019 129.230388) (xy 150.627576 129.13712)
				(xy 150.695787 129.058657) (xy 150.751942 128.997158) (xy 150.811801 128.918339) (xy 150.5 128.709)
				(xy 150.188199 128.918339) (xy 150.285219 129.038517) (xy 150.304214 129.058658) (xy 150.357366 129.117541)
				(xy 150.399591 129.181624) (xy 150.427449 129.264008) (xy 150.4375 129.377794)
			)
		)
	)
	(zone
		(net 491)
		(net_name "/2xSFP+/MDIO0.MDIO")
		(layer "F.Cu")
		(name "$teardrop_padvia$")
		(hatch none 0.1)
		(priority 31732)
		(attr
			(teardrop
				(type padvia)
			)
		)
		(connect_pads yes
			(clearance 0)
		)
		(min_thickness 0.0254)
		(filled_areas_thickness no)
		(fill yes
			(thermal_gap 0.5)
			(thermal_bridge_width 0.5)
			(island_removal_mode 1)
			(island_area_min 10)
		)
		(polygon
			(pts
				(xy 143.7765 152.109323) (xy 143.771682 152.178763) (xy 143.75796 152.230087) (xy 143.711245 152.305628)
				(xy 143.701702 152.317768) (xy 143.651919 152.384997) (xy 143.839 152.511) (xy 144.026081 152.384997)
				(xy 143.976299 152.317769) (xy 143.921894 152.234603) (xy 143.90681 152.181748) (xy 143.9015 152.109323)
			)
		)
	)
	(zone
		(net 899)
		(net_name "Net-(D4-C)")
		(layer "F.Cu")
		(name "$teardrop_padvia$")
		(hatch none 0.1)
		(priority 30175)
		(attr
			(teardrop
				(type padvia)
			)
		)
		(connect_pads yes
			(clearance 0)
		)
		(min_thickness 0.0254)
		(filled_areas_thickness no)
		(fill yes
			(thermal_gap 0.5)
			(thermal_bridge_width 0.5)
			(island_removal_mode 1)
			(island_area_min 10)
		)
		(polygon
			(pts
				(xy 147.75 156.1075) (xy 147.69156 156.088243) (xy 147.637486 156.027235) (xy 147.597203 155.917634)
				(xy 147.586022 155.81) (xy 147.189 156.17) (xy 147.586022 156.53) (xy 147.591642 156.454212) (xy 147.605856 156.387749)
				(xy 147.627451 156.331481) (xy 147.655051 156.286792) (xy 147.685041 156.256501) (xy 147.718017 156.238124)
				(xy 147.75 156.2325)
			)
		)
	)
	(zone
		(net 227)
		(net_name "/Com Express 7 Interfaces/PCIe_{B1x4}.TX0+")
		(layer "F.Cu")
		(name "$teardrop_padvia$")
		(hatch none 0.1)
		(priority 30262)
		(attr
			(teardrop
				(type padvia)
			)
		)
		(connect_pads yes
			(clearance 0)
		)
		(min_thickness 0.0254)
		(filled_areas_thickness no)
		(fill yes
			(thermal_gap 0.5)
			(thermal_bridge_width 0.5)
			(island_removal_mode 1)
			(island_area_min 10)
		)
		(polygon
			(pts
				(xy 209.6815 169.62) (xy 209.670401 169.446888) (xy 209.655784 169.21949) (xy 209.658819 169.084862)
				(xy 209.675 168.932978) (xy 209.525 168.684) (xy 209.441705 169.56) (xy 209.472136 169.564477) (xy 209.484903 169.575815)
				(xy 209.48258 169.605773) (xy 209.4795 169.62)
			)
		)
	)
	(zone
		(net 73)
		(net_name "+3V3_AON")
		(layer "F.Cu")
		(name "$teardrop_padvia$")
		(hatch none 0.1)
		(priority 31560)
		(attr
			(teardrop
				(type padvia)
			)
		)
		(connect_pads yes
			(clearance 0)
		)
		(min_thickness 0.0254)
		(filled_areas_thickness no)
		(fill yes
			(thermal_gap 0.5)
			(thermal_bridge_width 0.5)
			(island_removal_mode 1)
			(island_area_min 10)
		)
		(polygon
			(pts
				(xy 307.908 152.888) (xy 307.899751 152.865923) (xy 307.889017 152.827428) (xy 307.901982 152.813475)
				(xy 307.938 152.808) (xy 307.758 152.432) (xy 307.578 152.808) (xy 307.611735 152.81254) (xy 307.625928 152.824323)
				(xy 307.622446 152.852817) (xy 307.616249 152.865923) (xy 307.608 152.888)
			)
		)
	)
	(zone
		(net 328)
		(net_name "/Com Express 7 Interfaces/PCIe_{B2Ax4}.TX2+")
		(layer "F.Cu")
		(name "$teardrop_padvia$")
		(hatch none 0.1)
		(priority 31450)
		(attr
			(teardrop
				(type padvia)
			)
		)
		(connect_pads yes
			(clearance 0)
		)
		(min_thickness 0.0254)
		(filled_areas_thickness no)
		(fill yes
			(thermal_gap 0.5)
			(thermal_bridge_width 0.5)
			(island_removal_mode 1)
			(island_area_min 10)
		)
		(polygon
			(pts
				(xy 230.8565 147.163584) (xy 230.849528 146.993351) (xy 230.847677 146.815931) (xy 230.627 146.799)
				(xy 230.465834 146.950918) (xy 230.534098 147.00277) (xy 230.552419 147.013184) (xy 230.591426 147.036544)
				(xy 230.623955 147.064991) (xy 230.646236 147.105135) (xy 230.6545 147.163584)
			)
		)
	)
	(zone
		(net 55)
		(net_name "/USB-C console/USB_D+")
		(layer "F.Cu")
		(name "$teardrop_padvia$")
		(hatch none 0.1)
		(priority 30414)
		(attr
			(teardrop
				(type padvia)
			)
		)
		(connect_pads yes
			(clearance 0)
		)
		(min_thickness 0.0254)
		(filled_areas_thickness no)
		(fill yes
			(thermal_gap 0.5)
			(thermal_bridge_width 0.5)
			(island_removal_mode 1)
			(island_area_min 10)
		)
		(polygon
			(pts
				(xy 110.129277 75.543501) (xy 110.103629 75.534201) (xy 110.084376 75.515759) (xy 110.064065 75.452301)
				(xy 110.068765 75.321037) (xy 110.076999 75.264894) (xy 109.755999 75.356) (xy 109.706817 75.651)
				(xy 109.831822 75.654779) (xy 110.012995 75.698637) (xy 110.129277 75.728501)
			)
		)
	)
	(zone
		(net 115)
		(net_name "/2xSFP+/KR to SFI #2/CLK+")
		(layer "F.Cu")
		(name "$teardrop_padvia$")
		(hatch none 0.1)
		(priority 30037)
		(attr
			(teardrop
				(type padvia)
			)
		)
		(connect_pads yes
			(clearance 0)
		)
		(min_thickness 0.0254)
		(filled_areas_thickness no)
		(fill yes
			(thermal_gap 0.5)
			(thermal_bridge_width 0.5)
			(island_removal_mode 1)
			(island_area_min 10)
		)
		(polygon
			(pts
				(xy 122.985 139.644) (xy 122.968974 139.454959) (xy 122.953201 139.345519) (xy 122.923178 139.122038)
				(xy 122.91 138.884507) (xy 122.45 138.934) (xy 122.295368 139.46) (xy 122.463489 139.465389) (xy 122.606914 139.483115)
				(xy 122.689429 139.504203) (xy 122.754344 139.533341) (xy 122.790086 139.560915) (xy 122.813772 139.593797)
				(xy 122.825 139.644)
			)
		)
	)
	(zone
		(net 1)
		(net_name "GND")
		(layer "F.Cu")
		(name "$teardrop_padvia$")
		(hatch none 0.1)
		(priority 30549)
		(attr
			(teardrop
				(type padvia)
			)
		)
		(connect_pads yes
			(clearance 0)
		)
		(min_thickness 0.0254)
		(filled_areas_thickness no)
		(fill yes
			(thermal_gap 0.5)
			(thermal_bridge_width 0.5)
			(island_removal_mode 1)
			(island_area_min 10)
		)
		(polygon
			(pts
				(xy 219.125 157.62) (xy 219.121667 157.605514) (xy 219.11881 157.57539) (xy 219.130964 157.564349)
				(xy 219.16 157.56) (xy 219.025 156.684) (xy 218.89 157.56) (xy 218.919334 157.564475) (xy 218.931358 157.575801)
				(xy 218.928333 157.605514) (xy 218.925 157.62)
			)
		)
	)
	(zone
		(net 1)
		(net_name "GND")
		(layer "F.Cu")
		(name "$teardrop_padvia$")
		(hatch none 0.1)
		(priority 30442)
		(attr
			(teardrop
				(type padvia)
			)
		)
		(connect_pads yes
			(clearance 0)
		)
		(min_thickness 0.0254)
		(filled_areas_thickness no)
		(fill yes
			(thermal_gap 0.5)
			(thermal_bridge_width 0.5)
			(island_removal_mode 1)
			(island_area_min 10)
		)
		(polygon
			(pts
				(xy 113.756433 147.178045) (xy 113.704441 147.098305) (xy 113.672423 146.973241) (xy 113.67296 146.805568)
				(xy 113.675 146.78889) (xy 113.379293 146.859293) (xy 113.313201 147.18) (xy 113.46183 147.179012)
				(xy 113.529693 147.192388) (xy 113.588815 147.213581) (xy 113.668045 147.266433)
			)
		)
	)
	(zone
		(net 1)
		(net_name "GND")
		(layer "F.Cu")
		(hatch edge 0.5)
		(priority 44)
		(connect_pads yes
			(clearance 0.15)
		)
		(min_thickness 0.25)
		(filled_areas_thickness no)
		(fill yes
			(thermal_gap 0.5)
			(thermal_bridge_width 0.5)
		)
		(polygon
			(pts
				(xy 318.75 114.72) (xy 309.454999 114.72) (xy 308.804999 115.37) (xy 308.804999 119.9) (xy 308.924999 120.02)
				(xy 310.27 120.02) (xy 311.52 118.77) (xy 318.75 118.77)
			)
		)
	)
	(zone
		(net 1)
		(net_name "GND")
		(layer "F.Cu")
		(name "$teardrop_padvia$")
		(hatch none 0.1)
		(priority 30564)
		(attr
			(teardrop
				(type padvia)
			)
		)
		(connect_pads yes
			(clearance 0)
		)
		(min_thickness 0.0254)
		(filled_areas_thickness no)
		(fill yes
			(thermal_gap 0.5)
			(thermal_bridge_width 0.5)
			(island_removal_mode 1)
			(island_area_min 10)
		)
		(polygon
			(pts
				(xy 175.925 150.2) (xy 175.928333 150.214486) (xy 175.93119 150.24461) (xy 175.919036 150.255651)
				(xy 175.89 150.26) (xy 176.025 151.136) (xy 176.16 150.26) (xy 176.130666 150.255525) (xy 176.118642 150.244199)
				(xy 176.121667 150.214486) (xy 176.125 150.2)
			)
		)
	)
	(zone
		(net 57)
		(net_name "/USB-C console/FTDI_VCCIO")
		(layer "F.Cu")
		(name "$teardrop_padvia$")
		(hatch none 0.1)
		(priority 31666)
		(attr
			(teardrop
				(type padvia)
			)
		)
		(connect_pads yes
			(clearance 0)
		)
		(min_thickness 0.0254)
		(filled_areas_thickness no)
		(fill yes
			(thermal_gap 0.5)
			(thermal_bridge_width 0.5)
			(island_removal_mode 1)
			(island_area_min 10)
		)
		(polygon
			(pts
				(xy 112.825657 76.84773) (xy 112.842064 76.852003) (xy 112.852182 76.866609) (xy 112.859999 76.979198)
				(xy 112.859999 76.982848) (xy 113.260706 76.799293) (xy 112.859999 76.622834) (xy 112.842755 76.689948)
				(xy 112.796004 76.738758) (xy 112.73727 76.759343)
			)
		)
	)
	(zone
		(net 73)
		(net_name "+3V3_AON")
		(layer "F.Cu")
		(name "$teardrop_padvia$")
		(hatch none 0.1)
		(priority 30501)
		(attr
			(teardrop
				(type padvia)
			)
		)
		(connect_pads yes
			(clearance 0)
		)
		(min_thickness 0.0254)
		(filled_areas_thickness no)
		(fill yes
			(thermal_gap 0.5)
			(thermal_bridge_width 0.5)
			(island_removal_mode 1)
			(island_area_min 10)
		)
		(polygon
			(pts
				(xy 251.235556 131.578944) (xy 251.285409 131.656761) (xy 251.313529 131.778204) (xy 251.314743 131.852476)
				(xy 251.305492 131.932762) (xy 251.305 131.935474) (xy 251.625707 131.880707) (xy 251.705474 131.585)
				(xy 251.619034 131.588538) (xy 251.539401 131.582454) (xy 251.466862 131.567419) (xy 251.404048 131.544456)
				(xy 251.323944 131.490556)
			)
		)
	)
	(zone
		(net 1)
		(net_name "GND")
		(layer "F.Cu")
		(name "$teardrop_padvia$")
		(hatch none 0.1)
		(priority 30725)
		(attr
			(teardrop
				(type padvia)
			)
		)
		(connect_pads yes
			(clearance 0)
		)
		(min_thickness 0.0254)
		(filled_areas_thickness no)
		(fill yes
			(thermal_gap 0.5)
			(thermal_bridge_width 0.5)
			(island_removal_mode 1)
			(island_area_min 10)
		)
		(polygon
			(pts
				(xy 302.8875 105.45) (xy 302.892821 105.418265) (xy 302.910069 105.385565) (xy 302.936538 105.359374)
				(xy 302.974964 105.338445) (xy 303.01705 105.32705) (xy 302.825 104.809) (xy 302.63295 105.32705)
				(xy 302.677474 105.339409) (xy 302.7116 105.358008) (xy 302.753536 105.408803) (xy 302.7625 105.45)
			)
		)
	)
	(zone
		(net 72)
		(net_name "Net-(U20-CT)")
		(layer "F.Cu")
		(name "$teardrop_padvia$")
		(hatch none 0.1)
		(priority 31530)
		(attr
			(teardrop
				(type padvia)
			)
		)
		(connect_pads yes
			(clearance 0)
		)
		(min_thickness 0.0254)
		(filled_areas_thickness no)
		(fill yes
			(thermal_gap 0.5)
			(thermal_bridge_width 0.5)
			(island_removal_mode 1)
			(island_area_min 10)
		)
		(polygon
			(pts
				(xy 304.5575 128.754) (xy 304.537837 128.80383) (xy 304.476394 128.843532) (xy 304.36274 128.863697)
				(xy 304.344442 128.864) (xy 304.54 129.14) (xy 304.849962 128.864) (xy 304.797598 128.859324) (xy 304.755388 128.846588)
				(xy 304.722395 128.827225) (xy 304.699457 128.803531) (xy 304.6825 128.754)
			)
		)
	)
	(zone
		(net 73)
		(net_name "+3V3_AON")
		(layer "F.Cu")
		(name "$teardrop_padvia$")
		(hatch none 0.1)
		(priority 30157)
		(attr
			(teardrop
				(type padvia)
			)
		)
		(connect_pads yes
			(clearance 0)
		)
		(min_thickness 0.0254)
		(filled_areas_thickness no)
		(fill yes
			(thermal_gap 0.5)
			(thermal_bridge_width 0.5)
			(island_removal_mode 1)
			(island_area_min 10)
		)
		(polygon
			(pts
				(xy 190.60861 73.542163) (xy 190.60355 73.575682) (xy 190.588129 73.608588) (xy 190.562347 73.6389)
				(xy 190.525738 73.665407) (xy 190.478562 73.68631) (xy 190.420127 73.700395) (xy 190.34861 73.706141)
				(xy 190.70861 74.103163) (xy 191.06861 73.706141) (xy 190.998539 73.700621) (xy 190.940004 73.686759)
				(xy 190.892657 73.666073) (xy 190.856184 73.640095) (xy 190.8301 73.610127) (xy 190.814368 73.577901)
				(xy 190.80861 73.542163)
			)
		)
	)
	(zone
		(net 535)
		(net_name "Net-(Q3-G)")
		(layer "F.Cu")
		(hatch edge 0.5)
		(priority 31)
		(connect_pads yes
			(clearance 0.15)
		)
		(min_thickness 0.25)
		(filled_areas_thickness no)
		(fill yes
			(thermal_gap 0.5)
			(thermal_bridge_width 0.5)
			(smoothing fillet)
			(radius 0.2)
			(island_removal_mode 1)
			(island_area_min 10)
		)
		(polygon
			(pts
				(xy 288.95 103.21) (xy 289.7 103.21) (xy 289.7 101.51) (xy 289.1 101.51) (xy 288.8 101.21) (xy 288.8 99.96)
				(xy 288.1 99.96) (xy 288.1 102.36)
			)
		)
	)
	(zone
		(net 1)
		(net_name "GND")
		(layer "F.Cu")
		(name "$teardrop_padvia$")
		(hatch none 0.1)
		(priority 31233)
		(attr
			(teardrop
				(type padvia)
			)
		)
		(connect_pads yes
			(clearance 0)
		)
		(min_thickness 0.0254)
		(filled_areas_thickness no)
		(fill yes
			(thermal_gap 0.5)
			(thermal_bridge_width 0.5)
			(island_removal_mode 1)
			(island_area_min 10)
		)
		(polygon
			(pts
				(xy 179.625 150.350677) (xy 179.629737 150.259676) (xy 179.642896 150.192587) (xy 179.675418 150.105855)
				(xy 179.707644 150.025358) (xy 179.5 149.949) (xy 179.303541 150.052363) (xy 179.355343 150.135863)
				(xy 179.404833 150.221955) (xy 179.419614 150.27716) (xy 179.425 150.350677)
			)
		)
	)
	(zone
		(net 869)
		(net_name "/Backplane/PCIe_{x2}.TX1-")
		(layer "F.Cu")
		(name "$teardrop_padvia$")
		(hatch none 0.1)
		(priority 30265)
		(attr
			(teardrop
				(type padvia)
			)
		)
		(connect_pads yes
			(clearance 0)
		)
		(min_thickness 0.0254)
		(filled_areas_thickness no)
		(fill yes
			(thermal_gap 0.5)
			(thermal_bridge_width 0.5)
			(island_removal_mode 1)
			(island_area_min 10)
		)
		(polygon
			(pts
				(xy 203.3685 150.2) (xy 203.379599 150.373112) (xy 203.394216 150.60051) (xy 203.391181 150.735138)
				(xy 203.375 150.887021) (xy 203.525 151.136) (xy 203.608295 150.26) (xy 203.577864 150.255523) (xy 203.565097 150.244185)
				(xy 203.56742 150.214227) (xy 203.5705 150.2)
			)
		)
	)
	(zone
		(net 286)
		(net_name "/2xUSB3.0+RJ45/GbE.MDI3+")
		(layer "F.Cu")
		(name "$teardrop_padvia$")
		(hatch none 0.1)
		(priority 30314)
		(attr
			(teardrop
				(type padvia)
			)
		)
		(connect_pads yes
			(clearance 0)
		)
		(min_thickness 0.0254)
		(filled_areas_thickness no)
		(fill yes
			(thermal_gap 0.5)
			(thermal_bridge_width 0.5)
			(island_removal_mode 1)
			(island_area_min 10)
		)
		(polygon
			(pts
				(xy 176.875 167.75) (xy 176.882191 167.932252) (xy 176.891641 168.183885) (xy 176.888369 168.333893)
				(xy 176.875 168.504204) (xy 177.025 168.686) (xy 177.090241 167.81) (xy 177.055265 167.805495) (xy 177.035678 167.793958)
				(xy 177.024981 167.762811) (xy 177.024965 167.754084) (xy 177.025 167.75)
			)
		)
	)
	(zone
		(net 371)
		(net_name "/Com Express 7 MGMT/I2C.SCL")
		(layer "F.Cu")
		(name "$teardrop_padvia$")
		(hatch none 0.1)
		(priority 31830)
		(attr
			(teardrop
				(type padvia)
			)
		)
		(connect_pads yes
			(clearance 0)
		)
		(min_thickness 0.0254)
		(filled_areas_thickness no)
		(fill yes
			(thermal_gap 0.5)
			(thermal_bridge_width 0.5)
			(island_removal_mode 1)
			(island_area_min 10)
		)
		(polygon
			(pts
				(xy 240.575677 153.0375) (xy 240.506236 153.032682) (xy 240.454913 153.01896) (xy 240.379371 152.972246)
				(xy 240.367231 152.962701) (xy 240.300003 152.912919) (xy 240.174 153.1) (xy 240.300003 153.287081)
				(xy 240.367229 153.237299) (xy 240.450396 153.182894) (xy 240.503251 153.16781) (xy 240.575677 153.1625)
			)
		)
	)
	(zone
		(net 1)
		(net_name "GND")
		(layer "F.Cu")
		(name "$teardrop_padvia$")
		(hatch none 0.1)
		(priority 30537)
		(attr
			(teardrop
				(type padvia)
			)
		)
		(connect_pads yes
			(clearance 0)
		)
		(min_thickness 0.0254)
		(filled_areas_thickness no)
		(fill yes
			(thermal_gap 0.5)
			(thermal_bridge_width 0.5)
			(island_removal_mode 1)
			(island_area_min 10)
		)
		(polygon
			(pts
				(xy 215.425 167.75) (xy 215.428333 167.764486) (xy 215.43119 167.79461) (xy 215.419036 167.805651)
				(xy 215.39 167.81) (xy 215.525 168.686) (xy 215.66 167.81) (xy 215.630666 167.805525) (xy 215.618642 167.794199)
				(xy 215.621667 167.764486) (xy 215.625 167.75)
			)
		)
	)
	(zone
		(net 1)
		(net_name "GND")
		(layer "F.Cu")
		(name "$teardrop_padvia$")
		(hatch none 0.1)
		(priority 31217)
		(attr
			(teardrop
				(type padvia)
			)
		)
		(connect_pads yes
			(clearance 0)
		)
		(min_thickness 0.0254)
		(filled_areas_thickness no)
		(fill yes
			(thermal_gap 0.5)
			(thermal_bridge_width 0.5)
			(island_removal_mode 1)
			(island_area_min 10)
		)
		(polygon
			(pts
				(xy 195.925 169.498323) (xy 195.92028 169.567646) (xy 195.907244 169.620549) (xy 195.855344 169.713135)
				(xy 195.803541 169.796636) (xy 196 169.9) (xy 196.207644 169.823641) (xy 196.175418 169.743142)
				(xy 196.139035 169.641683) (xy 196.125 169.498323)
			)
		)
	)
	(zone
		(net 1)
		(net_name "GND")
		(layer "F.Cu")
		(name "$teardrop_padvia$")
		(hatch none 0.1)
		(priority 31207)
		(attr
			(teardrop
				(type padvia)
			)
		)
		(connect_pads yes
			(clearance 0)
		)
		(min_thickness 0.0254)
		(filled_areas_thickness no)
		(fill yes
			(thermal_gap 0.5)
			(thermal_bridge_width 0.5)
			(island_removal_mode 1)
			(island_area_min 10)
		)
		(polygon
			(pts
				(xy 180.925 157.499323) (xy 180.92028 157.568646) (xy 180.907244 157.621549) (xy 180.855344 157.714135)
				(xy 180.803541 157.797636) (xy 181 157.901) (xy 181.207644 157.824641) (xy 181.175418 157.744142)
				(xy 181.139035 157.642683) (xy 181.125 157.499323)
			)
		)
	)
	(zone
		(net 471)
		(net_name "Net-(J12K-10G_SDP3)")
		(layer "F.Cu")
		(name "$teardrop_padvia$")
		(hatch none 0.1)
		(priority 31627)
		(attr
			(teardrop
				(type padvia)
			)
		)
		(connect_pads yes
			(clearance 0)
		)
		(min_thickness 0.0254)
		(filled_areas_thickness no)
		(fill yes
			(thermal_gap 0.5)
			(thermal_bridge_width 0.5)
			(island_removal_mode 1)
			(island_area_min 10)
		)
		(polygon
			(pts
				(xy 184.0875 149.407479) (xy 184.092276 149.369801) (xy 184.105706 149.34454) (xy 184.148052 149.322287)
				(xy 184.218907 149.317945) (xy 184.289922 149.314876) (xy 184.358461 149.293932) (xy 184.25 149.099)
				(xy 184.029323 149.057915) (xy 183.996589 149.184419) (xy 183.972558 149.275974) (xy 183.9625 149.407479)
			)
		)
	)
	(zone
		(net 1)
		(net_name "GND")
		(layer "F.Cu")
		(name "$teardrop_padvia$")
		(hatch none 0.1)
		(priority 31926)
		(attr
			(teardrop
				(type padvia)
			)
		)
		(connect_pads yes
			(clearance 0)
		)
		(min_thickness 0.0254)
		(filled_areas_thickness no)
		(fill yes
			(thermal_gap 0.5)
			(thermal_bridge_width 0.5)
			(island_removal_mode 1)
			(island_area_min 10)
		)
		(polygon
			(pts
				(xy 112.118 137.81) (xy 112.107885 137.810153) (xy 112.077169 137.80954) (xy 112.04468 137.801218)
				(xy 112.015526 137.777325) (xy 111.994809 137.73) (xy 111.762 137.91) (xy 111.994809 138.09) (xy 112.008168 138.054099)
				(xy 112.026399 138.030801) (xy 112.071725 138.011101) (xy 112.107885 138.009847) (xy 112.118 138.01)
			)
		)
	)
	(zone
		(net 1)
		(net_name "GND")
		(layer "F.Cu")
		(name "$teardrop_padvia$")
		(hatch none 0.1)
		(priority 30529)
		(attr
			(teardrop
				(type padvia)
			)
		)
		(connect_pads yes
			(clearance 0)
		)
		(min_thickness 0.0254)
		(filled_areas_thickness no)
		(fill yes
			(thermal_gap 0.5)
			(thermal_bridge_width 0.5)
			(island_removal_mode 1)
			(island_area_min 10)
		)
		(polygon
			(pts
				(xy 210.625 152.07) (xy 210.621667 152.055514) (xy 210.61881 152.02539) (xy 210.630964 152.014349)
				(xy 210.66 152.01) (xy 210.525 151.134) (xy 210.39 152.01) (xy 210.419334 152.014475) (xy 210.431358 152.025801)
				(xy 210.428333 152.055514) (xy 210.425 152.07)
			)
		)
	)
	(zone
		(net 1)
		(net_name "GND")
		(layer "F.Cu")
		(name "$teardrop_padvia$")
		(hatch none 0.1)
		(priority 31223)
		(attr
			(teardrop
				(type padvia)
			)
		)
		(connect_pads yes
			(clearance 0)
		)
		(min_thickness 0.0254)
		(filled_areas_thickness no)
		(fill yes
			(thermal_gap 0.5)
			(thermal_bridge_width 0.5)
			(island_removal_mode 1)
			(island_area_min 10)
		)
		(polygon
			(pts
				(xy 176.125 162.100677) (xy 176.129737 162.009676) (xy 176.142896 161.942587) (xy 176.175418 161.855855)
				(xy 176.207644 161.775358) (xy 176 161.699) (xy 175.803541 161.802363) (xy 175.855343 161.885863)
				(xy 175.904833 161.971955) (xy 175.919614 162.02716) (xy 175.925 162.100677)
			)
		)
	)
	(zone
		(net 1)
		(net_name "GND")
		(layer "F.Cu")
		(name "$teardrop_padvia$")
		(hatch none 0.1)
		(priority 30536)
		(attr
			(teardrop
				(type padvia)
			)
		)
		(connect_pads yes
			(clearance 0)
		)
		(min_thickness 0.0254)
		(filled_areas_thickness no)
		(fill yes
			(thermal_gap 0.5)
			(thermal_bridge_width 0.5)
			(island_removal_mode 1)
			(island_area_min 10)
		)
		(polygon
			(pts
				(xy 197.425 150.2) (xy 197.428333 150.214486) (xy 197.43119 150.24461) (xy 197.419036 150.255651)
				(xy 197.39 150.26) (xy 197.525 151.136) (xy 197.66 150.26) (xy 197.630666 150.255525) (xy 197.618642 150.244199)
				(xy 197.621667 150.214486) (xy 197.625 150.2)
			)
		)
	)
	(zone
		(net 999)
		(net_name "Net-(C101-Pad1)")
		(layer "F.Cu")
		(name "$teardrop_padvia$")
		(hatch none 0.1)
		(priority 30003)
		(attr
			(teardrop
				(type padvia)
			)
		)
		(connect_pads yes
			(clearance 0)
		)
		(min_thickness 0.0254)
		(filled_areas_thickness no)
		(fill yes
			(thermal_gap 0.5)
			(thermal_bridge_width 0.5)
			(island_removal_mode 1)
			(island_area_min 10)
		)
		(polygon
			(pts
				(xy 178.365279 72.016891) (xy 178.312202 71.956893) (xy 178.275773 71.9003) (xy 178.256044 71.851678)
				(xy 178.24785 71.805157) (xy 178.261446 71.718847) (xy 178.314895 71.628075) (xy 178.424362 71.516261)
				(xy 178.538516 71.420218) (xy 178.718779 71.26465) (xy 178.803007 71.177603) (xy 178.876749 71.082235)
				(xy 178.169293 70.609293) (xy 177.463251 71.082235) (xy 177.573813 71.248777) (xy 177.722852 71.470905)
				(xy 177.859317 71.654652) (xy 178.028799 71.849587) (xy 178.276891 72.105279)
			)
		)
	)
	(zone
		(net 699)
		(net_name "/USB-C console/FTDI_RX")
		(layer "F.Cu")
		(name "$teardrop_padvia$")
		(hatch none 0.1)
		(priority 31634)
		(attr
			(teardrop
				(type padvia)
			)
		)
		(connect_pads yes
			(clearance 0)
		)
		(min_thickness 0.0254)
		(filled_areas_thickness no)
		(fill yes
			(thermal_gap 0.5)
			(thermal_bridge_width 0.5)
			(island_removal_mode 1)
			(island_area_min 10)
		)
		(polygon
			(pts
				(xy 115.422499 73.445) (xy 115.416977 73.472072) (xy 115.398321 73.497611) (xy 115.371702 73.51378)
				(xy 115.332961 73.523399) (xy 115.304999 73.525) (xy 115.484999 73.926) (xy 115.664999 73.525) (xy 115.619499 73.520387)
				(xy 115.586531 73.5081) (xy 115.552155 73.469945) (xy 115.547499 73.445)
			)
		)
	)
	(zone
		(net 146)
		(net_name "/2xUSB3.0+RJ45/DA+")
		(layer "F.Cu")
		(name "$teardrop_padvia$")
		(hatch none 0.1)
		(priority 31159)
		(attr
			(teardrop
				(type padvia)
			)
		)
		(connect_pads yes
			(clearance 0)
		)
		(min_thickness 0.0254)
		(filled_areas_thickness no)
		(fill yes
			(thermal_gap 0.5)
			(thermal_bridge_width 0.5)
			(island_removal_mode 1)
			(island_area_min 10)
		)
		(polygon
			(pts
				(xy 125.867073 113.553139) (xy 125.912063 113.608172) (xy 125.94717 113.685302) (xy 125.955193 113.734101)
				(xy 125.9525 113.788424) (xy 126.290707 113.770707) (xy 126.326943 113.5325) (xy 126.239355 113.536626)
				(xy 126.161899 113.530762) (xy 126.095663 113.516263) (xy 126.039618 113.494147) (xy 125.973139 113.447073)
			)
		)
	)
	(zone
		(net 665)
		(net_name "/2xSFP+/KR to SFI #1/KR_R.RX-")
		(layer "F.Cu")
		(name "$teardrop_padvia$")
		(hatch none 0.1)
		(priority 31949)
		(attr
			(teardrop
				(type padvia)
			)
		)
		(connect_pads yes
			(clearance 0)
		)
		(min_thickness 0.0254)
		(filled_areas_thickness no)
		(fill yes
			(thermal_gap 0.5)
			(thermal_bridge_width 0.5)
			(island_removal_mode 1)
			(island_area_min 10)
		)
		(polygon
			(pts
				(xy 152.68 146.717279) (xy 152.668264 146.740315) (xy 152.645802 146.756014) (xy 152.569443 146.765137)
				(xy 152.511231 146.76) (xy 152.57 146.991) (xy 152.77 147.018536) (xy 152.774353 146.919743) (xy 152.815938 146.786651)
				(xy 152.84 146.717279)
			)
		)
	)
	(zone
		(net 1)
		(net_name "GND")
		(layer "F.Cu")
		(name "$teardrop_padvia$")
		(hatch none 0.1)
		(priority 31254)
		(attr
			(teardrop
				(type padvia)
			)
		)
		(connect_pads yes
			(clearance 0)
		)
		(min_thickness 0.0254)
		(filled_areas_thickness no)
		(fill yes
			(thermal_gap 0.5)
			(thermal_bridge_width 0.5)
			(island_removal_mode 1)
			(island_area_min 10)
		)
		(polygon
			(pts
				(xy 230.909323 164.73) (xy 230.987235 164.734713) (xy 231.04602 164.7477) (xy 231.137051 164.789802)
				(xy 231.222222 164.8325) (xy 231.311 164.63) (xy 231.222222 164.4275) (xy 231.13705 164.470199)
				(xy 231.044217 164.512867) (xy 230.986078 164.525444) (xy 230.909323 164.53)
			)
		)
	)
	(zone
		(net 1)
		(net_name "GND")
		(layer "F.Cu")
		(name "$teardrop_padvia$")
		(hatch none 0.1)
		(priority 30499)
		(attr
			(teardrop
				(type padvia)
			)
		)
		(connect_pads yes
			(clearance 0)
		)
		(min_thickness 0.0254)
		(filled_areas_thickness no)
		(fill yes
			(thermal_gap 0.5)
			(thermal_bridge_width 0.5)
			(island_removal_mode 1)
			(island_area_min 10)
		)
		(polygon
			(pts
				(xy 201.218944 160.389444) (xy 201.296761 160.339591) (xy 201.418204 160.311471) (xy 201.492476 160.310257)
				(xy 201.572762 160.319508) (xy 201.575474 160.32) (xy 201.520707 159.999293) (xy 201.225 159.919526)
				(xy 201.228538 160.005966) (xy 201.222454 160.085599) (xy 201.207419 160.158138) (xy 201.184456 160.220952)
				(xy 201.130556 160.301056)
			)
		)
	)
	(zone
		(net 1)
		(net_name "GND")
		(layer "F.Cu")
		(name "$teardrop_padvia$")
		(hatch none 0.1)
		(priority 30226)
		(attr
			(teardrop
				(type padvia)
			)
		)
		(connect_pads yes
			(clearance 0)
		)
		(min_thickness 0.0254)
		(filled_areas_thickness no)
		(fill yes
			(thermal_gap 0.5)
			(thermal_bridge_width 0.5)
			(island_removal_mode 1)
			(island_area_min 10)
		)
		(polygon
			(pts
				(xy 120.537 74.943) (xy 120.54535 74.973608) (xy 120.555961 75.026593) (xy 120.542956 75.049725)
				(xy 120.507 75.066191) (xy 120.687 75.759) (xy 120.867 75.066191) (xy 120.837041 75.054257) (xy 120.821728 75.037936)
				(xy 120.819892 75.000262) (xy 120.82865 74.973608) (xy 120.837 74.943)
			)
		)
	)
	(zone
		(net 725)
		(net_name "/2xSFP+/KR to SFI #1/TCK")
		(layer "F.Cu")
		(name "$teardrop_padvia$")
		(hatch none 0.1)
		(priority 30113)
		(attr
			(teardrop
				(type padvia)
			)
		)
		(connect_pads yes
			(clearance 0)
		)
		(min_thickness 0.0254)
		(filled_areas_thickness no)
		(fill yes
			(thermal_gap 0.5)
			(thermal_bridge_width 0.5)
			(island_removal_mode 1)
			(island_area_min 10)
		)
		(polygon
			(pts
				(xy 152.5125 130.227794) (xy 152.517315 130.145733) (xy 152.531019 130.080388) (xy 152.577576 129.98712)
				(xy 152.645787 129.908657) (xy 152.701942 129.847158) (xy 152.761801 129.768339) (xy 152.45 129.559)
				(xy 152.138199 129.768339) (xy 152.235219 129.888517) (xy 152.254214 129.908658) (xy 152.307366 129.967541)
				(xy 152.349591 130.031624) (xy 152.377449 130.114008) (xy 152.3875 130.227794)
			)
		)
	)
	(zone
		(net 73)
		(net_name "+3V3_AON")
		(layer "F.Cu")
		(name "$teardrop_padvia$")
		(hatch none 0.1)
		(priority 30448)
		(attr
			(teardrop
				(type padvia)
			)
		)
		(connect_pads yes
			(clearance 0)
		)
		(min_thickness 0.0254)
		(filled_areas_thickness no)
		(fill yes
			(thermal_gap 0.5)
			(thermal_bridge_width 0.5)
			(island_removal_mode 1)
			(island_area_min 10)
		)
		(polygon
			(pts
				(xy 237.671833 153.243445) (xy 237.618534 153.162327) (xy 237.584822 153.035292) (xy 237.579449 152.954734)
				(xy 237.583835 152.866937) (xy 237.585 152.856445) (xy 237.289293 152.930292) (xy 237.22732 153.250999)
				(xy 237.377224 153.247371) (xy 237.445099 153.259569) (xy 237.504215 153.279793) (xy 237.583445 153.331833)
			)
		)
	)
	(zone
		(net 365)
		(net_name "/Com Express 7 MGMT/PWR_OK")
		(layer "F.Cu")
		(name "$teardrop_padvia$")
		(hatch none 0.1)
		(priority 30670)
		(attr
			(teardrop
				(type padvia)
			)
		)
		(connect_pads yes
			(clearance 0)
		)
		(min_thickness 0.0254)
		(filled_areas_thickness no)
		(fill yes
			(thermal_gap 0.5)
			(thermal_bridge_width 0.5)
			(island_removal_mode 1)
			(island_area_min 10)
		)
		(polygon
			(pts
				(xy 187.5875 164.07) (xy 187.598438 164.031177) (xy 187.620195 164.016067) (xy 187.66 164.01) (xy 187.525 163.134)
				(xy 187.39 164.01) (xy 187.425281 164.014517) (xy 187.446797 164.026138) (xy 187.461995 164.058961)
				(xy 187.4625 164.07)
			)
		)
	)
	(zone
		(net 314)
		(net_name "/2xUSB3.0+RJ45/FLG_1")
		(layer "F.Cu")
		(name "$teardrop_padvia$")
		(hatch none 0.1)
		(priority 31316)
		(attr
			(teardrop
				(type padvia)
			)
		)
		(connect_pads yes
			(clearance 0)
		)
		(min_thickness 0.0254)
		(filled_areas_thickness no)
		(fill yes
			(thermal_gap 0.5)
			(thermal_bridge_width 0.5)
			(island_removal_mode 1)
			(island_area_min 10)
		)
		(polygon
			(pts
				(xy 122.943 92.9375) (xy 122.888557 92.917767) (xy 122.841051 92.855422) (xy 122.824126 92.80664)
				(xy 122.814728 92.747044) (xy 122.813772 92.731054) (xy 122.529 92.96) (xy 122.781798 93.236798)
				(xy 122.795832 93.186069) (xy 122.816581 93.14426) (xy 122.874863 93.0843) (xy 122.909179 93.068036)
				(xy 122.942276 93.062503) (xy 122.943 93.0625)
			)
		)
	)
	(zone
		(net 721)
		(net_name "Net-(U43C-REFCLK1-)")
		(layer "F.Cu")
		(name "$teardrop_padvia$")
		(hatch none 0.1)
		(priority 30145)
		(attr
			(teardrop
				(type padvia)
			)
		)
		(connect_pads yes
			(clearance 0)
		)
		(min_thickness 0.0254)
		(filled_areas_thickness no)
		(fill yes
			(thermal_gap 0.5)
			(thermal_bridge_width 0.5)
			(island_removal_mode 1)
			(island_area_min 10)
		)
		(polygon
			(pts
				(xy 144.584195 130.214193) (xy 144.790976 129.995721) (xy 144.954486 129.775653) (xy 144.650707 129.559293)
				(xy 144.338199 129.768339) (xy 144.415988 129.85862) (xy 144.440959 129.882956) (xy 144.497988 129.941072)
				(xy 144.53558 129.998187) (xy 144.542663 130.027649) (xy 144.539575 130.058399) (xy 144.524546 130.090946)
				(xy 144.495807 130.125805)
			)
		)
	)
	(zone
		(net 691)
		(net_name "/2xUSB3.0+RJ45/DB_FL+")
		(layer "F.Cu")
		(name "$teardrop_padvia$")
		(hatch none 0.1)
		(priority 31148)
		(attr
			(teardrop
				(type padvia)
			)
		)
		(connect_pads yes
			(clearance 0)
		)
		(min_thickness 0.0254)
		(filled_areas_thickness no)
		(fill yes
			(thermal_gap 0.5)
			(thermal_bridge_width 0.5)
			(island_removal_mode 1)
			(island_area_min 10)
		)
		(polygon
			(pts
				(xy 128.526861 105.637073) (xy 128.442002 105.692661) (xy 128.383721 105.71191) (xy 128.315724 105.723528)
				(xy 128.173057 105.7225) (xy 128.209293 105.960707) (xy 128.5475 105.978424) (xy 128.5504 105.885052)
				(xy 128.58624 105.800804) (xy 128.632927 105.743139)
			)
		)
	)
	(zone
		(net 1)
		(net_name "GND")
		(layer "F.Cu")
		(name "$teardrop_padvia$")
		(hatch none 0.1)
		(priority 30216)
		(attr
			(teardrop
				(type padvia)
			)
		)
		(connect_pads yes
			(clearance 0)
		)
		(min_thickness 0.0254)
		(filled_areas_thickness no)
		(fill yes
			(thermal_gap 0.5)
			(thermal_bridge_width 0.5)
			(island_removal_mode 1)
			(island_area_min 10)
		)
		(polygon
			(pts
				(xy 143.34 147.925) (xy 143.33165 147.894391) (xy 143.321039 147.841406) (xy 143.334044 147.818274)
				(xy 143.37 147.801808) (xy 143.19 147.109) (xy 143.01 147.801808) (xy 143.039959 147.813742) (xy 143.055272 147.830064)
				(xy 143.057108 147.867738) (xy 143.04835 147.894391) (xy 143.04 147.925)
			)
		)
	)
	(zone
		(net 288)
		(net_name "/2xUSB3.0+RJ45/~{GBE0_LINK_1000}")
		(layer "F.Cu")
		(name "$teardrop_padvia$")
		(hatch none 0.1)
		(priority 30644)
		(attr
			(teardrop
				(type padvia)
			)
		)
		(connect_pads yes
			(clearance 0)
		)
		(min_thickness 0.0254)
		(filled_areas_thickness no)
		(fill yes
			(thermal_gap 0.5)
			(thermal_bridge_width 0.5)
			(island_removal_mode 1)
			(island_area_min 10)
		)
		(polygon
			(pts
				(xy 178.0875 169.62) (xy 178.098438 169.581177) (xy 178.120195 169.566067) (xy 178.16 169.56) (xy 178.025 168.684)
				(xy 177.89 169.56) (xy 177.925281 169.564517) (xy 177.946797 169.576138) (xy 177.961995 169.608961)
				(xy 177.9625 169.62)
			)
		)
	)
	(zone
		(net 1)
		(net_name "GND")
		(layer "F.Cu")
		(name "$teardrop_padvia$")
		(hatch none 0.1)
		(priority 30582)
		(attr
			(teardrop
				(type padvia)
			)
		)
		(connect_pads yes
			(clearance 0)
		)
		(min_thickness 0.0254)
		(filled_areas_thickness no)
		(fill yes
			(thermal_gap 0.5)
			(thermal_bridge_width 0.5)
			(island_removal_mode 1)
			(island_area_min 10)
		)
		(polygon
			(pts
				(xy 199.625 152.07) (xy 199.621667 152.055514) (xy 199.61881 152.02539) (xy 199.630964 152.014349)
				(xy 199.66 152.01) (xy 199.525 151.134) (xy 199.39 152.01) (xy 199.419334 152.014475) (xy 199.431358 152.025801)
				(xy 199.428333 152.055514) (xy 199.425 152.07)
			)
		)
	)
	(zone
		(net 1)
		(net_name "GND")
		(layer "F.Cu")
		(name "$teardrop_padvia$")
		(hatch none 0.1)
		(priority 31245)
		(attr
			(teardrop
				(type padvia)
			)
		)
		(connect_pads yes
			(clearance 0)
		)
		(min_thickness 0.0254)
		(filled_areas_thickness no)
		(fill yes
			(thermal_gap 0.5)
			(thermal_bridge_width 0.5)
			(island_removal_mode 1)
			(island_area_min 10)
		)
		(polygon
			(pts
				(xy 199.849 82.38716) (xy 199.844288 82.464016) (xy 199.831301 82.522101) (xy 199.788179 82.613422)
				(xy 199.744471 82.698655) (xy 199.94639 82.788837) (xy 200.149462 82.70144) (xy 200.107786 82.616394)
				(xy 200.06581 82.522791) (xy 200.053467 82.464319) (xy 200.049 82.38716)
			)
		)
	)
	(zone
		(net 672)
		(net_name "/2xSFP+/KR to SFI #2/MDC")
		(layer "F.Cu")
		(name "$teardrop_padvia$")
		(hatch none 0.1)
		(priority 31068)
		(attr
			(teardrop
				(type padvia)
			)
		)
		(connect_pads yes
			(clearance 0)
		)
		(min_thickness 0.0254)
		(filled_areas_thickness no)
		(fill yes
			(thermal_gap 0.5)
			(thermal_bridge_width 0.5)
			(island_removal_mode 1)
			(island_area_min 10)
		)
		(polygon
			(pts
				(xy 125.103 144.9875) (xy 125.043588 144.967727) (xy 124.987503 144.904453) (xy 124.965801 144.855828)
				(xy 124.951127 144.796468) (xy 124.949347 144.7845) (xy 124.689 145.05) (xy 124.949347 145.3155)
				(xy 124.962197 145.255361) (xy 124.982131 145.205477) (xy 125.008056 145.165358) (xy 125.037876 145.136345)
				(xy 125.069294 145.118854) (xy 125.101105 145.112521) (xy 125.103 145.1125)
			)
		)
	)
	(zone
		(net 929)
		(net_name "/2xSFP+/SFP1_LEDG")
		(layer "F.Cu")
		(name "$teardrop_padvia$")
		(hatch none 0.1)
		(priority 31220)
		(attr
			(teardrop
				(type padvia)
			)
		)
		(connect_pads yes
			(clearance 0)
		)
		(min_thickness 0.0254)
		(filled_areas_thickness no)
		(fill yes
			(thermal_gap 0.5)
			(thermal_bridge_width 0.5)
			(island_removal_mode 1)
			(island_area_min 10)
		)
		(polygon
			(pts
				(xy 154.876629 163.498241) (xy 154.878828 163.475271) (xy 154.890855 163.454857) (xy 154.947787 163.418682)
				(xy 155.070798 163.386798) (xy 154.818293 163.109293) (xy 154.567202 163.386798) (xy 154.661292 163.42102)
				(xy 154.73977 163.486781) (xy 154.768184 163.528159) (xy 154.784853 163.56911) (xy 154.788241 163.586629)
			)
		)
	)
	(zone
		(net 21)
		(net_name "/M.2 key E/PCIE_{REF}.CK-")
		(layer "F.Cu")
		(name "$teardrop_padvia$")
		(hatch none 0.1)
		(priority 30365)
		(attr
			(teardrop
				(type padvia)
			)
		)
		(connect_pads yes
			(clearance 0)
		)
		(min_thickness 0.0254)
		(filled_areas_thickness no)
		(fill yes
			(thermal_gap 0.5)
			(thermal_bridge_width 0.5)
			(island_removal_mode 1)
			(island_area_min 10)
		)
		(polygon
			(pts
				(xy 154.4085 82.514) (xy 154.394331 82.517024) (xy 154.363993 82.519052) (xy 154.352878 82.506062)
				(xy 154.3485 82.47572) (xy 153.5725 82.5595) (xy 153.793966 82.7095) (xy 154.007619 82.690152) (xy 154.252972 82.704897)
				(xy 154.4085 82.716)
			)
		)
	)
	(zone
		(net 1)
		(net_name "GND")
		(layer "F.Cu")
		(name "$teardrop_padvia$")
		(hatch none 0.1)
		(priority 30475)
		(attr
			(teardrop
				(type padvia)
			)
		)
		(connect_pads yes
			(clearance 0)
		)
		(min_thickness 0.0254)
		(filled_areas_thickness no)
		(fill yes
			(thermal_gap 0.5)
			(thermal_bridge_width 0.5)
			(island_removal_mode 1)
			(island_area_min 10)
		)
		(polygon
			(pts
				(xy 253.25 165.092) (xy 253.250338 165.10887) (xy 253.249759 165.153826) (xy 253.237941 165.201169)
				(xy 253.203362 165.243573) (xy 253.1345 165.273708) (xy 253.4 165.531) (xy 253.6655 165.273708)
				(xy 253.620731 165.258151) (xy 253.589115 165.237435) (xy 253.556381 165.186299) (xy 253.549662 165.10887)
				(xy 253.55 165.092)
			)
		)
	)
	(zone
		(net 976)
		(net_name "/PCIe redriver/RX_EQ2")
		(layer "F.Cu")
		(name "$teardrop_padvia$")
		(hatch none 0.1)
		(priority 31138)
		(attr
			(teardrop
				(type padvia)
			)
		)
		(connect_pads yes
			(clearance 0)
		)
		(min_thickness 0.0254)
		(filled_areas_thickness no)
		(fill yes
			(thermal_gap 0.5)
			(thermal_bridge_width 0.5)
			(island_removal_mode 1)
			(island_area_min 10)
		)
		(polygon
			(pts
				(xy 192.462748 130.87564) (xy 192.51874 130.847611) (xy 192.603139 130.852694) (xy 192.652868 130.871732)
				(xy 192.705217 130.90333) (xy 192.714939 130.910534) (xy 192.711296 130.538704) (xy 192.339465 130.53506)
				(xy 192.372904 130.58667) (xy 192.394082 130.636039) (xy 192.404119 130.68274) (xy 192.403549 130.724341)
				(xy 192.393701 130.758925) (xy 192.375686 130.785897) (xy 192.37436 130.787252)
			)
		)
	)
	(zone
		(net 948)
		(net_name "/2xSFP+/KR to SFI #1/BYP_TX-")
		(layer "F.Cu")
		(name "$teardrop_padvia$")
		(hatch none 0.1)
		(priority 31962)
		(attr
			(teardrop
				(type padvia)
			)
		)
		(connect_pads yes
			(clearance 0)
		)
		(min_thickness 0.0254)
		(filled_areas_thickness no)
		(fill yes
			(thermal_gap 0.5)
			(thermal_bridge_width 0.5)
			(island_removal_mode 1)
			(island_area_min 10)
		)
		(polygon
			(pts
				(xy 146.84 148.527721) (xy 146.815938 148.458348) (xy 146.779423 148.348401) (xy 146.769113 148.288313)
				(xy 146.77 148.226463) (xy 146.57 148.254) (xy 146.511231 148.485) (xy 146.592579 148.479702) (xy 146.644596 148.488493)
				(xy 146.666116 148.502345) (xy 146.678354 148.522403) (xy 146.68 148.527721)
			)
		)
	)
	(zone
		(net 897)
		(net_name "Net-(J2B-RS1)")
		(layer "F.Cu")
		(name "$teardrop_padvia$")
		(hatch none 0.1)
		(priority 30054)
		(attr
			(teardrop
				(type padvia)
			)
		)
		(connect_pads yes
			(clearance 0)
		)
		(min_thickness 0.0254)
		(filled_areas_thickness no)
		(fill yes
			(thermal_gap 0.5)
			(thermal_bridge_width 0.5)
			(island_removal_mode 1)
			(island_area_min 10)
		)
		(polygon
			(pts
				(xy 141.209947 159.7725) (xy 141.289662 159.772561) (xy 141.582352 159.767721) (xy 141.875805 159.731738)
				(xy 141.811 159.31) (xy 141.445244 159.088544) (xy 141.405484 159.18769) (xy 141.390718 159.315969)
				(xy 141.390185 159.385789) (xy 141.387631 159.487245) (xy 141.368064 159.570478) (xy 141.346593 159.602545)
				(xy 141.314498 159.626795) (xy 141.269658 159.642143) (xy 141.209947 159.6475)
			)
		)
	)
	(zone
		(net 324)
		(net_name "/Com Express 7 Interfaces/PCIe_{B2Ax4}.TX0+")
		(layer "F.Cu")
		(name "$teardrop_padvia$")
		(hatch none 0.1)
		(priority 30369)
		(attr
			(teardrop
				(type padvia)
			)
		)
		(connect_pads yes
			(clearance 0)
		)
		(min_thickness 0.0254)
		(filled_areas_thickness no)
		(fill yes
			(thermal_gap 0.5)
			(thermal_bridge_width 0.5)
			(island_removal_mode 1)
			(island_area_min 10)
		)
		(polygon
			(pts
				(xy 297.6535 73.2) (xy 297.656524 73.214169) (xy 297.658552 73.244507) (xy 297.645562 73.255622)
				(xy 297.61522 73.26) (xy 297.699 74.036) (xy 297.849 73.814533) (xy 297.829652 73.60088) (xy 297.844397 73.355527)
				(xy 297.8555 73.2)
			)
		)
	)
	(zone
		(net 1)
		(net_name "GND")
		(layer "F.Cu")
		(name "$teardrop_padvia$")
		(hatch none 0.1)
		(priority 30324)
		(attr
			(teardrop
				(type padvia)
			)
		)
		(connect_pads yes
			(clearance 0)
		)
		(min_thickness 0.0254)
		(filled_areas_thickness no)
		(fill yes
			(thermal_gap 0.5)
			(thermal_bridge_width 0.5)
			(island_removal_mode 1)
			(island_area_min 10)
		)
		(polygon
			(pts
				(xy 253.864 128.194248) (xy 253.890697 128.199263) (xy 253.916352 128.214369) (xy 253.93964 128.240246)
				(xy 253.95822 128.276797) (xy 253.974 128.375324) (xy 254.475 128.109) (xy 253.974 127.87998) (xy 253.969292 127.9399)
				(xy 253.956338 127.988485) (xy 253.937041 128.025492) (xy 253.913058 128.051262) (xy 253.864 128.069248)
			)
		)
	)
	(zone
		(net 75)
		(net_name "Net-(U50-IN+)")
		(layer "F.Cu")
		(hatch edge 0.5)
		(priority 1)
		(connect_pads yes
			(clearance 0.15)
		)
		(min_thickness 0.25)
		(filled_areas_thickness no)
		(fill yes
			(thermal_gap 0.2)
			(thermal_bridge_width 0.5)
			(smoothing fillet)
			(radius 0.2)
		)
		(polygon
			(pts
				(xy 310.8005 89.6865) (xy 310.8005 93.2865) (xy 310.1755 93.9115) (xy 310.1755 94.6615) (xy 309.3505 95.4865)
				(xy 309.3505 97.8365) (xy 309.0505 98.1365) (xy 304.7505 98.1365) (xy 304.7505 95.471) (xy 306.014849 95.471)
				(xy 308.098433 93.348508) (xy 308.098822 90.588178) (xy 309.3005 89.3865) (xy 310.5005 89.3865)
			)
		)
	)
	(zone
		(net 78)
		(net_name "+1V8")
		(layer "F.Cu")
		(name "$teardrop_padvia$")
		(hatch none 0.1)
		(priority 30899)
		(attr
			(teardrop
				(type padvia)
			)
		)
		(connect_pads yes
			(clearance 0)
		)
		(min_thickness 0.0254)
		(filled_areas_thickness no)
		(fill yes
			(thermal_gap 0.5)
			(thermal_bridge_width 0.5)
			(island_removal_mode 1)
			(island_area_min 10)
		)
		(polygon
			(pts
				(xy 124.232 148.446426) (xy 124.227303 148.485683) (xy 124.214427 148.515461) (xy 124.169401 148.556726)
				(xy 124.136016 148.574756) (xy 124.077708 148.610207) (xy 124.22 148.781) (xy 124.440677 148.789906)
				(xy 124.460763 148.70058) (xy 124.480511 148.656042) (xy 124.515492 148.568739) (xy 124.532 148.446426)
			)
		)
	)
	(zone
		(net 244)
		(net_name "/Com Express 7 Interfaces/PCIe_{B2Bx4}.RX2+")
		(layer "F.Cu")
		(name "$teardrop_padvia$")
		(hatch none 0.1)
		(priority 31411)
		(attr
			(teardrop
				(type padvia)
			)
		)
		(connect_pads yes
			(clearance 0)
		)
		(min_thickness 0.0254)
		(filled_areas_thickness no)
		(fill yes
			(thermal_gap 0.5)
			(thermal_bridge_width 0.5)
			(island_removal_mode 1)
			(island_area_min 10)
		)
		(polygon
			(pts
				(xy 191.632504 160.8065) (xy 191.794035 160.801105) (xy 191.878445 160.797554) (xy 191.98014 160.802177)
				(xy 192.001 160.5815) (xy 191.851147 160.418268) (xy 191.797007 160.486935) (xy 191.787115 160.503393)
				(xy 191.762615 160.542065) (xy 191.733109 160.574279) (xy 191.691953 160.596327) (xy 191.632504 160.6045)
			)
		)
	)
	(zone
		(net 192)
		(net_name "/OCuLink/PCIe_{REF0}.CK+")
		(layer "F.Cu")
		(name "$teardrop_padvia$")
		(hatch none 0.1)
		(priority 30423)
		(attr
			(teardrop
				(type padvia)
			)
		)
		(connect_pads yes
			(clearance 0)
		)
		(min_thickness 0.0254)
		(filled_areas_thickness no)
		(fill yes
			(thermal_gap 0.5)
			(thermal_bridge_width 0.5)
			(island_removal_mode 1)
			(island_area_min 10)
		)
		(polygon
			(pts
				(xy 210.434479 130.2205) (xy 210.462061 130.243758) (xy 210.482724 130.274997) (xy 210.505599 130.366916)
				(xy 210.505 130.523914) (xy 210.801 130.425) (xy 210.831754 130.105) (xy 210.716623 130.114439)
				(xy 210.588284 130.089667) (xy 210.456719 130.031792) (xy 210.434479 130.0185)
			)
		)
	)
	(zone
		(net 56)
		(net_name "/USB-C console/USB_D-")
		(layer "F.Cu")
		(name "$teardrop_padvia$")
		(hatch none 0.1)
		(priority 31328)
		(attr
			(teardrop
				(type padvia)
			)
		)
		(connect_pads yes
			(clearance 0)
		)
		(min_thickness 0.0254)
		(filled_areas_thickness no)
		(fill yes
			(thermal_gap 0.5)
			(thermal_bridge_width 0.5)
			(island_removal_mode 1)
			(island_area_min 10)
		)
		(polygon
			(pts
				(xy 102.6925 84.672) (xy 102.687657 84.658386) (xy 102.681467 84.634216) (xy 102.689804 84.625444)
				(xy 102.7125 84.622) (xy 102.6 83.8085) (xy 102.4875 84.622) (xy 102.512137 84.626419) (xy 102.518984 84.637354)
				(xy 102.512343 84.658386) (xy 102.5075 84.672)
			)
		)
	)
	(zone
		(net 661)
		(net_name "Net-(U43C-PRTAD4)")
		(layer "F.Cu")
		(name "$teardrop_padvia$")
		(hatch none 0.1)
		(priority 31464)
		(attr
			(teardrop
				(type padvia)
			)
		)
		(connect_pads yes
			(clearance 0)
		)
		(min_thickness 0.0254)
		(filled_areas_thickness no)
		(fill yes
			(thermal_gap 0.5)
			(thermal_bridge_width 0.5)
			(island_removal_mode 1)
			(island_area_min 10)
		)
		(polygon
			(pts
				(xy 144.982635 138.851023) (xy 145.053655 138.915544) (xy 145.112383 138.957066) (xy 145.183166 138.995115)
				(xy 145.311107 139.067867) (xy 145.450707 138.860707) (xy 145.311107 138.652133) (xy 145.233312 138.723429)
				(xy 145.194719 138.762477) (xy 145.156592 138.788485) (xy 145.116253 138.791767) (xy 145.071023 138.762635)
			)
		)
	)
	(zone
		(net 694)
		(net_name "/2xUSB3.0+RJ45/DC_FL-")
		(layer "F.Cu")
		(name "$teardrop_padvia$")
		(hatch none 0.1)
		(priority 31155)
		(attr
			(teardrop
				(type padvia)
			)
		)
		(connect_pads yes
			(clearance 0)
		)
		(min_thickness 0.0254)
		(filled_areas_thickness no)
		(fill yes
			(thermal_gap 0.5)
			(thermal_bridge_width 0.5)
			(island_removal_mode 1)
			(island_area_min 10)
		)
		(polygon
			(pts
				(xy 128.632927 109.176861) (xy 128.587939 109.121829) (xy 128.552832 109.044702) (xy 128.544807 108.995901)
				(xy 128.5475 108.941575) (xy 128.209293 108.959293) (xy 128.173057 109.1975) (xy 128.260646 109.193374)
				(xy 128.338104 109.199239) (xy 128.404339 109.213738) (xy 128.460384 109.235855) (xy 128.526861 109.282927)
			)
		)
	)
	(zone
		(net 1)
		(net_name "GND")
		(layer "F.Cu")
		(name "$teardrop_padvia$")
		(hatch none 0.1)
		(priority 30052)
		(attr
			(teardrop
				(type padvia)
			)
		)
		(connect_pads yes
			(clearance 0)
		)
		(min_thickness 0.0254)
		(filled_areas_thickness no)
		(fill yes
			(thermal_gap 0.5)
			(thermal_bridge_width 0.5)
			(island_removal_mode 1)
			(island_area_min 10)
		)
		(polygon
			(pts
				(xy 220.360208 159.22766) (xy 220.307108 159.277491) (xy 220.240968 159.327823) (xy 220.160864 159.370576)
				(xy 220.065872 159.397669) (xy 219.945303 159.4) (xy 219.999293 159.900707) (xy 220.4 159.980451)
				(xy 220.396537 159.886244) (xy 220.402584 159.80027) (xy 220.440269 159.646352) (xy 220.507863 159.51712)
				(xy 220.57234 159.439792)
			)
		)
	)
	(zone
		(net 2)
		(net_name "+3V3")
		(layer "F.Cu")
		(name "$teardrop_padvia$")
		(hatch none 0.1)
		(priority 31561)
		(attr
			(teardrop
				(type padvia)
			)
		)
		(connect_pads yes
			(clearance 0)
		)
		(min_thickness 0.0254)
		(filled_areas_thickness no)
		(fill yes
			(thermal_gap 0.5)
			(thermal_bridge_width 0.5)
			(island_removal_mode 1)
			(island_area_min 10)
		)
		(polygon
			(pts
				(xy 309.167 83.742) (xy 309.158751 83.719923) (xy 309.148017 83.681428) (xy 309.160982 83.667475)
				(xy 309.197 83.662) (xy 309.017 83.286) (xy 308.837 83.662) (xy 308.870735 83.66654) (xy 308.884928 83.678323)
				(xy 308.881446 83.706817) (xy 308.875249 83.719923) (xy 308.867 83.742)
			)
		)
	)
	(zone
		(net 52)
		(net_name "+5V")
		(layer "F.Cu")
		(hatch edge 0.5)
		(priority 35)
		(connect_pads yes
			(clearance 0.15)
		)
		(min_thickness 0.25)
		(filled_areas_thickness no)
		(fill yes
			(thermal_gap 0.5)
			(thermal_bridge_width 0.5)
			(smoothing fillet)
			(radius 0.2)
		)
		(polygon
			(pts
				(xy 117.5 84.66) (xy 117.5 86.36) (xy 119.65 86.36) (xy 119.65 84.659999)
			)
		)
	)
	(zone
		(net 164)
		(net_name "/2xSFP+/SDA0")
		(layer "F.Cu")
		(name "$teardrop_padvia$")
		(hatch none 0.1)
		(priority 31119)
		(attr
			(teardrop
				(type padvia)
			)
		)
		(connect_pads yes
			(clearance 0)
		)
		(min_thickness 0.0254)
		(filled_areas_thickness no)
		(fill yes
			(thermal_gap 0.5)
			(thermal_bridge_width 0.5)
			(island_removal_mode 1)
			(island_area_min 10)
		)
		(polygon
			(pts
				(xy 177.507 143.062498) (xy 177.566412 143.082271) (xy 177.622497 143.145545) (xy 177.644199 143.19417)
				(xy 177.658873 143.253529) (xy 177.660653 143.265498) (xy 177.921 142.999998) (xy 177.660653 142.734498)
				(xy 177.647804 142.794636) (xy 177.62787 142.84452) (xy 177.601945 142.884639) (xy 177.572125 142.913652)
				(xy 177.540707 142.931144) (xy 177.508896 142.937477) (xy 177.507 142.937498)
			)
		)
	)
	(zone
		(net 328)
		(net_name "/Com Express 7 Interfaces/PCIe_{B2Ax4}.TX2+")
		(layer "F.Cu")
		(name "$teardrop_padvia$")
		(hatch none 0.1)
		(priority 30519)
		(attr
			(teardrop
				(type padvia)
			)
		)
		(connect_pads yes
			(clearance 0)
		)
		(min_thickness 0.0254)
		(filled_areas_thickness no)
		(fill yes
			(thermal_gap 0.5)
			(thermal_bridge_width 0.5)
			(island_removal_mode 1)
			(island_area_min 10)
		)
		(polygon
			(pts
				(xy 213.924 167.75) (xy 213.927537 167.764678) (xy 213.930808 167.794685) (xy 213.918857 167.805673)
				(xy 213.89 167.81) (xy 214.025 168.686) (xy 214.16 167.81) (xy 214.130796 167.805525) (xy 214.119003 167.794203)
				(xy 214.122463 167.764678) (xy 214.126 167.75)
			)
		)
	)
	(zone
		(net 194)
		(net_name "/OCuLink/PCIe_{x4}.RX2+")
		(layer "F.Cu")
		(name "$teardrop_padvia$")
		(hatch none 0.1)
		(priority 32071)
		(attr
			(teardrop
				(type padvia)
			)
		)
		(connect_pads yes
			(clearance 0)
		)
		(min_thickness 0.0254)
		(filled_areas_thickness no)
		(fill yes
			(thermal_gap 0.5)
			(thermal_bridge_width 0.5)
			(island_removal_mode 1)
			(island_area_min 10)
		)
		(polygon
			(pts
				(xy 108.499 151.488) (xy 108.506198 151.508648) (xy 108.515792 151.540984) (xy 108.508965 151.555007)
				(xy 108.4875 151.564995) (xy 108.6 151.814) (xy 108.7125 151.564995) (xy 108.691324 151.555271)
				(xy 108.684269 151.541643) (xy 108.693802 151.508648) (xy 108.701 151.488)
			)
		)
	)
	(zone
		(net 626)
		(net_name "/PCIe redriver/TX_FG0")
		(layer "F.Cu")
		(name "$teardrop_padvia$")
		(hatch none 0.1)
		(priority 31579)
		(attr
			(teardrop
				(type padvia)
			)
		)
		(connect_pads yes
			(clearance 0)
		)
		(min_thickness 0.0254)
		(filled_areas_thickness no)
		(fill yes
			(thermal_gap 0.5)
			(thermal_bridge_width 0.5)
			(island_removal_mode 1)
			(island_area_min 10)
		)
		(polygon
			(pts
				(xy 113.500852 150.9025) (xy 113.577997 150.907144) (xy 113.636104 150.919655) (xy 113.717126 150.953974)
				(xy 113.83477 151.002254) (xy 113.9 150.79) (xy 113.773997 150.602919) (xy 113.698074 150.670724)
				(xy 113.683331 150.687582) (xy 113.615241 150.751108) (xy 113.567467 150.770413) (xy 113.500852 150.7775)
			)
		)
	)
	(zone
		(net 50)
		(net_name "Net-(C12-Pad2)")
		(layer "F.Cu")
		(name "$teardrop_padvia$")
		(hatch none 0.1)
		(priority 31454)
		(attr
			(teardrop
				(type padvia)
			)
		)
		(connect_pads yes
			(clearance 0)
		)
		(min_thickness 0.0254)
		(filled_areas_thickness no)
		(fill yes
			(thermal_gap 0.5)
			(thermal_bridge_width 0.5)
			(island_removal_mode 1)
			(island_area_min 10)
		)
		(polygon
			(pts
				(xy 137.422562 105.4) (xy 137.498596 105.399656) (xy 137.625178 105.401593) (xy 137.756105 105.420677)
				(xy 137.801 105.2) (xy 137.660146 105.027769) (xy 137.590204 105.105684) (xy 137.528889 105.171974)
				(xy 137.484702 105.192438) (xy 137.422562 105.2)
			)
		)
	)
	(zone
		(net 555)
		(net_name "/2xUSB3.0+RJ45/EN_1B")
		(layer "F.Cu")
		(name "$teardrop_padvia$")
		(hatch none 0.1)
		(priority 30078)
		(attr
			(teardrop
				(type padvia)
			)
		)
		(connect_pads yes
			(clearance 0)
		)
		(min_thickness 0.0254)
		(filled_areas_thickness no)
		(fill yes
			(thermal_gap 0.5)
			(thermal_bridge_width 0.5)
			(island_removal_mode 1)
			(island_area_min 10)
		)
		(polygon
			(pts
				(xy 118.939 87.7515) (xy 118.883736 87.732104) (xy 118.834452 87.670761) (xy 118.802899 87.562049)
				(xy 118.799 87.499) (xy 118.198 87.814) (xy 118.799 88.129) (xy 118.803756 88.059663) (xy 118.817044 88.000293)
				(xy 118.837444 87.951557) (xy 118.863462 87.914336) (xy 118.891726 87.89052) (xy 118.922426 87.878176)
				(xy 118.939 87.8765)
			)
		)
	)
	(zone
		(net 534)
		(net_name "Net-(Q1-D)")
		(layer "F.Cu")
		(name "$teardrop_padvia$")
		(hatch none 0.1)
		(priority 32002)
		(attr
			(teardrop
				(type padvia)
			)
		)
		(connect_pads yes
			(clearance 0)
		)
		(min_thickness 0.0254)
		(filled_areas_thickness no)
		(fill yes
			(thermal_gap 0.5)
			(thermal_bridge_width 0.5)
			(island_removal_mode 1)
			(island_area_min 10)
		)
		(polygon
			(pts
				(xy 307.47 141.0135) (xy 307.47007 141.019725) (xy 307.469124 141.044002) (xy 307.460097 141.068307)
				(xy 307.434812 141.087014) (xy 307.385096 141.0945) (xy 307.561 141.298) (xy 307.749779 141.0945)
				(xy 307.710655 141.089933) (xy 307.686822 141.077965) (xy 307.670323 141.044246) (xy 307.669842 141.021439)
				(xy 307.67 141.0135)
			)
		)
	)
	(zone
		(net 93)
		(net_name "/Com Express 7 Interfaces/PCIe_{B2Ax4}.RX3+")
		(layer "F.Cu")
		(name "$teardrop_padvia$")
		(hatch none 0.1)
		(priority 31342)
		(attr
			(teardrop
				(type padvia)
			)
		)
		(connect_pads yes
			(clearance 0)
		)
		(min_thickness 0.0254)
		(filled_areas_thickness no)
		(fill yes
			(thermal_gap 0.5)
			(thermal_bridge_width 0.5)
			(island_removal_mode 1)
			(island_area_min 10)
		)
		(polygon
			(pts
				(xy 287.152 75.019852) (xy 287.147265 75.066638) (xy 287.134121 75.10209) (xy 287.089113 75.150287)
				(xy 287.050893 75.174463) (xy 287.007726 75.201832) (xy 286.965768 75.238495) (xy 287.129 75.388348)
				(xy 287.349677 75.367488) (xy 287.345048 75.266817) (xy 287.34848 75.18345) (xy 287.348605 75.181383)
				(xy 287.354 75.019852)
			)
		)
	)
	(zone
		(net 701)
		(net_name "/USB-C console/FTDI_CBUS0")
		(layer "F.Cu")
		(name "$teardrop_padvia$")
		(hatch none 0.1)
		(priority 31631)
		(attr
			(teardrop
				(type padvia)
			)
		)
		(connect_pads yes
			(clearance 0)
		)
		(min_thickness 0.0254)
		(filled_areas_thickness no)
		(fill yes
			(thermal_gap 0.5)
			(thermal_bridge_width 0.5)
			(island_removal_mode 1)
			(island_area_min 10)
		)
		(polygon
			(pts
				(xy 116.197499 78.205) (xy 116.203021 78.177928) (xy 116.221677 78.152389) (xy 116.248296 78.13622)
				(xy 116.287037 78.126601) (xy 116.314999 78.125) (xy 116.134999 77.724) (xy 115.954999 78.125) (xy 116.000499 78.129613)
				(xy 116.033467 78.1419) (xy 116.067843 78.180055) (xy 116.072499 78.205)
			)
		)
	)
	(zone
		(net 740)
		(net_name "Net-(U45C-REFCLK1+)")
		(layer "F.Cu")
		(name "$teardrop_padvia$")
		(hatch none 0.1)
		(priority 30105)
		(attr
			(teardrop
				(type padvia)
			)
		)
		(connect_pads yes
			(clearance 0)
		)
		(min_thickness 0.0254)
		(filled_areas_thickness no)
		(fill yes
			(thermal_gap 0.5)
			(thermal_bridge_width 0.5)
			(island_removal_mode 1)
			(island_area_min 10)
		)
		(polygon
			(pts
				(xy 127.2025 129.377794) (xy 127.207315 129.295733) (xy 127.221019 129.230388) (xy 127.267576 129.13712)
				(xy 127.335787 129.058657) (xy 127.391942 128.997158) (xy 127.451801 128.918339) (xy 127.14 128.709)
				(xy 126.828199 128.918339) (xy 126.925219 129.038517) (xy 126.944214 129.058658) (xy 126.997366 129.117541)
				(xy 127.039591 129.181624) (xy 127.067449 129.264008) (xy 127.0775 129.377794)
			)
		)
	)
	(zone
		(net 73)
		(net_name "+3V3_AON")
		(layer "F.Cu")
		(name "$teardrop_padvia$")
		(hatch none 0.1)
		(priority 31851)
		(attr
			(teardrop
				(type padvia)
			)
		)
		(connect_pads yes
			(clearance 0)
		)
		(min_thickness 0.0254)
		(filled_areas_thickness no)
		(fill yes
			(thermal_gap 0.5)
			(thermal_bridge_width 0.5)
			(island_removal_mode 1)
			(island_area_min 10)
		)
		(polygon
			(pts
				(xy 247.039127 132.512485) (xy 246.986618 132.558181) (xy 246.940623 132.584768) (xy 246.854174 132.605152)
				(xy 246.838841 132.606988) (xy 246.756105 132.619323) (xy 246.799293 132.840707) (xy 247.020677 132.883895)
				(xy 247.033011 132.80116) (xy 247.053349 132.703881) (xy 247.080057 132.655841) (xy 247.127515 132.600873)
			)
		)
	)
	(zone
		(net 696)
		(net_name "/2xUSB3.0+RJ45/DD_FL-")
		(layer "F.Cu")
		(name "$teardrop_padvia$")
		(hatch none 0.1)
		(priority 31157)
		(attr
			(teardrop
				(type padvia)
			)
		)
		(connect_pads yes
			(clearance 0)
		)
		(min_thickness 0.0254)
		(filled_areas_thickness no)
		(fill yes
			(thermal_gap 0.5)
			(thermal_bridge_width 0.5)
			(island_removal_mode 1)
			(island_area_min 10)
		)
		(polygon
			(pts
				(xy 128.632927 101.366861) (xy 128.587939 101.311829) (xy 128.552832 101.234702) (xy 128.544807 101.185901)
				(xy 128.5475 101.131575) (xy 128.209293 101.149293) (xy 128.173057 101.3875) (xy 128.260646 101.383374)
				(xy 128.338104 101.389239) (xy 128.404339 101.403738) (xy 128.460384 101.425855) (xy 128.526861 101.472927)
			)
		)
	)
	(zone
		(net 531)
		(net_name "/Com Express 7 Interfaces/SD_CD")
		(layer "F.Cu")
		(name "$teardrop_padvia$")
		(hatch none 0.1)
		(priority 32097)
		(attr
			(teardrop
				(type padvia)
			)
		)
		(connect_pads yes
			(clearance 0)
		)
		(min_thickness 0.0254)
		(filled_areas_thickness no)
		(fill yes
			(thermal_gap 0.5)
			(thermal_bridge_width 0.5)
			(island_removal_mode 1)
			(island_area_min 10)
		)
		(polygon
			(pts
				(xy 112.088 131.31) (xy 112.067551 131.316912) (xy 112.035114 131.3261) (xy 112.021033 131.319098)
				(xy 112.011005 131.2975) (xy 111.762 131.41) (xy 112.011005 131.5225) (xy 112.020757 131.501206)
				(xy 112.034425 131.493973) (xy 112.067551 131.503088) (xy 112.088 131.51)
			)
		)
	)
	(zone
		(net 271)
		(net_name "/M.2 key M #2/PCIE_{REF}.CK-")
		(layer "F.Cu")
		(name "$teardrop_padvia$")
		(hatch none 0.1)
		(priority 31423)
		(attr
			(teardrop
				(type padvia)
			)
		)
		(connect_pads yes
			(clearance 0)
		)
		(min_thickness 0.0254)
		(filled_areas_thickness no)
		(fill yes
			(thermal_gap 0.5)
			(thermal_bridge_width 0.5)
			(island_removal_mode 1)
			(island_area_min 10)
		)
		(polygon
			(pts
				(xy 260.9935 136.632504) (xy 260.998895 136.794035) (xy 261.002445 136.878446) (xy 260.997823 136.98014)
				(xy 261.2185 137.001) (xy 261.381731 136.851147) (xy 261.313062 136.797007) (xy 261.296608 136.787116)
				(xy 261.257935 136.762616) (xy 261.225721 136.733109) (xy 261.203673 136.691953) (xy 261.1955 136.632504)
			)
		)
	)
	(zone
		(net 1)
		(net_name "GND")
		(layer "F.Cu")
		(name "$teardrop_padvia$")
		(hatch none 0.1)
		(priority 30869)
		(attr
			(teardrop
				(type padvia)
			)
		)
		(connect_pads yes
			(clearance 0)
		)
		(min_thickness 0.0254)
		(filled_areas_thickness no)
		(fill yes
			(thermal_gap 0.5)
			(thermal_bridge_width 0.5)
			(island_removal_mode 1)
			(island_area_min 10)
		)
		(polygon
			(pts
				(xy 186.80861 78.045163) (xy 186.814382 78.004426) (xy 186.834786 77.962511) (xy 186.861961 77.93421)
				(xy 186.901507 77.910781) (xy 186.97411 77.89151) (xy 186.70861 77.631163) (xy 186.44311 77.89151)
				(xy 186.496252 77.903377) (xy 186.537291 77.921825) (xy 186.588992 77.972499) (xy 186.608328 78.036068)
				(xy 186.60861 78.045163)
			)
		)
	)
	(zone
		(net 139)
		(net_name "/Com Express 7 MGMT/SPI_POWER")
		(layer "F.Cu")
		(name "$teardrop_padvia$")
		(hatch none 0.1)
		(priority 30746)
		(attr
			(teardrop
				(type padvia)
			)
		)
		(connect_pads yes
			(clearance 0)
		)
		(min_thickness 0.0254)
		(filled_areas_thickness no)
		(fill yes
			(thermal_gap 0.5)
			(thermal_bridge_width 0.5)
			(island_removal_mode 1)
			(island_area_min 10)
		)
		(polygon
			(pts
				(xy 263.499323 162.681) (xy 263.58054 162.68039) (xy 263.711039 162.682741) (xy 263.827391 162.708783)
				(xy 263.901 162.5) (xy 263.79368 162.305179) (xy 263.66895 162.361941) (xy 263.596479 162.376222)
				(xy 263.499323 162.381)
			)
		)
	)
	(zone
		(net 273)
		(net_name "/M.2 key M #2/PCIE_{REF}.CK+")
		(layer "F.Cu")
		(name "$teardrop_padvia$")
		(hatch none 0.1)
		(priority 30370)
		(attr
			(teardrop
				(type padvia)
			)
		)
		(connect_pads yes
			(clearance 0)
		)
		(min_thickness 0.0254)
		(filled_areas_thickness no)
		(fill yes
			(thermal_gap 0.5)
			(thermal_bridge_width 0.5)
			(island_removal_mode 1)
			(island_area_min 10)
		)
		(polygon
			(pts
				(xy 299.744 74.87) (xy 299.740971 74.855826) (xy 299.738932 74.825491) (xy 299.751912 74.814377)
				(xy 299.782239 74.81) (xy 299.698 74.034) (xy 299.548 74.257561) (xy 299.567555 74.47053) (xy 299.552991 74.715428)
				(xy 299.542 74.87)
			)
		)
	)
	(zone
		(net 1)
		(net_name "GND")
		(layer "F.Cu")
		(name "$teardrop_padvia$")
		(hatch none 0.1)
		(priority 30548)
		(attr
			(teardrop
				(type padvia)
			)
		)
		(connect_pads yes
			(clearance 0)
		)
		(min_thickness 0.0254)
		(filled_areas_thickness no)
		(fill yes
			(thermal_gap 0.5)
			(thermal_bridge_width 0.5)
			(island_removal_mode 1)
			(island_area_min 10)
		)
		(polygon
			(pts
				(xy 205.425 167.75) (xy 205.428333 167.764486) (xy 205.43119 167.79461) (xy 205.419036 167.805651)
				(xy 205.39 167.81) (xy 205.525 168.686) (xy 205.66 167.81) (xy 205.630666 167.805525) (xy 205.618642 167.794199)
				(xy 205.621667 167.764486) (xy 205.625 167.75)
			)
		)
	)
	(zone
		(net 531)
		(net_name "/Com Express 7 Interfaces/SD_CD")
		(layer "F.Cu")
		(name "$teardrop_padvia$")
		(hatch none 0.1)
		(priority 32096)
		(attr
			(teardrop
				(type padvia)
			)
		)
		(connect_pads yes
			(clearance 0)
		)
		(min_thickness 0.0254)
		(filled_areas_thickness no)
		(fill yes
			(thermal_gap 0.5)
			(thermal_bridge_width 0.5)
			(island_removal_mode 1)
			(island_area_min 10)
		)
		(polygon
			(pts
				(xy 112.86 131.31) (xy 112.839551 131.316912) (xy 112.807114 131.3261) (xy 112.793033 131.319098)
				(xy 112.783005 131.2975) (xy 112.534 131.41) (xy 112.783005 131.5225) (xy 112.792757 131.501206)
				(xy 112.806425 131.493973) (xy 112.839551 131.503088) (xy 112.86 131.51)
			)
		)
	)
	(zone
		(net 528)
		(net_name "/Backplane/~{PERST}")
		(layer "F.Cu")
		(name "$teardrop_padvia$")
		(hatch none 0.1)
		(priority 31895)
		(attr
			(teardrop
				(type padvia)
			)
		)
		(connect_pads yes
			(clearance 0)
		)
		(min_thickness 0.0254)
		(filled_areas_thickness no)
		(fill yes
			(thermal_gap 0.5)
			(thermal_bridge_width 0.5)
			(island_removal_mode 1)
			(island_area_min 10)
		)
		(polygon
			(pts
				(xy 308.6935 156.309323) (xy 308.688708 156.376284) (xy 308.675161 156.426084) (xy 308.629015 156.499112)
				(xy 308.617605 156.513044) (xy 308.562919 156.584997) (xy 308.75 156.711) (xy 308.937081 156.584997)
				(xy 308.892631 156.52346) (xy 308.838295 156.43719) (xy 308.823606 156.383281) (xy 308.8185 156.309323)
			)
		)
	)
	(zone
		(net 1)
		(net_name "GND")
		(layer "F.Cu")
		(name "$teardrop_padvia$")
		(hatch none 0.1)
		(priority 30588)
		(attr
			(teardrop
				(type padvia)
			)
		)
		(connect_pads yes
			(clearance 0)
		)
		(min_thickness 0.0254)
		(filled_areas_thickness no)
		(fill yes
			(thermal_gap 0.5)
			(thermal_bridge_width 0.5)
			(island_removal_mode 1)
			(island_area_min 10)
		)
		(polygon
			(pts
				(xy 186.125 157.62) (xy 186.121667 157.605514) (xy 186.11881 157.57539) (xy 186.130964 157.564349)
				(xy 186.16 157.56) (xy 186.025 156.684) (xy 185.89 157.56) (xy 185.919334 157.564475) (xy 185.931358 157.575801)
				(xy 185.928333 157.605514) (xy 185.925 157.62)
			)
		)
	)
	(zone
		(net 336)
		(net_name "/Com Express 7 Interfaces/PCIE_{REF}.CK+")
		(layer "F.Cu")
		(name "$teardrop_padvia$")
		(hatch none 0.1)
		(priority 31341)
		(attr
			(teardrop
				(type padvia)
			)
		)
		(connect_pads yes
			(clearance 0)
		)
		(min_thickness 0.0254)
		(filled_areas_thickness no)
		(fill yes
			(thermal_gap 0.5)
			(thermal_bridge_width 0.5)
			(island_removal_mode 1)
			(island_area_min 10)
		)
		(polygon
			(pts
				(xy 219.4795 169.632504) (xy 219.474765 169.67929) (xy 219.461621 169.714742) (xy 219.416613 169.762939)
				(xy 219.378393 169.787115) (xy 219.335226 169.814484) (xy 219.293268 169.851147) (xy 219.4565 170.001)
				(xy 219.677177 169.98014) (xy 219.672548 169.879469) (xy 219.67598 169.796102) (xy 219.676105 169.794035)
				(xy 219.6815 169.632504)
			)
		)
	)
	(zone
		(net 1)
		(net_name "GND")
		(layer "F.Cu")
		(name "$teardrop_padvia$")
		(hatch none 0.1)
		(priority 30956)
		(attr
			(teardrop
				(type padvia)
			)
		)
		(connect_pads yes
			(clearance 0)
		)
		(min_thickness 0.0254)
		(filled_areas_thickness no)
		(fill yes
			(thermal_gap 0.5)
			(thermal_bridge_width 0.5)
			(island_removal_mode 1)
			(island_area_min 10)
		)
		(polygon
			(pts
				(xy 113.4425 146.298) (xy 113.462469 146.235134) (xy 113.488921 146.203156) (xy 113.526332 146.174642)
				(xy 113.573527 146.152118) (xy 113.631167 146.136907) (xy 113.631798 146.136798) (xy 113.38 145.859)
				(xy 113.128202 146.136798) (xy 113.183635 146.151095) (xy 113.22952 146.172175) (xy 113.267201 146.19954)
				(xy 113.294434 146.230448) (xy 113.311472 146.263735) (xy 113.317489 146.296566) (xy 113.3175 146.298)
			)
		)
	)
	(zone
		(net 527)
		(net_name "/Backplane/GPIO")
		(layer "F.Cu")
		(name "$teardrop_padvia$")
		(hatch none 0.1)
		(priority 32112)
		(attr
			(teardrop
				(type padvia)
			)
		)
		(connect_pads yes
			(clearance 0)
		)
		(min_thickness 0.0254)
		(filled_areas_thickness no)
		(fill yes
			(thermal_gap 0.5)
			(thermal_bridge_width 0.5)
			(island_removal_mode 1)
			(island_area_min 10)
		)
		(polygon
			(pts
				(xy 314.81 165.0205) (xy 314.816322 165.020404) (xy 314.855825 165.025989) (xy 314.874047 165.040922)
				(xy 314.886995 165.0705) (xy 315.136 164.958) (xy 314.886995 164.8455) (xy 314.875879 164.872493)
				(xy 314.860352 164.887595) (xy 314.816322 164.895596) (xy 314.81 164.8955)
			)
		)
	)
	(zone
		(net 577)
		(net_name "Net-(U18-EN)")
		(layer "F.Cu")
		(name "$teardrop_padvia$")
		(hatch none 0.1)
		(priority 32131)
		(attr
			(teardrop
				(type padvia)
			)
		)
		(connect_pads yes
			(clearance 0)
		)
		(min_thickness 0.0254)
		(filled_areas_thickness no)
		(fill yes
			(thermal_gap 0.5)
			(thermal_bridge_width 0.5)
			(island_removal_mode 1)
			(island_area_min 10)
		)
		(polygon
			(pts
				(xy 309.97692 120.171499) (xy 309.994386 120.170024) (xy 310.035831 120.169895) (xy 310.056844 120.178882)
				(xy 310.075986 120.198999) (xy 310.315999 120.108999) (xy 310.075986 120.018999) (xy 310.057842 120.038417)
				(xy 310.037938 120.047605) (xy 309.994386 120.047974) (xy 309.97692 120.046499)
			)
		)
	)
	(zone
		(net 52)
		(net_name "+5V")
		(layer "F.Cu")
		(hatch edge 0.5)
		(priority 35)
		(connect_pads yes
			(clearance 0.15)
		)
		(min_thickness 0.25)
		(filled_areas_thickness no)
		(fill yes
			(thermal_gap 0.5)
			(thermal_bridge_width 0.5)
			(smoothing fillet)
			(radius 0.2)
		)
		(polygon
			(pts
				(xy 117.5 89.56) (xy 117.5 91.26) (xy 119.65 91.26) (xy 119.65 89.559999)
			)
		)
	)
	(zone
		(net 214)
		(net_name "/Com Express 7 Interfaces/PCIe_{B1x4}.RX2+")
		(layer "F.Cu")
		(name "$teardrop_padvia$")
		(hatch none 0.1)
		(priority 30510)
		(attr
			(teardrop
				(type padvia)
			)
		)
		(connect_pads yes
			(clearance 0)
		)
		(min_thickness 0.0254)
		(filled_areas_thickness no)
		(fill yes
			(thermal_gap 0.5)
			(thermal_bridge_width 0.5)
			(island_removal_mode 1)
			(island_area_min 10)
		)
		(polygon
			(pts
				(xy 205.924 162.2) (xy 205.927537 162.214678) (xy 205.930808 162.244685) (xy 205.918857 162.255673)
				(xy 205.89 162.26) (xy 206.025 163.136) (xy 206.16 162.26) (xy 206.130796 162.255525) (xy 206.119003 162.244203)
				(xy 206.122463 162.214678) (xy 206.126 162.2)
			)
		)
	)
	(zone
		(net 781)
		(net_name "/Misc/TACH_{B3V3}")
		(layer "F.Cu")
		(name "$teardrop_padvia$")
		(hatch none 0.1)
		(priority 30337)
		(attr
			(teardrop
				(type padvia)
			)
		)
		(connect_pads yes
			(clearance 0)
		)
		(min_thickness 0.0254)
		(filled_areas_thickness no)
		(fill yes
			(thermal_gap 0.5)
			(thermal_bridge_width 0.5)
			(island_removal_mode 1)
			(island_area_min 10)
		)
		(polygon
			(pts
				(xy 251.666709 79.0095) (xy 251.632846 79.003719) (xy 251.598224 78.983254) (xy 251.576402 78.956188)
				(xy 251.560709 78.916848) (xy 251.55742 78.901289) (xy 250.850709 79.072) (xy 251.55742 79.242711)
				(xy 251.56901 79.20249) (xy 251.586594 79.173016) (xy 251.634177 79.139827) (xy 251.666709 79.1345)
			)
		)
	)
	(zone
		(net 372)
		(net_name "/Com Express 7 MGMT/I2C.SDA")
		(layer "F.Cu")
		(name "$teardrop_padvia$")
		(hatch none 0.1)
		(priority 30816)
		(attr
			(teardrop
				(type padvia)
			)
		)
		(connect_pads yes
			(clearance 0)
		)
		(min_thickness 0.0254)
		(filled_areas_thickness no)
		(fill yes
			(thermal_gap 0.5)
			(thermal_bridge_width 0.5)
			(island_removal_mode 1)
			(island_area_min 10)
		)
		(polygon
			(pts
				(xy 259.336 89.602499) (xy 259.362609 89.607862) (xy 259.387883 89.625399) (xy 259.405522 89.651693)
				(xy 259.41695 89.689839) (xy 259.42 89.728999) (xy 259.981 89.54) (xy 259.42 89.350999) (xy 259.415373 89.398362)
				(xy 259.402982 89.43341) (xy 259.385123 89.457348) (xy 259.363985 89.471545) (xy 259.336 89.477499)
			)
		)
	)
	(zone
		(net 289)
		(net_name "/2xUSB3.0+RJ45/GbE.MDI2-")
		(layer "F.Cu")
		(name "$teardrop_padvia$")
		(hatch none 0.1)
		(priority 31646)
		(attr
			(teardrop
				(type padvia)
			)
		)
		(connect_pads yes
			(clearance 0)
		)
		(min_thickness 0.0254)
		(filled_areas_thickness no)
		(fill yes
			(thermal_gap 0.5)
			(thermal_bridge_width 0.5)
			(island_removal_mode 1)
			(island_area_min 10)
		)
		(polygon
			(pts
				(xy 178.675 167.742084) (xy 178.672797 167.536718) (xy 178.670677 167.398242) (xy 178.45 167.399)
				(xy 178.324997 167.587081) (xy 178.401138 167.620995) (xy 178.417738 167.62605) (xy 178.459281 167.639844)
				(xy 178.493398 167.659262) (xy 178.516501 167.691083) (xy 178.525 167.742084)
			)
		)
	)
	(zone
		(net 1)
		(net_name "GND")
		(layer "F.Cu")
		(name "$teardrop_padvia$")
		(hatch none 0.1)
		(priority 30599)
		(attr
			(teardrop
				(type padvia)
			)
		)
		(connect_pads yes
			(clearance 0)
		)
		(min_thickness 0.0254)
		(filled_areas_thickness no)
		(fill yes
			(thermal_gap 0.5)
			(thermal_bridge_width 0.5)
			(island_removal_mode 1)
			(island_area_min 10)
		)
		(polygon
			(pts
				(xy 190.925 167.75) (xy 190.928333 167.764486) (xy 190.93119 167.79461) (xy 190.919036 167.805651)
				(xy 190.89 167.81) (xy 191.025 168.686) (xy 191.16 167.81) (xy 191.130666 167.805525) (xy 191.118642 167.794199)
				(xy 191.121667 167.764486) (xy 191.125 167.75)
			)
		)
	)
	(zone
		(net 65)
		(net_name "+12V")
		(layer "F.Cu")
		(name "$teardrop_padvia$")
		(hatch none 0.1)
		(priority 31284)
		(attr
			(teardrop
				(type padvia)
			)
		)
		(connect_pads yes
			(clearance 0)
		)
		(min_thickness 0.0254)
		(filled_areas_thickness no)
		(fill yes
			(thermal_gap 0.5)
			(thermal_bridge_width 0.5)
			(island_removal_mode 1)
			(island_area_min 10)
		)
		(polygon
			(pts
				(xy 193.60861 73.701486) (xy 193.603897 73.779397) (xy 193.59091 73.838181) (xy 193.548809 73.929211)
				(xy 193.50611 74.014384) (xy 193.70861 74.103163) (xy 193.91111 74.014384) (xy 193.868411 73.929213)
				(xy 193.825743 73.83638) (xy 193.813166 73.778241) (xy 193.80861 73.701486)
			)
		)
	)
	(zone
		(net 526)
		(net_name "/Backplane/~{PRSNT}")
		(layer "F.Cu")
		(name "$teardrop_padvia$")
		(hatch none 0.1)
		(priority 32116)
		(attr
			(teardrop
				(type padvia)
			)
		)
		(connect_pads yes
			(clearance 0)
		)
		(min_thickness 0.0254)
		(filled_areas_thickness no)
		(fill yes
			(thermal_gap 0.5)
			(thermal_bridge_width 0.5)
			(island_removal_mode 1)
			(island_area_min 10)
		)
		(polygon
			(pts
				(xy 314.688 164.3955) (xy 314.681678 164.395596) (xy 314.642175 164.390011) (xy 314.623953 164.375078)
				(xy 314.611005 164.3455) (xy 314.362 164.458) (xy 314.611005 164.5705) (xy 314.622121 164.543506)
				(xy 314.637648 164.528405) (xy 314.681678 164.520404) (xy 314.688 164.5205)
			)
		)
	)
	(zone
		(net 1)
		(net_name "GND")
		(layer "F.Cu")
		(name "$teardrop_padvia$")
		(hatch none 0.1)
		(priority 30796)
		(attr
			(teardrop
				(type padvia)
			)
		)
		(connect_pads yes
			(clearance 0)
		)
		(min_thickness 0.0254)
		(filled_areas_thickness no)
		(fill yes
			(thermal_gap 0.5)
			(thermal_bridge_width 0.5)
			(island_removal_mode 1)
			(island_area_min 10)
		)
		(polygon
			(pts
				(xy 304.047 74.639323) (xy 304.040069 74.796893) (xy 304.011549 74.910421) (xy 303.9945 74.952221)
				(xy 304.197 75.041) (xy 304.3995 74.952221) (xy 304.365117 74.856179) (xy 304.3499 74.754304) (xy 304.347 74.639323)
			)
		)
	)
	(zone
		(net 582)
		(net_name "Net-(U20-~{MR})")
		(layer "F.Cu")
		(name "$teardrop_padvia$")
		(hatch none 0.1)
		(priority 30320)
		(attr
			(teardrop
				(type padvia)
			)
		)
		(connect_pads yes
			(clearance 0)
		)
		(min_thickness 0.0254)
		(filled_areas_thickness no)
		(fill yes
			(thermal_gap 0.5)
			(thermal_bridge_width 0.5)
			(island_removal_mode 1)
			(island_area_min 10)
		)
		(polygon
			(pts
				(xy 305.15 130.9775) (xy 305.098087 130.957458) (xy 305.074975 130.931598) (xy 305.056462 130.895129)
				(xy 305.04 130.792319) (xy 304.539 131.039) (xy 305.04 131.28732) (xy 305.044701 131.229002) (xy 305.057604 131.181758)
				(xy 305.076914 131.145545) (xy 305.100834 131.120325) (xy 305.15 131.1025)
			)
		)
	)
	(zone
		(net 869)
		(net_name "/Backplane/PCIe_{x2}.TX1-")
		(layer "F.Cu")
		(name "$teardrop_padvia$")
		(hatch none 0.1)
		(priority 31379)
		(attr
			(teardrop
				(type padvia)
			)
		)
		(connect_pads yes
			(clearance 0)
		)
		(min_thickness 0.0254)
		(filled_areas_thickness no)
		(fill yes
			(thermal_gap 0.5)
			(thermal_bridge_width 0.5)
			(island_removal_mode 1)
			(island_area_min 10)
		)
		(polygon
			(pts
				(xy 268.632504 140.9955) (xy 268.67929 141.000235) (xy 268.714742 141.013379) (xy 268.762939 141.058387)
				(xy 268.787116 141.096608) (xy 268.814485 141.139773) (xy 268.851147 141.181731) (xy 269.001 141.0185)
				(xy 268.98014 140.797823) (xy 268.879466 140.802452) (xy 268.796096 140.799019) (xy 268.794035 140.798895)
				(xy 268.632504 140.7935)
			)
		)
	)
	(zone
		(net 733)
		(net_name "Net-(U43C-CLKOUTB-)")
		(layer "F.Cu")
		(name "$teardrop_padvia$")
		(hatch none 0.1)
		(priority 31472)
		(attr
			(teardrop
				(type padvia)
			)
		)
		(connect_pads yes
			(clearance 0)
		)
		(min_thickness 0.0254)
		(filled_areas_thickness no)
		(fill yes
			(thermal_gap 0.5)
			(thermal_bridge_width 0.5)
			(island_removal_mode 1)
			(island_area_min 10)
		)
		(polygon
			(pts
				(xy 156.715607 140.496005) (xy 156.659844 140.544933) (xy 156.610961 140.574262) (xy 156.52167 140.597534)
				(xy 156.493497 140.601012) (xy 156.401227 140.614804) (xy 156.449293 140.860707) (xy 156.695196 140.908773)
				(xy 156.708304 140.801352) (xy 156.725939 140.696454) (xy 156.753485 140.643865) (xy 156.803995 140.584393)
			)
		)
	)
	(zone
		(net 873)
		(net_name "Net-(U34-EN)")
		(layer "F.Cu")
		(name "$teardrop_padvia$")
		(hatch none 0.1)
		(priority 31037)
		(attr
			(teardrop
				(type padvia)
			)
		)
		(connect_pads yes
			(clearance 0)
		)
		(min_thickness 0.0254)
		(filled_areas_thickness no)
		(fill yes
			(thermal_gap 0.5)
			(thermal_bridge_width 0.5)
			(island_removal_mode 1)
			(island_area_min 10)
		)
		(polygon
			(pts
				(xy 243.362 131.9425) (xy 243.425901 131.962577) (xy 243.458346 131.989046) (xy 243.487174 132.026567)
				(xy 243.508676 132.071363) (xy 243.523202 132.125798) (xy 243.801 131.874) (xy 243.523202 131.622202)
				(xy 243.508794 131.679595) (xy 243.487572 131.727166) (xy 243.460236 131.765956) (xy 243.429297 131.79401)
				(xy 243.396394 131.811305) (xy 243.363666 131.817485) (xy 243.362 131.8175)
			)
		)
	)
	(zone
		(net 339)
		(net_name "/Com Express 7 Interfaces/SDIO.CLK")
		(layer "F.Cu")
		(name "$teardrop_padvia$")
		(hatch none 0.1)
		(priority 30046)
		(attr
			(teardrop
				(type padvia)
			)
		)
		(connect_pads yes
			(clearance 0)
		)
		(min_thickness 0.0254)
		(filled_areas_thickness no)
		(fill yes
			(thermal_gap 0.5)
			(thermal_bridge_width 0.5)
			(island_removal_mode 1)
			(island_area_min 10)
		)
		(polygon
			(pts
				(xy 110.595 134.519) (xy 110.563366 134.513903) (xy 110.532489 134.498222) (xy 110.505162 134.472417)
				(xy 110.482138 134.435622) (xy 110.465474 134.388468) (xy 110.456279 134.329788) (xy 110.455 134.295)
				(xy 109.504 134.61) (xy 110.455 134.925) (xy 110.459723 134.860141) (xy 110.472784 134.807088) (xy 110.492459 134.765444)
				(xy 110.517125 134.734553) (xy 110.545573 134.713687) (xy 110.575742 134.702878) (xy 110.595 134.701)
			)
		)
	)
	(zone
		(net 67)
		(net_name "Net-(C47-Pad2)")
		(layer "F.Cu")
		(hatch edge 0.5)
		(priority 46)
		(connect_pads yes
			(clearance 0.15)
		)
		(min_thickness 0.25)
		(filled_areas_thickness no)
		(fill yes
			(thermal_gap 0.5)
			(thermal_bridge_width 0.5)
		)
		(polygon
			(pts
				(xy 314.364999 122.07) (xy 314.514999 122.22) (xy 314.514999 126.47) (xy 313.514999 127.47) (xy 311.939999 127.47)
				(xy 311.764999 127.295) (xy 311.764999 122.57) (xy 312.014999 122.32) (xy 313.57 122.32) (xy 313.82 122.07)
			)
		)
	)
	(zone
		(net 624)
		(net_name "/PCIe redriver/TX_EQ1")
		(layer "F.Cu")
		(name "$teardrop_padvia$")
		(hatch none 0.1)
		(priority 31908)
		(attr
			(teardrop
				(type padvia)
			)
		)
		(connect_pads yes
			(clearance 0)
		)
		(min_thickness 0.0254)
		(filled_areas_thickness no)
		(fill yes
			(thermal_gap 0.5)
			(thermal_bridge_width 0.5)
			(island_removal_mode 1)
			(island_area_min 10)
		)
		(polygon
			(pts
				(xy 112.132479 147.7975) (xy 112.099001 147.792731) (xy 112.078145 147.779345) (xy 112.064195 147.737885)
				(xy 112.068704 147.673788) (xy 112.073866 147.619791) (xy 112.070677 147.566105) (xy 111.849 147.61)
				(xy 111.806105 147.830677) (xy 111.917114 147.867331) (xy 111.937237 147.87683) (xy 112.016211 147.908594)
				(xy 112.132479 147.9225)
			)
		)
	)
	(zone
		(net 72)
		(net_name "Net-(U20-CT)")
		(layer "F.Cu")
		(name "$teardrop_padvia$")
		(hatch none 0.1)
		(priority 30937)
		(attr
			(teardrop
				(type padvia)
			)
		)
		(connect_pads yes
			(clearance 0)
		)
		(min_thickness 0.0254)
		(filled_areas_thickness no)
		(fill yes
			(thermal_gap 0.5)
			(thermal_bridge_width 0.5)
			(island_removal_mode 1)
			(island_area_min 10)
		)
		(polygon
			(pts
				(xy 304.5575 127.352) (xy 304.537531 127.414866) (xy 304.511079 127.446844) (xy 304.473668 127.475358)
				(xy 304.426473 127.497882) (xy 304.368833 127.513093) (xy 304.368202 127.513202) (xy 304.62 127.791)
				(xy 304.871798 127.513202) (xy 304.816365 127.498905) (xy 304.77048 127.477825) (xy 304.732799 127.45046)
				(xy 304.705566 127.419552) (xy 304.688528 127.386265) (xy 304.682511 127.353434) (xy 304.6825 127.352)
			)
		)
	)
	(zone
		(net 73)
		(net_name "+3V3_AON")
		(layer "F.Cu")
		(name "$teardrop_padvia$")
		(hatch none 0.1)
		(priority 31996)
		(attr
			(teardrop
				(type padvia)
			)
		)
		(connect_pads yes
			(clearance 0)
		)
		(min_thickness 0.0254)
		(filled_areas_thickness no)
		(fill yes
			(thermal_gap 0.5)
			(thermal_bridge_width 0.5)
			(island_removal_mode 1)
			(island_area_min 10)
		)
		(polygon
			(pts
				(xy 238.3125 157.271) (xy 238.323438 157.232177) (xy 238.345195 157.217067) (xy 238.385 157.211)
				(xy 238.25 156.86) (xy 238.115 157.211) (xy 238.150281 157.215517) (xy 238.171797 157.227138) (xy 238.186995 157.259961)
				(xy 238.1875 157.271)
			)
		)
	)
	(zone
		(net 1)
		(net_name "GND")
		(layer "F.Cu")
		(name "$teardrop_padvia$")
		(hatch none 0.1)
		(priority 30232)
		(attr
			(teardrop
				(type padvia)
			)
		)
		(connect_pads yes
			(clearance 0)
		)
		(min_thickness 0.0254)
		(filled_areas_thickness no)
		(fill yes
			(thermal_gap 0.5)
			(thermal_bridge_width 0.5)
			(island_removal_mode 1)
			(island_area_min 10)
		)
		(polygon
			(pts
				(xy 243.330815 127.161316) (xy 243.34834 127.143308) (xy 243.395075 127.097412) (xy 243.4542 127.055037)
				(xy 243.529678 127.02847) (xy 243.625474 127.03) (xy 243.570707 126.709293) (xy 243.275 126.629526)
				(xy 243.275839 126.687082) (xy 243.267683 126.738009) (xy 243.22741 126.828788) (xy 243.156185 126.912675)
				(xy 243.138504 126.92985) (xy 243.118684 126.949185)
			)
		)
	)
	(zone
		(net 543)
		(net_name "Net-(Q10-B)")
		(layer "F.Cu")
		(name "$teardrop_padvia$")
		(hatch none 0.1)
		(priority 31792)
		(attr
			(teardrop
				(type padvia)
			)
		)
		(connect_pads yes
			(clearance 0)
		)
		(min_thickness 0.0254)
		(filled_areas_thickness no)
		(fill yes
			(thermal_gap 0.5)
			(thermal_bridge_width 0.5)
			(island_removal_mode 1)
			(island_area_min 10)
		)
		(polygon
			(pts
				(xy 316.400677 111.6465) (xy 316.331236 111.641682) (xy 316.279913 111.62796) (xy 316.204371 111.581246)
				(xy 316.192231 111.571701) (xy 316.125003 111.521919) (xy 315.999 111.709) (xy 316.125003 111.896081)
				(xy 316.192229 111.846299) (xy 316.275396 111.791894) (xy 316.328251 111.77681) (xy 316.400677 111.7715)
			)
		)
	)
	(zone
		(net 271)
		(net_name "/M.2 key M #2/PCIE_{REF}.CK-")
		(layer "F.Cu")
		(name "$teardrop_padvia$")
		(hatch none 0.1)
		(priority 30384)
		(attr
			(teardrop
				(type padvia)
			)
		)
		(connect_pads yes
			(clearance 0)
		)
		(min_thickness 0.0254)
		(filled_areas_thickness no)
		(fill yes
			(thermal_gap 0.5)
			(thermal_bridge_width 0.5)
			(island_removal_mode 1)
			(island_area_min 10)
		)
		(polygon
			(pts
				(xy 299.355 74.87) (xy 299.344009 74.715428) (xy 299.32954 74.511774) (xy 299.332682 74.391947)
				(xy 299.349 74.257561) (xy 299.199 74.034) (xy 299.114761 74.81) (xy 299.145337 74.814477) (xy 299.158218 74.825818)
				(xy 299.156029 74.855826) (xy 299.153 74.87)
			)
		)
	)
	(zone
		(net 2)
		(net_name "+3V3")
		(layer "F.Cu")
		(name "$teardrop_padvia$")
		(hatch none 0.1)
		(priority 30409)
		(attr
			(teardrop
				(type padvia)
			)
		)
		(connect_pads yes
			(clearance 0)
		)
		(min_thickness 0.0254)
		(filled_areas_thickness no)
		(fill yes
			(thermal_gap 0.5)
			(thermal_bridge_width 0.5)
			(island_removal_mode 1)
			(island_area_min 10)
		)
		(polygon
			(pts
				(xy 190.972734 135.80085) (xy 191.018729 135.817991) (xy 191.055756 135.828406) (xy 191.084774 135.845299)
				(xy 191.093692 135.874155) (xy 191.070421 135.920459) (xy 191.442252 135.916816) (xy 191.445895 135.544985)
				(xy 191.412016 135.564977) (xy 191.387145 135.568059) (xy 191.360756 135.545904) (xy 191.343428 135.493293)
				(xy 191.326286 135.447297)
			)
		)
	)
	(zone
		(net 207)
		(net_name "/Backplane/UART.TX")
		(layer "F.Cu")
		(name "$teardrop_padvia$")
		(hatch none 0.1)
		(priority 31737)
		(attr
			(teardrop
				(type padvia)
			)
		)
		(connect_pads yes
			(clearance 0)
		)
		(min_thickness 0.0254)
		(filled_areas_thickness no)
		(fill yes
			(thermal_gap 0.5)
			(thermal_bridge_width 0.5)
			(island_removal_mode 1)
			(island_area_min 10)
		)
		(polygon
			(pts
				(xy 313.2375 168.809323) (xy 313.232682 168.878763) (xy 313.21896 168.930087) (xy 313.172245 169.005628)
				(xy 313.162702 169.017768) (xy 313.112919 169.084997) (xy 313.3 169.211) (xy 313.487081 169.084997)
				(xy 313.437299 169.017769) (xy 313.382894 168.934603) (xy 313.36781 168.881748) (xy 313.3625 168.809323)
			)
		)
	)
	(zone
		(net 138)
		(net_name "Net-(U33-1A)")
		(layer "F.Cu")
		(name "$teardrop_padvia$")
		(hatch none 0.1)
		(priority 30210)
		(attr
			(teardrop
				(type padvia)
			)
		)
		(connect_pads yes
			(clearance 0)
		)
		(min_thickness 0.0254)
		(filled_areas_thickness no)
		(fill yes
			(thermal_gap 0.5)
			(thermal_bridge_width 0.5)
			(island_removal_mode 1)
			(island_area_min 10)
		)
		(polygon
			(pts
				(xy 253.712 129.79) (xy 253.692279 129.84726) (xy 253.629467 129.899784) (xy 253.580847 129.91955)
				(xy 253.521549 129.932076) (xy 253.5045 129.933927) (xy 253.7745 130.411) (xy 254.0445 129.933927)
				(xy 253.983256 129.923751) (xy 253.93233 129.906075) (xy 253.891487 129.882177) (xy 253.861803 129.853978)
				(xy 253.84387 129.823988) (xy 253.83706 129.793138) (xy 253.837 129.79)
			)
		)
	)
	(zone
		(net 77)
		(net_name "+5V_AON")
		(layer "F.Cu")
		(hatch edge 0.5)
		(priority 1)
		(connect_pads yes
			(clearance 0.15)
		)
		(min_thickness 0.25)
		(filled_areas_thickness no)
		(fill yes
			(thermal_gap 0.2)
			(thermal_bridge_width 0.5)
			(smoothing fillet)
			(radius 0.2)
		)
		(polygon
			(pts
				(xy 303.75 98.141) (xy 298.1 98.141) (xy 298.1 100.41) (xy 297.3 100.41) (xy 297.3 98.141) (xy 295.95 98.141)
				(xy 295.95 100.26) (xy 295.65 100.26) (xy 295.65 98.141) (xy 292.5 98.141) (xy 292.5 95.47) (xy 303.75 95.47)
			)
		)
	)
	(zone
		(net 622)
		(net_name "/PCIe misc/DIF5-")
		(layer "F.Cu")
		(name "$teardrop_padvia$")
		(hatch none 0.1)
		(priority 31315)
		(attr
			(teardrop
				(type padvia)
			)
		)
		(connect_pads yes
			(clearance 0)
		)
		(min_thickness 0.0254)
		(filled_areas_thickness no)
		(fill yes
			(thermal_gap 0.5)
			(thermal_bridge_width 0.5)
			(island_removal_mode 1)
			(island_area_min 10)
		)
		(polygon
			(pts
				(xy 220.021964 127.598173) (xy 220.157249 127.57651) (xy 220.256257 127.573197) (xy 220.314856 127.575351)
				(xy 220.35989 127.577177) (xy 220.369046 127.356305) (xy 220.212553 127.199928) (xy 220.149097 127.281206)
				(xy 220.090403 127.353229) (xy 220.046233 127.380552) (xy 219.982546 127.400058)
			)
		)
	)
	(zone
		(net 148)
		(net_name "/2xUSB3.0+RJ45/DB+")
		(layer "F.Cu")
		(name "$teardrop_padvia$")
		(hatch none 0.1)
		(priority 30016)
		(attr
			(teardrop
				(type padvia)
			)
		)
		(connect_pads yes
			(clearance 0)
		)
		(min_thickness 0.0254)
		(filled_areas_thickness no)
		(fill yes
			(thermal_gap 0.5)
			(thermal_bridge_width 0.5)
			(island_removal_mode 1)
			(island_area_min 10)
		)
		(polygon
			(pts
				(xy 116.94797 107.345) (xy 117.056258 107.349857) (xy 117.147842 107.363853) (xy 117.221997 107.384867)
				(xy 117.285927 107.412635) (xy 117.398217 107.490245) (xy 117.506017 107.596069) (xy 117.621758 107.710939)
				(xy 117.77499 107.831242) (xy 118.151 107.27) (xy 117.77499 106.708758) (xy 117.615761 106.834561)
				(xy 117.506017 106.943932) (xy 117.40577 107.04312) (xy 117.294599 107.122763) (xy 117.227767 107.153035)
				(xy 117.149625 107.175757) (xy 117.057313 107.190041) (xy 116.94797 107.195)
			)
		)
	)
	(zone
		(net 196)
		(net_name "/OCuLink/PCIe_{x4}.RX3+")
		(layer "F.Cu")
		(name "$teardrop_padvia$")
		(hatch none 0.1)
		(priority 31430)
		(attr
			(teardrop
				(type padvia)
			)
		)
		(connect_pads yes
			(clearance 0)
		)
		(min_thickness 0.0254)
		(filled_areas_thickness no)
		(fill yes
			(thermal_gap 0.5)
			(thermal_bridge_width 0.5)
			(island_removal_mode 1)
			(island_area_min 10)
		)
		(polygon
			(pts
				(xy 99.392496 158.4435) (xy 99.230964 158.448895) (xy 99.146554 158.452445) (xy 99.04486 158.447823)
				(xy 99.024 158.6685) (xy 99.173852 158.831731) (xy 99.227992 158.763062) (xy 99.237883 158.746608)
				(xy 99.262383 158.707935) (xy 99.29189 158.675721) (xy 99.333046 158.653673) (xy 99.392496 158.6455)
			)
		)
	)
	(zone
		(net 241)
		(net_name "/Com Express 7 Interfaces/PCIe_{B2Bx4}.TX3-")
		(layer "F.Cu")
		(name "$teardrop_padvia$")
		(hatch none 0.1)
		(priority 31363)
		(attr
			(teardrop
				(type padvia)
			)
		)
		(connect_pads yes
			(clearance 0)
		)
		(min_thickness 0.0254)
		(filled_areas_thickness no)
		(fill yes
			(thermal_gap 0.5)
			(thermal_bridge_width 0.5)
			(island_removal_mode 1)
			(island_area_min 10)
		)
		(polygon
			(pts
				(xy 187.0705 167.367496) (xy 187.075235 167.32071) (xy 187.088379 167.285257) (xy 187.133387 167.23706)
				(xy 187.171608 167.212883) (xy 187.214774 167.185514) (xy 187.256731 167.148852) (xy 187.0935 166.999)
				(xy 186.872823 167.019859) (xy 186.877452 167.120536) (xy 186.874019 167.203908) (xy 186.873895 167.205963)
				(xy 186.8685 167.367496)
			)
		)
	)
	(zone
		(net 531)
		(net_name "/Com Express 7 Interfaces/SD_CD")
		(layer "F.Cu")
		(name "$teardrop_padvia$")
		(hatch none 0.1)
		(priority 31268)
		(attr
			(teardrop
				(type padvia)
			)
		)
		(connect_pads yes
			(clearance 0)
		)
		(min_thickness 0.0254)
		(filled_areas_thickness no)
		(fill yes
			(thermal_gap 0.5)
			(thermal_bridge_width 0.5)
			(island_removal_mode 1)
			(island_area_min 10)
		)
		(polygon
			(pts
				(xy 113.900677 139.26) (xy 113.822765 139.255287) (xy 113.763981 139.2423) (xy 113.672949 139.200198)
				(xy 113.587778 139.1575) (xy 113.499 139.36) (xy 113.587778 139.5625) (xy 113.672947 139.519802)
				(xy 113.765782 139.477133) (xy 113.823921 139.464556) (xy 113.900677 139.46)
			)
		)
	)
	(zone
		(net 194)
		(net_name "/OCuLink/PCIe_{x4}.RX2+")
		(layer "F.Cu")
		(name "$teardrop_padvia$")
		(hatch none 0.1)
		(priority 31359)
		(attr
			(teardrop
				(type padvia)
			)
		)
		(connect_pads yes
			(clearance 0)
		)
		(min_thickness 0.0254)
		(filled_areas_thickness no)
		(fill yes
			(thermal_gap 0.5)
			(thermal_bridge_width 0.5)
			(island_removal_mode 1)
			(island_area_min 10)
		)
		(polygon
			(pts
				(xy 109.3955 149.167496) (xy 109.400235 149.12071) (xy 109.413379 149.085257) (xy 109.458387 149.03706)
				(xy 109.496608 149.012883) (xy 109.539774 148.985514) (xy 109.581731 148.948852) (xy 109.4185 148.799)
				(xy 109.197823 148.819859) (xy 109.202452 148.920536) (xy 109.199019 149.003908) (xy 109.198895 149.005963)
				(xy 109.1935 149.167496)
			)
		)
	)
	(zone
		(net 434)
		(net_name "/Com Express 7 MGMT/~{TYPE1}")
		(layer "F.Cu")
		(name "$teardrop_padvia$")
		(hatch none 0.1)
		(priority 31806)
		(attr
			(teardrop
				(type padvia)
			)
		)
		(connect_pads yes
			(clearance 0)
		)
		(min_thickness 0.0254)
		(filled_areas_thickness no)
		(fill yes
			(thermal_gap 0.5)
			(thermal_bridge_width 0.5)
			(island_removal_mode 1)
			(island_area_min 10)
		)
		(polygon
			(pts
				(xy 221.950677 149.0625) (xy 221.881236 149.057682) (xy 221.829913 149.04396) (xy 221.754371 148.997246)
				(xy 221.742231 148.987701) (xy 221.675003 148.937919) (xy 221.549 149.125) (xy 221.675003 149.312081)
				(xy 221.742229 149.262299) (xy 221.825396 149.207894) (xy 221.878251 149.19281) (xy 221.950677 149.1875)
			)
		)
	)
	(zone
		(net 192)
		(net_name "/OCuLink/PCIe_{REF0}.CK+")
		(layer "F.Cu")
		(name "$teardrop_padvia$")
		(hatch none 0.1)
		(priority 31435)
		(attr
			(teardrop
				(type padvia)
			)
		)
		(connect_pads yes
			(clearance 0)
		)
		(min_thickness 0.0254)
		(filled_areas_thickness no)
		(fill yes
			(thermal_gap 0.5)
			(thermal_bridge_width 0.5)
			(island_removal_mode 1)
			(island_area_min 10)
		)
		(polygon
			(pts
				(xy 207.737496 130.0185) (xy 207.575964 130.023895) (xy 207.491554 130.027445) (xy 207.38986 130.022823)
				(xy 207.369 130.2435) (xy 207.518852 130.406731) (xy 207.572992 130.338062) (xy 207.582883 130.321608)
				(xy 207.607383 130.282935) (xy 207.63689 130.250721) (xy 207.678046 130.228673) (xy 207.737496 130.2205)
			)
		)
	)
	(zone
		(net 618)
		(net_name "/PCIe misc/DIF3-")
		(layer "F.Cu")
		(name "$teardrop_padvia$")
		(hatch none 0.1)
		(priority 30439)
		(attr
			(teardrop
				(type padvia)
			)
		)
		(connect_pads yes
			(clearance 0)
		)
		(min_thickness 0.0254)
		(filled_areas_thickness no)
		(fill yes
			(thermal_gap 0.5)
			(thermal_bridge_width 0.5)
			(island_removal_mode 1)
			(island_area_min 10)
		)
		(polygon
			(pts
				(xy 216.5735 132.274479) (xy 216.615458 132.352727) (xy 216.651472 132.451282) (xy 216.66683 132.528157)
				(xy 216.669442 132.608423) (xy 216.66 132.671754) (xy 216.98 132.641) (xy 217.078914 132.345) (xy 216.954533 132.347815)
				(xy 216.863647 132.335293) (xy 216.821613 132.318304) (xy 216.789966 132.293452) (xy 216.7755 132.274479)
			)
		)
	)
	(zone
		(net 977)
		(net_name "/PCIe redriver/RX_EQ1")
		(layer "F.Cu")
		(name "$teardrop_padvia$")
		(hatch none 0.1)
		(priority 31544)
		(attr
			(teardrop
				(type padvia)
			)
		)
		(connect_pads yes
			(clearance 0)
		)
		(min_thickness 0.0254)
		(filled_areas_thickness no)
		(fill yes
			(thermal_gap 0.5)
			(thermal_bridge_width 0.5)
			(island_removal_mode 1)
			(island_area_min 10)
		)
		(polygon
			(pts
				(xy 190.117975 140.14276) (xy 190.19887 140.1207) (xy 190.252934 140.121662) (xy 190.309836 140.133821)
				(xy 190.35805 140.154286) (xy 190.403733 140.185133) (xy 190.423604 139.81863) (xy 190.060058 139.857398)
				(xy 190.109273 139.918988) (xy 190.133656 139.967198) (xy 190.136069 139.993176) (xy 190.12613 140.011911)
				(xy 190.117975 140.01776)
			)
		)
	)
	(zone
		(net 978)
		(net_name "/PCIe redriver/RX_EQ0")
		(layer "F.Cu")
		(name "$teardrop_padvia$")
		(hatch none 0.1)
		(priority 31140)
		(attr
			(teardrop
				(type padvia)
			)
		)
		(connect_pads yes
			(clearance 0)
		)
		(min_thickness 0.0254)
		(filled_areas_thickness no)
		(fill yes
			(thermal_gap 0.5)
			(thermal_bridge_width 0.5)
			(island_removal_mode 1)
			(island_area_min 10)
		)
		(polygon
			(pts
				(xy 188.76055 138.740645) (xy 188.816542 138.712616) (xy 188.900941 138.717699) (xy 188.95067 138.736737)
				(xy 189.003019 138.768335) (xy 189.012741 138.775539) (xy 189.009098 138.40371) (xy 188.637267 138.400065)
				(xy 188.670706 138.451675) (xy 188.691884 138.501044) (xy 188.701921 138.547745) (xy 188.701351 138.589346)
				(xy 188.691503 138.62393) (xy 188.673488 138.650902) (xy 188.672162 138.652257)
			)
		)
	)
	(zone
		(net 950)
		(net_name "/2xSFP+/KR to SFI #2/SFI_R.RX+")
		(layer "F.Cu")
		(name "$teardrop_padvia$")
		(hatch none 0.1)
		(priority 31970)
		(attr
			(teardrop
				(type padvia)
			)
		)
		(connect_pads yes
			(clearance 0)
		)
		(min_thickness 0.0254)
		(filled_areas_thickness no)
		(fill yes
			(thermal_gap 0.5)
			(thermal_bridge_width 0.5)
			(island_removal_mode 1)
			(island_area_min 10)
		)
		(polygon
			(pts
				(xy 131.52 146.739321) (xy 131.500773 146.763574) (xy 131.470489 146.779871) (xy 131.377293 146.787898)
				(xy 131.349956 146.786) (xy 131.41 147.017) (xy 131.61 147.043457) (xy 131.608097 146.939652) (xy 131.639419 146.825164)
				(xy 131.68 146.739321)
			)
		)
	)
	(zone
		(net 19)
		(net_name "/M.2 key E/PCIE_{REF}.CK+")
		(layer "F.Cu")
		(name "$teardrop_padvia$")
		(hatch none 0.1)
		(priority 30418)
		(attr
			(teardrop
				(type padvia)
			)
		)
		(connect_pads yes
			(clearance 0)
		)
		(min_thickness 0.0254)
		(filled_areas_thickness no)
		(fill yes
			(thermal_gap 0.5)
			(thermal_bridge_width 0.5)
			(island_removal_mode 1)
			(island_area_min 10)
		)
		(polygon
			(pts
				(xy 214.7755 135.845521) (xy 214.798758 135.817939) (xy 214.829996 135.797276) (xy 214.921915 135.774401)
				(xy 215.078914 135.775) (xy 214.98 135.479) (xy 214.66 135.448245) (xy 214.669439 135.563376) (xy 214.644667 135.691715)
				(xy 214.586792 135.823281) (xy 214.5735 135.845521)
			)
		)
	)
	(zone
		(net 303)
		(net_name "/Com Express 7 MGMT/~{SUS_S5}")
		(layer "F.Cu")
		(name "$teardrop_padvia$")
		(hatch none 0.1)
		(priority 31876)
		(attr
			(teardrop
				(type padvia)
			)
		)
		(connect_pads yes
			(clearance 0)
		)
		(min_thickness 0.0254)
		(filled_areas_thickness no)
		(fill yes
			(thermal_gap 0.5)
			(thermal_bridge_width 0.5)
			(island_removal_mode 1)
			(island_area_min 10)
		)
		(polygon
			(pts
				(xy 221.560873 142.427515) (xy 221.613382 142.381819) (xy 221.659376 142.355231) (xy 221.745824 142.334847)
				(xy 221.76116 142.333011) (xy 221.843895 142.320677) (xy 221.800707 142.099293) (xy 221.579323 142.056105)
				(xy 221.566988 142.138841) (xy 221.546651 142.236119) (xy 221.519943 142.284159) (xy 221.472485 142.339127)
			)
		)
	)
	(zone
		(net 2)
		(net_name "+3V3")
		(layer "F.Cu")
		(name "$teardrop_padvia$")
		(hatch none 0.1)
		(priority 30890)
		(attr
			(teardrop
				(type padvia)
			)
		)
		(connect_pads yes
			(clearance 0)
		)
		(min_thickness 0.0254)
		(filled_areas_thickness no)
		(fill yes
			(thermal_gap 0.5)
			(thermal_bridge_width 0.5)
			(island_removal_mode 1)
			(island_area_min 10)
		)
		(polygon
			(pts
				(xy 245.321857 78.273) (xy 245.259181 78.277612) (xy 245.207545 78.289897) (xy 245.105682 78.340622)
				(xy 245.045363 78.374173) (xy 244.974439 78.394323) (xy 244.999709 78.615) (xy 245.188538 78.738195)
				(xy 245.215649 78.673815) (xy 245.247325 78.604232) (xy 245.276512 78.581561) (xy 245.321857 78.573)
			)
		)
	)
	(zone
		(net 547)
		(net_name "/2xUSB3.0+RJ45/P1_ISET")
		(layer "F.Cu")
		(name "$teardrop_padvia$")
		(hatch none 0.1)
		(priority 31039)
		(attr
			(teardrop
				(type padvia)
			)
		)
		(connect_pads yes
			(clearance 0)
		)
		(min_thickness 0.0254)
		(filled_areas_thickness no)
		(fill yes
			(thermal_gap 0.5)
			(thermal_bridge_width 0.5)
			(island_removal_mode 1)
			(island_area_min 10)
		)
		(polygon
			(pts
				(xy 119.762 86.9265) (xy 119.82982 86.947019) (xy 119.863595 86.973459) (xy 119.893121 87.011216)
				(xy 119.923202 87.091798) (xy 120.201 86.84) (xy 119.922446 86.589332) (xy 119.907877 86.652522)
				(xy 119.886374 86.705032) (xy 119.859265 86.746839) (xy 119.828341 86.777085) (xy 119.796538 86.794934)
				(xy 119.764161 86.801474) (xy 119.762 86.8015)
			)
		)
	)
	(zone
		(net 439)
		(net_name "Net-(J12L-RAPID_SHUTDOWN)")
		(layer "F.Cu")
		(name "$teardrop_padvia$")
		(hatch none 0.1)
		(priority 31669)
		(attr
			(teardrop
				(type padvia)
			)
		)
		(connect_pads yes
			(clearance 0)
		)
		(min_thickness 0.0254)
		(filled_areas_thickness no)
		(fill yes
			(thermal_gap 0.5)
			(thermal_bridge_width 0.5)
			(island_removal_mode 1)
			(island_area_min 10)
		)
		(polygon
			(pts
				(xy 208.9625 157.721811) (xy 208.957735 157.760433) (xy 208.94438 157.787144) (xy 208.901154 157.814219)
				(xy 208.844668 157.825481) (xy 208.784199 157.837036) (xy 208.724997 157.862919) (xy 208.85 158.051)
				(xy 209.070677 158.067287) (xy 209.076304 157.998078) (xy 209.0875 157.721811)
			)
		)
	)
	(zone
		(net 1)
		(net_name "GND")
		(layer "F.Cu")
		(name "$teardrop_padvia$")
		(hatch none 0.1)
		(priority 31287)
		(attr
			(teardrop
				(type padvia)
			)
		)
		(connect_pads yes
			(clearance 0)
		)
		(min_thickness 0.0254)
		(filled_areas_thickness no)
		(fill yes
			(thermal_gap 0.5)
			(thermal_bridge_width 0.5)
			(island_removal_mode 1)
			(island_area_min 10)
		)
		(polygon
			(pts
				(xy 199.425 157.474323) (xy 199.420287 157.552234) (xy 199.4073 157.611018) (xy 199.365199 157.702048)
				(xy 199.3225 157.787221) (xy 199.525 157.876) (xy 199.7275 157.787221) (xy 199.684801 157.70205)
				(xy 199.642133 157.609217) (xy 199.629556 157.551078) (xy 199.625 157.474323)
			)
		)
	)
	(zone
		(net 88)
		(net_name "/Com Express 7 Interfaces/PCIe_{B2Ax4}.RX2-")
		(layer "F.Cu")
		(name "$teardrop_padvia$")
		(hatch none 0.1)
		(priority 30371)
		(attr
			(teardrop
				(type padvia)
			)
		)
		(connect_pads yes
			(clearance 0)
		)
		(min_thickness 0.0254)
		(filled_areas_thickness no)
		(fill yes
			(thermal_gap 0.5)
			(thermal_bridge_width 0.5)
			(island_removal_mode 1)
			(island_area_min 10)
		)
		(polygon
			(pts
				(xy 290.744 74.87) (xy 290.740971 74.855826) (xy 290.738932 74.825491) (xy 290.751912 74.814377)
				(xy 290.782239 74.81) (xy 290.698 74.034) (xy 290.548 74.257561) (xy 290.567555 74.47053) (xy 290.552991 74.715428)
				(xy 290.542 74.87)
			)
		)
	)
	(zone
		(net 16)
		(net_name "/Com Express 7 Interfaces/PCIe_{B1x2}.RX0-")
		(layer "F.Cu")
		(name "$teardrop_padvia$")
		(hatch none 0.1)
		(priority 30364)
		(attr
			(teardrop
				(type padvia)
			)
		)
		(connect_pads yes
			(clearance 0)
		)
		(min_thickness 0.0254)
		(filled_areas_thickness no)
		(fill yes
			(thermal_gap 0.5)
			(thermal_bridge_width 0.5)
			(island_removal_mode 1)
			(island_area_min 10)
		)
		(polygon
			(pts
				(xy 154.4085 81.014) (xy 154.394331 81.017024) (xy 154.363993 81.019052) (xy 154.352878 81.006062)
				(xy 154.3485 80.97572) (xy 153.5725 81.0595) (xy 153.793966 81.2095) (xy 154.007619 81.190152) (xy 154.252972 81.204897)
				(xy 154.4085 81.216)
			)
		)
	)
	(zone
		(net 541)
		(net_name "Net-(Q9-B)")
		(layer "F.Cu")
		(name "$teardrop_padvia$")
		(hatch none 0.1)
		(priority 30820)
		(attr
			(teardrop
				(type padvia)
			)
		)
		(connect_pads yes
			(clearance 0)
		)
		(min_thickness 0.0254)
		(filled_areas_thickness no)
		(fill yes
			(thermal_gap 0.5)
			(thermal_bridge_width 0.5)
			(island_removal_mode 1)
			(island_area_min 10)
		)
		(polygon
			(pts
				(xy 255.344 84.397499) (xy 255.317391 84.392136) (xy 255.292117 84.374599) (xy 255.274478 84.348305)
				(xy 255.26305 84.310159) (xy 255.26 84.270999) (xy 254.699 84.46) (xy 255.26 84.648999) (xy 255.264627 84.601636)
				(xy 255.277018 84.566588) (xy 255.294877 84.54265) (xy 255.316015 84.528453) (xy 255.344 84.522499)
			)
		)
	)
	(zone
		(net 543)
		(net_name "Net-(Q10-B)")
		(layer "F.Cu")
		(name "$teardrop_padvia$")
		(hatch none 0.1)
		(priority 30206)
		(attr
			(teardrop
				(type padvia)
			)
		)
		(connect_pads yes
			(clearance 0)
		)
		(min_thickness 0.0254)
		(filled_areas_thickness no)
		(fill yes
			(thermal_gap 0.5)
			(thermal_bridge_width 0.5)
			(island_removal_mode 1)
			(island_area_min 10)
		)
		(polygon
			(pts
				(xy 317.58 112.722) (xy 317.63726 112.741721) (xy 317.689784 112.804533) (xy 317.709551 112.853153)
				(xy 317.722077 112.912451) (xy 317.723928 112.9295) (xy 318.201 112.6595) (xy 317.723928 112.3895)
				(xy 317.713752 112.450744) (xy 317.696075 112.501671) (xy 317.672177 112.542514) (xy 317.643978 112.572197)
				(xy 317.613988 112.59013) (xy 317.583138 112.596941) (xy 317.58 112.597)
			)
		)
	)
	(zone
		(net 207)
		(net_name "/Backplane/UART.TX")
		(layer "F.Cu")
		(name "$teardrop_padvia$")
		(hatch none 0.1)
		(priority 30033)
		(attr
			(teardrop
				(type padvia)
			)
		)
		(connect_pads yes
			(clearance 0)
		)
		(min_thickness 0.0254)
		(filled_areas_thickness no)
		(fill yes
			(thermal_gap 0.5)
			(thermal_bridge_width 0.5)
			(island_removal_mode 1)
			(island_area_min 10)
		)
		(polygon
			(pts
				(xy 317.84 167.3725) (xy 317.902625 167.392823) (xy 317.933436 167.419267) (xy 317.960377 167.456912)
				(xy 317.990273 167.544727) (xy 319.451 167.31) (xy 317.990273 167.075273) (xy 317.976502 167.127739)
				(xy 317.956084 167.170431) (xy 317.929557 167.204843) (xy 317.89976 167.229005) (xy 317.84 167.2475)
			)
		)
	)
	(zone
		(net 970)
		(net_name "/M.2 key M #2/M2_3V3")
		(layer "F.Cu")
		(name "$teardrop_padvia$")
		(hatch none 0.1)
		(priority 30760)
		(attr
			(teardrop
				(type padvia)
			)
		)
		(connect_pads yes
			(clearance 0)
		)
		(min_thickness 0.0254)
		(filled_areas_thickness no)
		(fill yes
			(thermal_gap 0.5)
			(thermal_bridge_width 0.5)
			(island_removal_mode 1)
			(island_area_min 10)
		)
		(polygon
			(pts
				(xy 290.598 80.978677) (xy 290.604932 80.8211) (xy 290.633456 80.707565) (xy 290.6505 80.665778)
				(xy 290.448 80.577) (xy 290.2455 80.665778) (xy 290.279883 80.761822) (xy 290.295101 80.863702)
				(xy 290.298 80.978677)
			)
		)
	)
	(zone
		(net 6)
		(net_name "/M.2 key E/~{LED_2}")
		(layer "F.Cu")
		(name "$teardrop_padvia$")
		(hatch none 0.1)
		(priority 30174)
		(attr
			(teardrop
				(type padvia)
			)
		)
		(connect_pads yes
			(clearance 0)
		)
		(min_thickness 0.0254)
		(filled_areas_thickness no)
		(fill yes
			(thermal_gap 0.5)
			(thermal_bridge_width 0.5)
			(island_removal_mode 1)
			(island_area_min 10)
		)
		(polygon
			(pts
				(xy 115.0125 71.12) (xy 115.031757 71.06156) (xy 115.092765 71.007485) (xy 115.202366 70.967203)
				(xy 115.31 70.956021) (xy 114.95 70.559) (xy 114.59 70.956021) (xy 114.665789 70.961642) (xy 114.732251 70.975856)
				(xy 114.78852 70.997451) (xy 114.833209 71.025051) (xy 114.863499 71.055041) (xy 114.881876 71.088017)
				(xy 114.8875 71.12)
			)
		)
	)
	(zone
		(net 1)
		(net_name "GND")
		(layer "F.Cu")
		(name "$teardrop_padvia$")
		(hatch none 0.1)
		(priority 30563)
		(attr
			(teardrop
				(type padvia)
			)
		)
		(connect_pads yes
			(clearance 0)
		)
		(min_thickness 0.0254)
		(filled_areas_thickness no)
		(fill yes
			(thermal_gap 0.5)
			(thermal_bridge_width 0.5)
			(island_removal_mode 1)
			(island_area_min 10)
		)
		(polygon
			(pts
				(xy 181.125 157.62) (xy 181.121667 157.605514) (xy 181.11881 157.57539) (xy 181.130964 157.564349)
				(xy 181.16 157.56) (xy 181.025 156.684) (xy 180.89 157.56) (xy 180.919334 157.564475) (xy 180.931358 157.575801)
				(xy 180.928333 157.605514) (xy 180.925 157.62)
			)
		)
	)
	(zone
		(net 83)
		(net_name "Net-(Q11-D)")
		(layer "F.Cu")
		(name "$teardrop_padvia$")
		(hatch none 0.1)
		(priority 30205)
		(attr
			(teardrop
				(type padvia)
			)
		)
		(connect_pads yes
			(clearance 0)
		)
		(min_thickness 0.0254)
		(filled_areas_thickness no)
		(fill yes
			(thermal_gap 0.5)
			(thermal_bridge_width 0.5)
			(island_removal_mode 1)
			(island_area_min 10)
		)
		(polygon
			(pts
				(xy 249.18 127.223) (xy 249.23726 127.242721) (xy 249.289784 127.305533) (xy 249.309551 127.354153)
				(xy 249.322077 127.413451) (xy 249.323928 127.4305) (xy 249.801 127.1605) (xy 249.323928 126.8905)
				(xy 249.313752 126.951744) (xy 249.296075 127.002671) (xy 249.272177 127.043514) (xy 249.243978 127.073197)
				(xy 249.213988 127.09113) (xy 249.183138 127.097941) (xy 249.18 127.098)
			)
		)
	)
	(zone
		(net 375)
		(net_name "/2xUSB3.0+RJ45/USB_2.D+")
		(layer "F.Cu")
		(name "$teardrop_padvia$")
		(hatch none 0.1)
		(priority 31548)
		(attr
			(teardrop
				(type padvia)
			)
		)
		(connect_pads yes
			(clearance 0)
		)
		(min_thickness 0.0254)
		(filled_areas_thickness no)
		(fill yes
			(thermal_gap 0.5)
			(thermal_bridge_width 0.5)
			(island_removal_mode 1)
			(island_area_min 10)
		)
		(polygon
			(pts
				(xy 154.8305 122.657916) (xy 154.825752 122.697787) (xy 154.81252 122.726451) (xy 154.768144 122.760593)
				(xy 154.728021 122.77623) (xy 154.647997 122.812919) (xy 154.773 123.001) (xy 154.993677 123.001757)
				(xy 155.003901 122.85154) (xy 155.0155 122.657916)
			)
		)
	)
	(zone
		(net 543)
		(net_name "Net-(Q10-B)")
		(layer "F.Cu")
		(name "$teardrop_padvia$")
		(hatch none 0.1)
		(priority 30318)
		(attr
			(teardrop
				(type padvia)
			)
		)
		(connect_pads yes
			(clearance 0)
		)
		(min_thickness 0.0254)
		(filled_areas_thickness no)
		(fill yes
			(thermal_gap 0.5)
			(thermal_bridge_width 0.5)
			(island_removal_mode 1)
			(island_area_min 10)
		)
		(polygon
			(pts
				(xy 316.658043 111.679656) (xy 316.59201 111.651586) (xy 316.555815 111.619807) (xy 316.524021 111.577958)
				(xy 316.500469 111.529596) (xy 316.486225 111.474081) (xy 316.483735 111.450469) (xy 315.999293 111.708293)
				(xy 316.493149 111.953442) (xy 316.500815 111.863909) (xy 316.518634 111.802012) (xy 316.536158 111.777969)
				(xy 316.558607 111.767892) (xy 316.569656 111.768043)
			)
		)
	)
	(zone
		(net 623)
		(net_name "/PCIe redriver/TX_EQ0")
		(layer "F.Cu")
		(name "$teardrop_padvia$")
		(hatch none 0.1)
		(priority 31660)
		(attr
			(teardrop
				(type padvia)
			)
		)
		(connect_pads yes
			(clearance 0)
		)
		(min_thickness 0.0254)
		(filled_areas_thickness no)
		(fill yes
			(thermal_gap 0.5)
			(thermal_bridge_width 0.5)
			(island_removal_mode 1)
			(island_area_min 10)
		)
		(polygon
			(pts
				(xy 111.965383 148.736995) (xy 111.94199 148.706852) (xy 111.933384 148.67928) (xy 111.946967 148.632666)
				(xy 111.990205 148.580537) (xy 112.035207 148.527907) (xy 112.066237 148.464613) (xy 111.849293 148.409293)
				(xy 111.668407 148.540491) (xy 111.736516 148.645442) (xy 111.788647 148.72549) (xy 111.876995 148.825383)
			)
		)
	)
	(zone
		(net 528)
		(net_name "/Backplane/~{PERST}")
		(layer "F.Cu")
		(name "$teardrop_padvia$")
		(hatch none 0.1)
		(priority 31889)
		(attr
			(teardrop
				(type padvia)
			)
		)
		(connect_pads yes
			(clearance 0)
		)
		(min_thickness 0.0254)
		(filled_areas_thickness no)
		(fill yes
			(thermal_gap 0.5)
			(thermal_bridge_width 0.5)
			(island_removal_mode 1)
			(island_area_min 10)
		)
		(polygon
			(pts
				(xy 282.727515 103.424127) (xy 282.681819 103.371618) (xy 282.655231 103.325623) (xy 282.634847 103.239175)
				(xy 282.633011 103.22384) (xy 282.620677 103.141105) (xy 282.399293 103.184293) (xy 282.356105 103.405677)
				(xy 282.43884 103.418011) (xy 282.536119 103.438349) (xy 282.584159 103.465057) (xy 282.639127 103.512515)
			)
		)
	)
	(zone
		(net 165)
		(net_name "/2xSFP+/SCL0")
		(layer "F.Cu")
		(name "$teardrop_padvia$")
		(hatch none 0.1)
		(priority 31804)
		(attr
			(teardrop
				(type padvia)
			)
		)
		(connect_pads yes
			(clearance 0)
		)
		(min_thickness 0.0254)
		(filled_areas_thickness no)
		(fill yes
			(thermal_gap 0.5)
			(thermal_bridge_width 0.5)
			(island_removal_mode 1)
			(island_area_min 10)
		)
		(polygon
			(pts
				(xy 177.400677 146.9375) (xy 177.331236 146.932682) (xy 177.279913 146.91896) (xy 177.204371 146.872246)
				(xy 177.192231 146.862701) (xy 177.125003 146.812919) (xy 176.999 147) (xy 177.125003 147.187081)
				(xy 177.192229 147.137299) (xy 177.275396 147.082894) (xy 177.328251 147.06781) (xy 177.400677 147.0625)
			)
		)
	)
	(zone
		(net 1)
		(net_name "GND")
		(layer "F.Cu")
		(name "$teardrop_padvia$")
		(hatch none 0.1)
		(priority 31324)
		(attr
			(teardrop
				(type padvia)
			)
		)
		(connect_pads yes
			(clearance 0)
		)
		(min_thickness 0.0254)
		(filled_areas_thickness no)
		(fill yes
			(thermal_gap 0.5)
			(thermal_bridge_width 0.5)
			(island_removal_mode 1)
			(island_area_min 10)
		)
		(polygon
			(pts
				(xy 213.625 162.187793) (xy 213.631205 162.026365) (xy 213.654641 161.902721) (xy 213.664815 161.861192)
				(xy 213.666731 161.853421) (xy 213.45 161.799) (xy 213.269305 161.931389) (xy 213.338296 162.00539)
				(xy 213.399512 162.074698) (xy 213.418152 162.122293) (xy 213.425 162.187793)
			)
		)
	)
	(zone
		(net 1)
		(net_name "GND")
		(layer "F.Cu")
		(name "$teardrop_padvia$")
		(hatch none 0.1)
		(priority 30619)
		(attr
			(teardrop
				(type padvia)
			)
		)
		(connect_pads yes
			(clearance 0)
		)
		(min_thickness 0.0254)
		(filled_areas_thickness no)
		(fill yes
			(thermal_gap 0.5)
			(thermal_bridge_width 0.5)
			(island_removal_mode 1)
			(island_area_min 10)
		)
		(polygon
			(pts
				(xy 195.925 162.2) (xy 195.928333 162.214486) (xy 195.93119 162.24461) (xy 195.919036 162.255651)
				(xy 195.89 162.26) (xy 196.025 163.136) (xy 196.16 162.26) (xy 196.130666 162.255525) (xy 196.118642 162.244199)
				(xy 196.121667 162.214486) (xy 196.125 162.2)
			)
		)
	)
	(zone
		(net 377)
		(net_name "/Com Express 7 Interfaces/USB1.D-")
		(layer "F.Cu")
		(name "$teardrop_padvia$")
		(hatch none 0.1)
		(priority 31489)
		(attr
			(teardrop
				(type padvia)
			)
		)
		(connect_pads yes
			(clearance 0)
		)
		(min_thickness 0.0254)
		(filled_areas_thickness no)
		(fill yes
			(thermal_gap 0.5)
			(thermal_bridge_width 0.5)
			(island_removal_mode 1)
			(island_area_min 10)
		)
		(polygon
			(pts
				(xy 158.290416 72.0825) (xy 158.335028 72.08724) (xy 158.368424 72.100418) (xy 158.412019 72.145201)
				(xy 158.434851 72.187819) (xy 158.460509 72.235662) (xy 158.497104 72.281688) (xy 158.651 72.1225)
				(xy 158.637562 71.901823) (xy 158.454858 71.901684) (xy 158.290416 71.8975)
			)
		)
	)
	(zone
		(net 434)
		(net_name "/Com Express 7 MGMT/~{TYPE1}")
		(layer "F.Cu")
		(name "$teardrop_padvia$")
		(hatch none 0.1)
		(priority 30672)
		(attr
			(teardrop
				(type padvia)
			)
		)
		(connect_pads yes
			(clearance 0)
		)
		(min_thickness 0.0254)
		(filled_areas_thickness no)
		(fill yes
			(thermal_gap 0.5)
			(thermal_bridge_width 0.5)
			(island_removal_mode 1)
			(island_area_min 10)
		)
		(polygon
			(pts
				(xy 203.9625 155.75) (xy 203.951563 155.788823) (xy 203.929805 155.803933) (xy 203.89 155.81) (xy 204.025 156.686)
				(xy 204.16 155.81) (xy 204.124719 155.805483) (xy 204.103203 155.793862) (xy 204.088005 155.761039)
				(xy 204.0875 155.75)
			)
		)
	)
	(zone
		(net 1)
		(net_name "GND")
		(layer "F.Cu")
		(name "$teardrop_padvia$")
		(hatch none 0.1)
		(priority 31283)
		(attr
			(teardrop
				(type padvia)
			)
		)
		(connect_pads yes
			(clearance 0)
		)
		(min_thickness 0.0254)
		(filled_areas_thickness no)
		(fill yes
			(thermal_gap 0.5)
			(thermal_bridge_width 0.5)
			(island_removal_mode 1)
			(island_area_min 10)
		)
		(polygon
			(pts
				(xy 225.4 163.899323) (xy 225.395287 163.977234) (xy 225.3823 164.036018) (xy 225.340199 164.127048)
				(xy 225.2975 164.212221) (xy 225.5 164.301) (xy 225.7025 164.212221) (xy 225.659801 164.12705) (xy 225.617133 164.034217)
				(xy 225.604556 163.976078) (xy 225.6 163.899323)
			)
		)
	)
	(zone
		(net 557)
		(net_name "Net-(U5-A0)")
		(layer "F.Cu")
		(name "$teardrop_padvia$")
		(hatch none 0.1)
		(priority 30990)
		(attr
			(teardrop
				(type padvia)
			)
		)
		(connect_pads yes
			(clearance 0)
		)
		(min_thickness 0.0254)
		(filled_areas_thickness no)
		(fill yes
			(thermal_gap 0.5)
			(thermal_bridge_width 0.5)
			(island_removal_mode 1)
			(island_area_min 10)
		)
		(polygon
			(pts
				(xy 162.6825 159.798) (xy 162.702469 159.735134) (xy 162.728921 159.703156) (xy 162.766332 159.674642)
				(xy 162.813527 159.652118) (xy 162.871167 159.636907) (xy 162.871798 159.636798) (xy 162.62 159.359)
				(xy 162.368202 159.636798) (xy 162.423635 159.651095) (xy 162.46952 159.672175) (xy 162.507201 159.69954)
				(xy 162.534434 159.730448) (xy 162.551472 159.763735) (xy 162.557489 159.796566) (xy 162.5575 159.798)
			)
		)
	)
	(zone
		(net 370)
		(net_name "Net-(J12D-SPKR)")
		(layer "F.Cu")
		(name "$teardrop_padvia$")
		(hatch none 0.1)
		(priority 30649)
		(attr
			(teardrop
				(type padvia)
			)
		)
		(connect_pads yes
			(clearance 0)
		)
		(min_thickness 0.0254)
		(filled_areas_thickness no)
		(fill yes
			(thermal_gap 0.5)
			(thermal_bridge_width 0.5)
			(island_removal_mode 1)
			(island_area_min 10)
		)
		(polygon
			(pts
				(xy 191.5875 164.07) (xy 191.598438 164.031177) (xy 191.620195 164.016067) (xy 191.66 164.01) (xy 191.525 163.134)
				(xy 191.39 164.01) (xy 191.425281 164.014517) (xy 191.446797 164.026138) (xy 191.461995 164.058961)
				(xy 191.4625 164.07)
			)
		)
	)
	(zone
		(net 541)
		(net_name "Net-(Q9-B)")
		(layer "F.Cu")
		(name "$teardrop_padvia$")
		(hatch none 0.1)
		(priority 31302)
		(attr
			(teardrop
				(type padvia)
			)
		)
		(connect_pads yes
			(clearance 0)
		)
		(min_thickness 0.0254)
		(filled_areas_thickness no)
		(fill yes
			(thermal_gap 0.5)
			(thermal_bridge_width 0.5)
			(island_removal_mode 1)
			(island_area_min 10)
		)
		(polygon
			(pts
				(xy 121.399323 142.911) (xy 121.477653 142.915713) (xy 121.536712 142.928701) (xy 121.627625 142.970412)
				(xy 121.712752 143.012719) (xy 121.801 142.81) (xy 121.711685 142.607722) (xy 121.626483 142.650809)
				(xy 121.53394 142.693743) (xy 121.475927 142.70641) (xy 121.399323 142.711)
			)
		)
	)
	(zone
		(net 16)
		(net_name "/Com Express 7 Interfaces/PCIe_{B1x2}.RX0-")
		(layer "F.Cu")
		(name "$teardrop_padvia$")
		(hatch none 0.1)
		(priority 31428)
		(attr
			(teardrop
				(type padvia)
			)
		)
		(connect_pads yes
			(clearance 0)
		)
		(min_thickness 0.0254)
		(filled_areas_thickness no)
		(fill yes
			(thermal_gap 0.5)
			(thermal_bridge_width 0.5)
			(island_removal_mode 1)
			(island_area_min 10)
		)
		(polygon
			(pts
				(xy 203.3685 163.982504) (xy 203.373895 164.144035) (xy 203.377445 164.228446) (xy 203.372823 164.33014)
				(xy 203.5935 164.351) (xy 203.756731 164.201147) (xy 203.688062 164.147007) (xy 203.671608 164.137116)
				(xy 203.632935 164.112616) (xy 203.600721 164.083109) (xy 203.578673 164.041953) (xy 203.5705 163.982504)
			)
		)
	)
	(zone
		(net 397)
		(net_name "/Com Express 7 MGMT/SPI.~{CS}")
		(layer "F.Cu")
		(name "$teardrop_padvia$")
		(hatch none 0.1)
		(priority 31580)
		(attr
			(teardrop
				(type padvia)
			)
		)
		(connect_pads yes
			(clearance 0)
		)
		(min_thickness 0.0254)
		(filled_areas_thickness no)
		(fill yes
			(thermal_gap 0.5)
			(thermal_bridge_width 0.5)
			(island_removal_mode 1)
			(island_area_min 10)
		)
		(polygon
			(pts
				(xy 257.499323 163.9) (xy 257.573121 163.90466) (xy 257.629124 163.917283) (xy 257.714161 163.956768)
				(xy 257.829182 164.009525) (xy 257.901 163.8) (xy 257.774997 163.612919) (xy 257.689503 163.6862)
				(xy 257.616781 163.745753) (xy 257.567407 163.763526) (xy 257.499323 163.77)
			)
		)
	)
	(zone
		(net 148)
		(net_name "/2xUSB3.0+RJ45/DB+")
		(layer "F.Cu")
		(name "$teardrop_padvia$")
		(hatch none 0.1)
		(priority 31577)
		(attr
			(teardrop
				(type padvia)
			)
		)
		(connect_pads yes
			(clearance 0)
		)
		(min_thickness 0.0254)
		(filled_areas_thickness no)
		(fill yes
			(thermal_gap 0.5)
			(thermal_bridge_width 0.5)
			(island_removal_mode 1)
			(island_area_min 10)
		)
		(polygon
			(pts
				(xy 125.8575 106.035) (xy 125.894762 106.040773) (xy 125.933367 106.061186) (xy 125.958689 106.088248)
				(xy 125.978392 106.12759) (xy 125.987281 106.162719) (xy 126.291 105.96) (xy 125.987281 105.757281)
				(xy 125.97498 105.801474) (xy 125.956524 105.834766) (xy 125.90635 105.87492) (xy 125.8575 105.885)
			)
		)
	)
	(zone
		(net 325)
		(net_name "/Com Express 7 Interfaces/PCIe_{B2Ax4}.TX0-")
		(layer "F.Cu")
		(name "$teardrop_padvia$")
		(hatch none 0.1)
		(priority 30377)
		(attr
			(teardrop
				(type padvia)
			)
		)
		(connect_pads yes
			(clearance 0)
		)
		(min_thickness 0.0254)
		(filled_areas_thickness no)
		(fill yes
			(thermal_gap 0.5)
			(thermal_bridge_width 0.5)
			(island_removal_mode 1)
			(island_area_min 10)
		)
		(polygon
			(pts
				(xy 298.0425 73.2) (xy 298.053603 73.355527) (xy 298.068217 73.559681) (xy 298.06518 73.679806)
				(xy 298.049 73.814533) (xy 298.199 74.036) (xy 298.28278 73.26) (xy 298.252191 73.255523) (xy 298.239299 73.244182)
				(xy 298.241476 73.214169) (xy 298.2445 73.2)
			)
		)
	)
	(zone
		(net 2)
		(net_name "+3V3")
		(layer "F.Cu")
		(name "$teardrop_padvia$")
		(hatch none 0.1)
		(priority 31018)
		(attr
			(teardrop
				(type padvia)
			)
		)
		(connect_pads yes
			(clearance 0)
		)
		(min_thickness 0.0254)
		(filled_areas_thickness no)
		(fill yes
			(thermal_gap 0.5)
			(thermal_bridge_width 0.5)
			(island_removal_mode 1)
			(island_area_min 10)
		)
		(polygon
			(pts
				(xy 191.455332 139.405326) (xy 191.425 139.346753) (xy 191.421093 139.305437) (xy 191.427384 139.258821)
				(xy 191.444829 139.209522) (xy 191.474831 139.158009) (xy 191.4752 139.157486) (xy 191.100719 139.139101)
				(xy 191.119104 139.513582) (xy 191.16841 139.484494) (xy 191.215761 139.466955) (xy 191.261756 139.45966)
				(xy 191.302868 139.462259) (xy 191.338453 139.473748) (xy 191.365922 139.492708) (xy 191.366944 139.493714)
			)
		)
	)
	(zone
		(net 87)
		(net_name "/Com Express 7 Interfaces/PCIe_{B2Ax4}.RX1-")
		(layer "F.Cu")
		(name "$teardrop_padvia$")
		(hatch none 0.1)
		(priority 30271)
		(attr
			(teardrop
				(type padvia)
			)
		)
		(connect_pads yes
			(clearance 0)
		)
		(min_thickness 0.0254)
		(filled_areas_thickness no)
		(fill yes
			(thermal_gap 0.5)
			(thermal_bridge_width 0.5)
			(island_removal_mode 1)
			(island_area_min 10)
		)
		(polygon
			(pts
				(xy 212.8685 162.2) (xy 212.879599 162.373112) (xy 212.894216 162.60051) (xy 212.891181 162.735138)
				(xy 212.875 162.887021) (xy 213.025 163.136) (xy 213.108295 162.26) (xy 213.077864 162.255523) (xy 213.065097 162.244185)
				(xy 213.06742 162.214227) (xy 213.0705 162.2)
			)
		)
	)
	(zone
		(net 866)
		(net_name "/Backplane/PCIe_{x2}.TX0+")
		(layer "F.Cu")
		(name "$teardrop_padvia$")
		(hatch none 0.1)
		(priority 31402)
		(attr
			(teardrop
				(type padvia)
			)
		)
		(connect_pads yes
			(clearance 0)
		)
		(min_thickness 0.0254)
		(filled_areas_thickness no)
		(fill yes
			(thermal_gap 0.5)
			(thermal_bridge_width 0.5)
			(island_removal_mode 1)
			(island_area_min 10)
		)
		(polygon
			(pts
				(xy 268.632504 139.0065) (xy 268.794035 139.001105) (xy 268.878445 138.997554) (xy 268.98014 139.002177)
				(xy 269.001 138.7815) (xy 268.851147 138.618268) (xy 268.797007 138.686935) (xy 268.787115 138.703393)
				(xy 268.762615 138.742065) (xy 268.733109 138.774279) (xy 268.691953 138.796327) (xy 268.632504 138.8045)
			)
		)
	)
	(zone
		(net 187)
		(net_name "/OCuLink/PCIe_{x4}.RX0-")
		(layer "F.Cu")
		(name "$teardrop_padvia$")
		(hatch none 0.1)
		(priority 31348)
		(attr
			(teardrop
				(type padvia)
			)
		)
		(connect_pads yes
			(clearance 0)
		)
		(min_thickness 0.0254)
		(filled_areas_thickness no)
		(fill yes
			(thermal_gap 0.5)
			(thermal_bridge_width 0.5)
			(island_removal_mode 1)
			(island_area_min 10)
		)
		(polygon
			(pts
				(xy 97.279092 149.318809) (xy 97.315522 149.289074) (xy 97.349885 149.2733) (xy 97.415791 149.271045)
				(xy 97.459912 149.280976) (xy 97.509788 149.292147) (xy 97.565381 149.295891) (xy 97.555921 149.074507)
				(xy 97.385129 148.933214) (xy 97.317215 149.007674) (xy 97.255836 149.064198) (xy 97.254294 149.065565)
				(xy 97.136256 149.175973)
			)
		)
	)
	(zone
		(net 93)
		(net_name "/Com Express 7 Interfaces/PCIe_{B2Ax4}.RX3+")
		(layer "F.Cu")
		(name "$teardrop_padvia$")
		(hatch none 0.1)
		(priority 30374)
		(attr
			(teardrop
				(type padvia)
			)
		)
		(connect_pads yes
			(clearance 0)
		)
		(min_thickness 0.0254)
		(filled_areas_thickness no)
		(fill yes
			(thermal_gap 0.5)
			(thermal_bridge_width 0.5)
			(island_removal_mode 1)
			(island_area_min 10)
		)
		(polygon
			(pts
				(xy 287.354 74.87) (xy 287.342784 74.713526) (xy 287.328025 74.508886) (xy 287.330958 74.388472)
				(xy 287.347 74.253414) (xy 287.197 74.034) (xy 287.113678 74.81) (xy 287.144281 74.814477) (xy 287.157183 74.825818)
				(xy 287.15502 74.855836) (xy 287.152 74.87)
			)
		)
	)
	(zone
		(net 1)
		(net_name "GND")
		(layer "F.Cu")
		(name "$teardrop_padvia$")
		(hatch none 0.1)
		(priority 30895)
		(attr
			(teardrop
				(type padvia)
			)
		)
		(connect_pads yes
			(clearance 0)
		)
		(min_thickness 0.0254)
		(filled_areas_thickness no)
		(fill yes
			(thermal_gap 0.5)
			(thermal_bridge_width 0.5)
			(island_removal_mode 1)
			(island_area_min 10)
		)
		(polygon
			(pts
				(xy 143.04 148.454781) (xy 143.044603 148.518102) (xy 143.056828 148.570232) (xy 143.104937 148.670131)
				(xy 143.137259 148.730742) (xy 143.156323 148.801697) (xy 143.377 148.779) (xy 143.502003 148.590919)
				(xy 143.439486 148.563236) (xy 143.370799 148.530132) (xy 143.348441 148.500428) (xy 143.34 148.454781)
			)
		)
	)
	(zone
		(net 669)
		(net_name "/2xSFP+/KR to SFI #2/MDIO_R")
		(layer "F.Cu")
		(name "$teardrop_padvia$")
		(hatch none 0.1)
		(priority 30345)
		(attr
			(teardrop
				(type padvia)
			)
		)
		(connect_pads yes
			(clearance 0)
		)
		(min_thickness 0.0254)
		(filled_areas_thickness no)
		(fill yes
			(thermal_gap 0.5)
			(thermal_bridge_width 0.5)
			(island_removal_mode 1)
			(island_area_min 10)
		)
		(polygon
			(pts
				(xy 123.6705 150.596) (xy 123.664719 150.629863) (xy 123.644254 150.664486) (xy 123.617188 150.686307)
				(xy 123.577849 150.702) (xy 123.562289 150.705289) (xy 123.733 151.412) (xy 123.903711 150.705289)
				(xy 123.86349 150.6937) (xy 123.834017 150.676116) (xy 123.800827 150.628533) (xy 123.7955 150.596)
			)
		)
	)
	(zone
		(net 1)
		(net_name "GND")
		(layer "F.Cu")
		(name "$teardrop_padvia$")
		(hatch none 0.1)
		(priority 31261)
		(attr
			(teardrop
				(type padvia)
			)
		)
		(connect_pads yes
			(clearance 0)
		)
		(min_thickness 0.0254)
		(filled_areas_thickness no)
		(fill yes
			(thermal_gap 0.5)
			(thermal_bridge_width 0.5)
			(island_removal_mode 1)
			(island_area_min 10)
		)
		(polygon
			(pts
				(xy 107.7 151.600677) (xy 107.704713 151.522764) (xy 107.7177 151.46398) (xy 107.759802 151.372947)
				(xy 107.8025 151.287778) (xy 107.6 151.199) (xy 107.3975 151.287778) (xy 107.440198 151.372949)
				(xy 107.482867 151.465783) (xy 107.495444 151.523922) (xy 107.5 151.600677)
			)
		)
	)
	(zone
		(net 2)
		(net_name "+3V3")
		(layer "F.Cu")
		(name "$teardrop_padvia$")
		(hatch none 0.1)
		(priority 30929)
		(attr
			(teardrop
				(type padvia)
			)
		)
		(connect_pads yes
			(clearance 0)
		)
		(min_thickness 0.0254)
		(filled_areas_thickness no)
		(fill yes
			(thermal_gap 0.5)
			(thermal_bridge_width 0.5)
			(island_removal_mode 1)
			(island_area_min 10)
		)
		(polygon
			(pts
				(xy 298.762 84.5525) (xy 298.824866 84.572469) (xy 298.856844 84.598921) (xy 298.885358 84.636332)
				(xy 298.907882 84.683527) (xy 298.923093 84.741167) (xy 298.923202 84.741798) (xy 299.201 84.49)
				(xy 298.923202 84.238202) (xy 298.908905 84.293635) (xy 298.887825 84.33952) (xy 298.86046 84.377201)
				(xy 298.829552 84.404434) (xy 298.796265 84.421472) (xy 298.763434 84.427489) (xy 298.762 84.4275)
			)
		)
	)
	(zone
		(net 330)
		(net_name "/Com Express 7 Interfaces/PCIe_{B2Ax4}.TX3+")
		(layer "F.Cu")
		(name "$teardrop_padvia$")
		(hatch none 0.1)
		(priority 30521)
		(attr
			(teardrop
				(type padvia)
			)
		)
		(connect_pads yes
			(clearance 0)
		)
		(min_thickness 0.0254)
		(filled_areas_thickness no)
		(fill yes
			(thermal_gap 0.5)
			(thermal_bridge_width 0.5)
			(island_removal_mode 1)
			(island_area_min 10)
		)
		(polygon
			(pts
				(xy 215.924 167.75) (xy 215.927537 167.764678) (xy 215.930808 167.794685) (xy 215.918857 167.805673)
				(xy 215.89 167.81) (xy 216.025 168.686) (xy 216.16 167.81) (xy 216.130796 167.805525) (xy 216.119003 167.794203)
				(xy 216.122463 167.764678) (xy 216.126 167.75)
			)
		)
	)
	(zone
		(net 565)
		(net_name "/2xSFP+/~{LED1_0}")
		(layer "F.Cu")
		(name "$teardrop_padvia$")
		(hatch none 0.1)
		(priority 32016)
		(attr
			(teardrop
				(type padvia)
			)
		)
		(connect_pads yes
			(clearance 0)
		)
		(min_thickness 0.0254)
		(filled_areas_thickness no)
		(fill yes
			(thermal_gap 0.5)
			(thermal_bridge_width 0.5)
			(island_removal_mode 1)
			(island_area_min 10)
		)
		(polygon
			(pts
				(xy 156.8995 160.9205) (xy 156.905822 160.920404) (xy 156.945325 160.925989) (xy 156.963547 160.940922)
				(xy 156.976495 160.9705) (xy 157.363 160.858) (xy 156.976495 160.7455) (xy 156.965379 160.772493)
				(xy 156.949852 160.787595) (xy 156.905822 160.795596) (xy 156.8995 160.7955)
			)
		)
	)
	(zone
		(net 663)
		(net_name "Net-(U43C-ST)")
		(layer "F.Cu")
		(name "$teardrop_padvia$")
		(hatch none 0.1)
		(priority 30970)
		(attr
			(teardrop
				(type padvia)
			)
		)
		(connect_pads yes
			(clearance 0)
		)
		(min_thickness 0.0254)
		(filled_areas_thickness no)
		(fill yes
			(thermal_gap 0.5)
			(thermal_bridge_width 0.5)
			(island_removal_mode 1)
			(island_area_min 10)
		)
		(polygon
			(pts
				(xy 143.5425 134.318) (xy 143.562469 134.255134) (xy 143.588921 134.223156) (xy 143.626332 134.194642)
				(xy 143.673527 134.172118) (xy 143.731167 134.156907) (xy 143.731798 134.156798) (xy 143.48 133.879)
				(xy 143.228202 134.156798) (xy 143.283635 134.171095) (xy 143.32952 134.192175) (xy 143.367201 134.21954)
				(xy 143.394434 134.250448) (xy 143.411472 134.283735) (xy 143.417489 134.316566) (xy 143.4175 134.318)
			)
		)
	)
	(zone
		(net 166)
		(net_name "Net-(J2A-MOD_{ABS})")
		(layer "F.Cu")
		(name "$teardrop_padvia$")
		(hatch none 0.1)
		(priority 31117)
		(attr
			(teardrop
				(type padvia)
			)
		)
		(connect_pads yes
			(clearance 0)
		)
		(min_thickness 0.0254)
		(filled_areas_thickness no)
		(fill yes
			(thermal_gap 0.5)
			(thermal_bridge_width 0.5)
			(island_removal_mode 1)
			(island_area_min 10)
		)
		(polygon
			(pts
				(xy 177.507 145.0625) (xy 177.566412 145.082273) (xy 177.622497 145.145547) (xy 177.644199 145.194172)
				(xy 177.658873 145.253531) (xy 177.660653 145.2655) (xy 177.921 145) (xy 177.660653 144.7345) (xy 177.647804 144.794638)
				(xy 177.62787 144.844522) (xy 177.601945 144.884641) (xy 177.572125 144.913654) (xy 177.540707 144.931146)
				(xy 177.508896 144.937479) (xy 177.507 144.9375)
			)
		)
	)
	(zone
		(net 84)
		(net_name "/Com Express 7 MGMT/PWRBTN")
		(layer "F.Cu")
		(name "$teardrop_padvia$")
		(hatch none 0.1)
		(priority 31795)
		(attr
			(teardrop
				(type padvia)
			)
		)
		(connect_pads yes
			(clearance 0)
		)
		(min_thickness 0.0254)
		(filled_areas_thickness no)
		(fill yes
			(thermal_gap 0.5)
			(thermal_bridge_width 0.5)
			(island_removal_mode 1)
			(island_area_min 10)
		)
		(polygon
			(pts
				(xy 223.550677 124.8475) (xy 223.481236 124.842682) (xy 223.429913 124.82896) (xy 223.354371 124.782246)
				(xy 223.342231 124.772701) (xy 223.275003 124.722919) (xy 223.149 124.91) (xy 223.275003 125.097081)
				(xy 223.342229 125.047299) (xy 223.425396 124.992894) (xy 223.478251 124.97781) (xy 223.550677 124.9725)
			)
		)
	)
	(zone
		(net 62)
		(net_name "+12V_AON")
		(layer "F.Cu")
		(name "$teardrop_padvia$")
		(hatch none 0.1)
		(priority 30073)
		(attr
			(teardrop
				(type padvia)
			)
		)
		(connect_pads yes
			(clearance 0)
		)
		(min_thickness 0.0254)
		(filled_areas_thickness no)
		(fill yes
			(thermal_gap 0.5)
			(thermal_bridge_width 0.5)
			(island_removal_mode 1)
			(island_area_min 10)
		)
		(polygon
			(pts
				(xy 201.04861 74.202163) (xy 201.085772 74.207238) (xy 201.12365 74.222765) (xy 201.160172 74.249033)
				(xy 201.193664 74.28654) (xy 201.221272 74.33361) (xy 201.242698 74.391874) (xy 201.255473 74.4553)
				(xy 201.70961 74.102163) (xy 201.255473 73.749026) (xy 201.241879 73.815361) (xy 201.221126 73.871025)
				(xy 201.194019 73.917296) (xy 201.162526 73.953141) (xy 201.126885 73.97972) (xy 201.089968 73.99589)
				(xy 201.04861 74.002163)
			)
		)
	)
	(zone
		(net 400)
		(net_name "/Com Express 7 MGMT/FAN_PWM")
		(layer "F.Cu")
		(name "$teardrop_padvia$")
		(hatch none 0.1)
		(priority 31588)
		(attr
			(teardrop
				(type padvia)
			)
		)
		(connect_pads yes
			(clearance 0)
		)
		(min_thickness 0.0254)
		(filled_areas_thickness no)
		(fill yes
			(thermal_gap 0.5)
			(thermal_bridge_width 0.5)
			(island_removal_mode 1)
			(island_area_min 10)
		)
		(polygon
			(pts
				(xy 226.0875 162.387793) (xy 226.09224 162.336431) (xy 226.105419 162.297426) (xy 226.150294 162.243864)
				(xy 226.185714 162.217855) (xy 226.233726 162.181814) (xy 226.280694 162.131389) (xy 226.1 161.999)
				(xy 225.883268 162.053421) (xy 225.921603 162.170931) (xy 225.950489 162.259583) (xy 225.9625 162.387793)
			)
		)
	)
	(zone
		(net 968)
		(net_name "/2xSFP+/KR to SFI #2/BYP_RX-")
		(layer "F.Cu")
		(name "$teardrop_padvia$")
		(hatch none 0.1)
		(priority 31942)
		(attr
			(teardrop
				(type padvia)
			)
		)
		(connect_pads yes
			(clearance 0)
		)
		(min_thickness 0.0254)
		(filled_areas_thickness no)
		(fill yes
			(thermal_gap 0.5)
			(thermal_bridge_width 0.5)
			(island_removal_mode 1)
			(island_area_min 10)
		)
		(polygon
			(pts
				(xy 132.06 148.553721) (xy 132.071736 148.530685) (xy 132.094198 148.514987) (xy 132.170557 148.505864)
				(xy 132.228769 148.511) (xy 132.17 148.28) (xy 131.97 148.252463) (xy 131.965648 148.351256) (xy 131.924062 148.484347)
				(xy 131.9 148.553721)
			)
		)
	)
	(zone
		(net 318)
		(net_name "Net-(J12D-LPC_SERIRQ{slash}~{ESPI_CS1})")
		(layer "F.Cu")
		(name "$teardrop_padvia$")
		(hatch none 0.1)
		(priority 31590)
		(attr
			(teardrop
				(type padvia)
			)
		)
		(connect_pads yes
			(clearance 0)
		)
		(min_thickness 0.0254)
		(filled_areas_thickness no)
		(fill yes
			(thermal_gap 0.5)
			(thermal_bridge_width 0.5)
			(island_removal_mode 1)
			(island_area_min 10)
		)
		(polygon
			(pts
				(xy 200.081273 169.980339) (xy 200.019035 170.036048) (xy 199.966661 170.071007) (xy 199.897881 170.103337)
				(xy 199.786347 170.158217) (xy 199.899293 170.350707) (xy 200.120677 170.386813) (xy 200.121442 170.292016)
				(xy 200.116523 170.258806) (xy 200.110365 170.21212) (xy 200.112236 170.166671) (xy 200.129534 170.119769)
				(xy 200.169661 170.068727)
			)
		)
	)
	(zone
		(net 553)
		(net_name "/2xUSB3.0+RJ45/FLG_1B")
		(layer "F.Cu")
		(name "$teardrop_padvia$")
		(hatch none 0.1)
		(priority 30996)
		(attr
			(teardrop
				(type padvia)
			)
		)
		(connect_pads yes
			(clearance 0)
		)
		(min_thickness 0.0254)
		(filled_areas_thickness no)
		(fill yes
			(thermal_gap 0.5)
			(thermal_bridge_width 0.5)
			(island_removal_mode 1)
			(island_area_min 10)
		)
		(polygon
			(pts
				(xy 121.6325 87.498) (xy 121.652469 87.435134) (xy 121.678921 87.403156) (xy 121.716332 87.374642)
				(xy 121.763527 87.352118) (xy 121.821167 87.336907) (xy 121.821798 87.336798) (xy 121.57 87.059)
				(xy 121.318202 87.336798) (xy 121.373635 87.351095) (xy 121.41952 87.372175) (xy 121.457201 87.39954)
				(xy 121.484434 87.430448) (xy 121.501472 87.463735) (xy 121.507489 87.496566) (xy 121.5075 87.498)
			)
		)
	)
	(zone
		(net 719)
		(net_name "Net-(U40-~{I2C_{RESET}})")
		(layer "F.Cu")
		(name "$teardrop_padvia$")
		(hatch none 0.1)
		(priority 31796)
		(attr
			(teardrop
				(type padvia)
			)
		)
		(connect_pads yes
			(clearance 0)
		)
		(min_thickness 0.0254)
		(filled_areas_thickness no)
		(fill yes
			(thermal_gap 0.5)
			(thermal_bridge_width 0.5)
			(island_removal_mode 1)
			(island_area_min 10)
		)
		(polygon
			(pts
				(xy 194.824798 131.452576) (xy 194.755357 131.447758) (xy 194.704034 131.434036) (xy 194.628492 131.387322)
				(xy 194.616352 131.377777) (xy 194.549124 131.327995) (xy 194.423121 131.515076) (xy 194.549124 131.702157)
				(xy 194.61635 131.652375) (xy 194.699517 131.59797) (xy 194.752372 131.582886) (xy 194.824798 131.577576)
			)
		)
	)
	(zone
		(net 1)
		(net_name "GND")
		(layer "F.Cu")
		(name "$teardrop_padvia$")
		(hatch none 0.1)
		(priority 30220)
		(attr
			(teardrop
				(type padvia)
			)
		)
		(connect_pads yes
			(clearance 0)
		)
		(min_thickness 0.0254)
		(filled_areas_thickness no)
		(fill yes
			(thermal_gap 0.5)
			(thermal_bridge_width 0.5)
			(island_removal_mode 1)
			(island_area_min 10)
		)
		(polygon
			(pts
				(xy 259.467708 77.922) (xy 259.498316 77.91365) (xy 259.551301 77.903039) (xy 259.574433 77.916044)
				(xy 259.590899 77.952) (xy 260.283708 77.772) (xy 259.590899 77.592) (xy 259.578965 77.621959) (xy 259.562644 77.637272)
				(xy 259.52497 77.639108) (xy 259.498316 77.63035) (xy 259.467708 77.622)
			)
		)
	)
	(zone
		(net 244)
		(net_name "/Com Express 7 Interfaces/PCIe_{B2Bx4}.RX2+")
		(layer "F.Cu")
		(name "$teardrop_padvia$")
		(hatch none 0.1)
		(priority 30243)
		(attr
			(teardrop
				(type padvia)
			)
		)
		(connect_pads yes
			(clearance 0)
		)
		(min_thickness 0.0254)
		(filled_areas_thickness no)
		(fill yes
			(thermal_gap 0.5)
			(thermal_bridge_width 0.5)
			(island_removal_mode 1)
			(island_area_min 10)
		)
		(polygon
			(pts
				(xy 187.9795 162.2) (xy 187.98258 162.214227) (xy 187.984749 162.244527) (xy 187.971877 162.255628)
				(xy 187.941705 162.26) (xy 188.025 163.136) (xy 188.175 162.887021) (xy 188.155644 162.645818) (xy 188.170401 162.373112)
				(xy 188.1815 162.2)
			)
		)
	)
	(zone
		(net 1)
		(net_name "GND")
		(layer "F.Cu")
		(name "$teardrop_padvia$")
		(hatch none 0.1)
		(priority 30604)
		(attr
			(teardrop
				(type padvia)
			)
		)
		(connect_pads yes
			(clearance 0)
		)
		(min_thickness 0.0254)
		(filled_areas_thickness no)
		(fill yes
			(thermal_gap 0.5)
			(thermal_bridge_width 0.5)
			(island_removal_mode 1)
			(island_area_min 10)
		)
		(polygon
			(pts
				(xy 230.625 152.07) (xy 230.621667 152.055514) (xy 230.61881 152.02539) (xy 230.630964 152.014349)
				(xy 230.66 152.01) (xy 230.525 151.134) (xy 230.39 152.01) (xy 230.419334 152.014475) (xy 230.431358 152.025801)
				(xy 230.428333 152.055514) (xy 230.425 152.07)
			)
		)
	)
	(zone
		(net 424)
		(net_name "/2xSFP+/I2C_{SFP1}.SDA")
		(layer "F.Cu")
		(name "$teardrop_padvia$")
		(hatch none 0.1)
		(priority 31091)
		(attr
			(teardrop
				(type padvia)
			)
		)
		(connect_pads yes
			(clearance 0)
		)
		(min_thickness 0.0254)
		(filled_areas_thickness no)
		(fill yes
			(thermal_gap 0.5)
			(thermal_bridge_width 0.5)
			(island_removal_mode 1)
			(island_area_min 10)
		)
		(polygon
			(pts
				(xy 179.293 143.9375) (xy 179.233588 143.917727) (xy 179.177503 143.854453) (xy 179.155801 143.805828)
				(xy 179.141127 143.746468) (xy 179.139347 143.7345) (xy 178.879 144) (xy 179.139347 144.2655) (xy 179.152197 144.205361)
				(xy 179.172131 144.155477) (xy 179.198056 144.115358) (xy 179.227876 144.086345) (xy 179.259294 144.068854)
				(xy 179.291105 144.062521) (xy 179.293 144.0625)
			)
		)
	)
	(zone
		(net 137)
		(net_name "/Com Express 7 MGMT/~{TYPE2}")
		(layer "F.Cu")
		(name "$teardrop_padvia$")
		(hatch none 0.1)
		(priority 30698)
		(attr
			(teardrop
				(type padvia)
			)
		)
		(connect_pads yes
			(clearance 0)
		)
		(min_thickness 0.0254)
		(filled_areas_thickness no)
		(fill yes
			(thermal_gap 0.5)
			(thermal_bridge_width 0.5)
			(island_removal_mode 1)
			(island_area_min 10)
		)
		(polygon
			(pts
				(xy 203.9625 150.2) (xy 203.951563 150.238823) (xy 203.929805 150.253933) (xy 203.89 150.26) (xy 204.025 151.136)
				(xy 204.16 150.26) (xy 204.124719 150.255483) (xy 204.103203 150.243862) (xy 204.088005 150.211039)
				(xy 204.0875 150.2)
			)
		)
	)
	(zone
		(net 279)
		(net_name "/Misc/TACH_{A5V}")
		(layer "F.Cu")
		(name "$teardrop_padvia$")
		(hatch none 0.1)
		(priority 30010)
		(attr
			(teardrop
				(type padvia)
			)
		)
		(connect_pads yes
			(clearance 0)
		)
		(min_thickness 0.0254)
		(filled_areas_thickness no)
		(fill yes
			(thermal_gap 0.5)
			(thermal_bridge_width 0.5)
			(island_removal_mode 1)
			(island_area_min 10)
		)
		(polygon
			(pts
				(xy 262.124456 72.735359) (xy 262.053805 72.637539) (xy 262.00068 72.495936) (xy 261.970678 72.30263)
				(xy 261.972336 72.05536) (xy 262.013612 71.765372) (xy 262.025708 71.71) (xy 261.160001 71.859293)
				(xy 261.329461 72.858379) (xy 261.482568 72.782683) (xy 261.652636 72.740142) (xy 261.738587 72.733309)
				(xy 261.819802 72.736611) (xy 261.892475 72.749312) (xy 261.956587 72.771083) (xy 262.036067 72.823748)
			)
		)
	)
	(zone
		(net 527)
		(net_name "/Backplane/GPIO")
		(layer "F.Cu")
		(name "$teardrop_padvia$")
		(hatch none 0.1)
		(priority 31797)
		(attr
			(teardrop
				(type padvia)
			)
		)
		(connect_pads yes
			(clearance 0)
		)
		(min_thickness 0.0254)
		(filled_areas_thickness no)
		(fill yes
			(thermal_gap 0.5)
			(thermal_bridge_width 0.5)
			(island_removal_mode 1)
			(island_area_min 10)
		)
		(polygon
			(pts
				(xy 311.750677 165.6475) (xy 311.681236 165.642682) (xy 311.629913 165.62896) (xy 311.554371 165.582246)
				(xy 311.542231 165.572701) (xy 311.475003 165.522919) (xy 311.349 165.71) (xy 311.475003 165.897081)
				(xy 311.542229 165.847299) (xy 311.625396 165.792894) (xy 311.678251 165.77781) (xy 311.750677 165.7725)
			)
		)
	)
	(zone
		(net 1)
		(net_name "GND")
		(layer "F.Cu")
		(name "$teardrop_padvia$")
		(hatch none 0.1)
		(priority 31455)
		(attr
			(teardrop
				(type padvia)
			)
		)
		(connect_pads yes
			(clearance 0)
		)
		(min_thickness 0.0254)
		(filled_areas_thickness no)
		(fill yes
			(thermal_gap 0.5)
			(thermal_bridge_width 0.5)
			(island_removal_mode 1)
			(island_area_min 10)
		)
		(polygon
			(pts
				(xy 225.625 150.136768) (xy 225.620303 150.070908) (xy 225.607427 150.01836) (xy 225.562232 149.935871)
				(xy 225.537555 149.904229) (xy 225.494566 149.846605) (xy 225.456578 149.772068) (xy 225.25 149.849)
				(xy 225.206105 150.070677) (xy 225.301353 150.070747) (xy 225.348452 150.067715) (xy 225.387869 150.072607)
				(xy 225.41494 150.093074) (xy 225.425 150.136768)
			)
		)
	)
	(zone
		(net 74)
		(net_name "+1V0")
		(layer "F.Cu")
		(name "$teardrop_padvia$")
		(hatch none 0.1)
		(priority 31249)
		(attr
			(teardrop
				(type padvia)
			)
		)
		(connect_pads yes
			(clearance 0)
		)
		(min_thickness 0.0254)
		(filled_areas_thickness no)
		(fill yes
			(thermal_gap 0.5)
			(thermal_bridge_width 0.5)
			(island_removal_mode 1)
			(island_area_min 10)
		)
		(polygon
			(pts
				(xy 202.257933 72.902163) (xy 202.335845 72.906876) (xy 202.39463 72.919863) (xy 202.485661 72.961965)
				(xy 202.570832 73.004663) (xy 202.65961 72.802163) (xy 202.570832 72.599663) (xy 202.48566 72.642362)
				(xy 202.392827 72.68503) (xy 202.334688 72.697607) (xy 202.257933 72.702163)
			)
		)
	)
	(zone
		(net 430)
		(net_name "/2xSFP+/MDIO0.MDC")
		(layer "F.Cu")
		(name "$teardrop_padvia$")
		(hatch none 0.1)
		(priority 31771)
		(attr
			(teardrop
				(type padvia)
			)
		)
		(connect_pads yes
			(clearance 0)
		)
		(min_thickness 0.0254)
		(filled_areas_thickness no)
		(fill yes
			(thermal_gap 0.5)
			(thermal_bridge_width 0.5)
			(island_removal_mode 1)
			(island_area_min 10)
		)
		(polygon
			(pts
				(xy 144.629323 147.3625) (xy 144.698764 147.367318) (xy 144.750088 147.38104) (xy 144.825629 147.427755)
				(xy 144.837769 147.437299) (xy 144.904997 147.487081) (xy 145.031 147.3) (xy 144.904997 147.112919)
				(xy 144.837768 147.162702) (xy 144.754602 147.217106) (xy 144.701748 147.23219) (xy 144.629323 147.2375)
			)
		)
	)
	(zone
		(net 351)
		(net_name "Net-(J12D-LPC_AD2{slash}ESPI_IO_2)")
		(layer "F.Cu")
		(name "$teardrop_padvia$")
		(hatch none 0.1)
		(priority 31853)
		(attr
			(teardrop
				(type padvia)
			)
		)
		(connect_pads yes
			(clearance 0)
		)
		(min_thickness 0.0254)
		(filled_areas_thickness no)
		(fill yes
			(thermal_gap 0.5)
			(thermal_bridge_width 0.5)
			(island_removal_mode 1)
			(island_area_min 10)
		)
		(polygon
			(pts
				(xy 178.239127 165.372485) (xy 178.186618 165.418181) (xy 178.140623 165.444768) (xy 178.054174 165.465152)
				(xy 178.038841 165.466988) (xy 177.956105 165.479323) (xy 177.999293 165.700707) (xy 178.220677 165.743895)
				(xy 178.233011 165.66116) (xy 178.253349 165.563881) (xy 178.280057 165.515841) (xy 178.327515 165.460873)
			)
		)
	)
	(zone
		(net 11)
		(net_name "/Com Express 7 Interfaces/PCIe_{B1x2}.TX0-")
		(layer "F.Cu")
		(name "$teardrop_padvia$")
		(hatch none 0.1)
		(priority 30363)
		(attr
			(teardrop
				(type padvia)
			)
		)
		(connect_pads yes
			(clearance 0)
		)
		(min_thickness 0.0254)
		(filled_areas_thickness no)
		(fill yes
			(thermal_gap 0.5)
			(thermal_bridge_width 0.5)
			(island_removal_mode 1)
			(island_area_min 10)
		)
		(polygon
			(pts
				(xy 154.4085 79.514) (xy 154.394331 79.517024) (xy 154.363993 79.519052) (xy 154.352878 79.506062)
				(xy 154.3485 79.47572) (xy 153.5725 79.5595) (xy 153.793966 79.7095) (xy 154.007619 79.690152) (xy 154.252972 79.704897)
				(xy 154.4085 79.716)
			)
		)
	)
	(zone
		(net 772)
		(net_name "/Backplane/PCIe_{x2}.RX1-")
		(layer "F.Cu")
		(name "$teardrop_padvia$")
		(hatch none 0.1)
		(priority 31380)
		(attr
			(teardrop
				(type padvia)
			)
		)
		(connect_pads yes
			(clearance 0)
		)
		(min_thickness 0.0254)
		(filled_areas_thickness no)
		(fill yes
			(thermal_gap 0.5)
			(thermal_bridge_width 0.5)
			(island_removal_mode 1)
			(island_area_min 10)
		)
		(polygon
			(pts
				(xy 218.982504 154.9455) (xy 219.02929 154.950235) (xy 219.064742 154.963379) (xy 219.112939 155.008387)
				(xy 219.137116 155.046608) (xy 219.164485 155.089773) (xy 219.201147 155.131731) (xy 219.351 154.9685)
				(xy 219.33014 154.747823) (xy 219.229466 154.752452) (xy 219.146096 154.749019) (xy 219.144035 154.748895)
				(xy 218.982504 154.7435)
			)
		)
	)
	(zone
		(net 84)
		(net_name "/Com Express 7 MGMT/PWRBTN")
		(layer "F.Cu")
		(name "$teardrop_padvia$")
		(hatch none 0.1)
		(priority 30203)
		(attr
			(teardrop
				(type padvia)
			)
		)
		(connect_pads yes
			(clearance 0)
		)
		(min_thickness 0.0254)
		(filled_areas_thickness no)
		(fill yes
			(thermal_gap 0.5)
			(thermal_bridge_width 0.5)
			(island_removal_mode 1)
			(island_area_min 10)
		)
		(polygon
			(pts
				(xy 237.5215 129.21) (xy 237.541221 129.15274) (xy 237.604033 129.100216) (xy 237.652653 129.080449)
				(xy 237.711951 129.067923) (xy 237.729 129.066072) (xy 237.459 128.589) (xy 237.189 129.066072)
				(xy 237.250244 129.076248) (xy 237.301171 129.093925) (xy 237.342014 129.117823) (xy 237.371697 129.146022)
				(xy 237.38963 129.176012) (xy 237.396441 129.206862) (xy 237.3965 129.21)
			)
		)
	)
	(zone
		(net 771)
		(net_name "/Backplane/PCIe_{x2}.RX1+")
		(layer "F.Cu")
		(name "$teardrop_padvia$")
		(hatch none 0.1)
		(priority 31405)
		(attr
			(teardrop
				(type padvia)
			)
		)
		(connect_pads yes
			(clearance 0)
		)
		(min_thickness 0.0254)
		(filled_areas_thickness no)
		(fill yes
			(thermal_gap 0.5)
			(thermal_bridge_width 0.5)
			(island_removal_mode 1)
			(island_area_min 10)
		)
		(polygon
			(pts
				(xy 218.982504 154.5565) (xy 219.144035 154.551105) (xy 219.228445 154.547554) (xy 219.33014 154.552177)
				(xy 219.351 154.3315) (xy 219.201147 154.168268) (xy 219.147007 154.236935) (xy 219.137115 154.253393)
				(xy 219.112615 154.292065) (xy 219.083109 154.324279) (xy 219.041953 154.346327) (xy 218.982504 154.3545)
			)
		)
	)
	(zone
		(net 326)
		(net_name "/Com Express 7 Interfaces/PCIe_{B2Ax4}.TX1+")
		(layer "F.Cu")
		(name "$teardrop_padvia$")
		(hatch none 0.1)
		(priority 31399)
		(attr
			(teardrop
				(type padvia)
			)
		)
		(connect_pads yes
			(clearance 0)
		)
		(min_thickness 0.0254)
		(filled_areas_thickness no)
		(fill yes
			(thermal_gap 0.5)
			(thermal_bridge_width 0.5)
			(island_removal_mode 1)
			(island_area_min 10)
		)
		(polygon
			(pts
				(xy 229.5565 145.367496) (xy 229.551105 145.205964) (xy 229.547555 145.121553) (xy 229.552177 145.019859)
				(xy 229.3315 144.999) (xy 229.168268 145.148852) (xy 229.236936 145.202992) (xy 229.253392 145.212884)
				(xy 229.292064 145.237384) (xy 229.324279 145.26689) (xy 229.346327 145.308046) (xy 229.3545 145.367496)
			)
		)
	)
	(zone
		(net 310)
		(net_name "/Com Express 7 MGMT/~{BIOS_DIS0}")
		(layer "F.Cu")
		(name "$teardrop_padvia$")
		(hatch none 0.1)
		(priority 30863)
		(attr
			(teardrop
				(type padvia)
			)
		)
		(connect_pads yes
			(clearance 0)
		)
		(min_thickness 0.0254)
		(filled_areas_thickness no)
		(fill yes
			(thermal_gap 0.5)
			(thermal_bridge_width 0.5)
			(island_removal_mode 1)
			(island_area_min 10)
		)
		(polygon
			(pts
				(xy 209.832 78.01) (xy 209.791263 78.004228) (xy 209.749348 77.983824) (xy 209.721047 77.956649)
				(xy 209.697618 77.917103) (xy 209.678347 77.8445) (xy 209.418 78.11) (xy 209.678347 78.3755) (xy 209.690214 78.322358)
				(xy 209.708662 78.281319) (xy 209.759336 78.229618) (xy 209.822905 78.210282) (xy 209.832 78.21)
			)
		)
	)
	(zone
		(net 333)
		(net_name "/Com Express 7 Interfaces/SDIO.DAT3")
		(layer "F.Cu")
		(name "$teardrop_padvia$")
		(hatch none 0.1)
		(priority 30626)
		(attr
			(teardrop
				(type padvia)
			)
		)
		(connect_pads yes
			(clearance 0)
		)
		(min_thickness 0.0254)
		(filled_areas_thickness no)
		(fill yes
			(thermal_gap 0.5)
			(thermal_bridge_width 0.5)
			(island_removal_mode 1)
			(island_area_min 10)
		)
		(polygon
			(pts
				(xy 218.116 169.62) (xy 218.114282 169.607584) (xy 218.115106 169.576206) (xy 218.129162 169.56459)
				(xy 218.16 169.56) (xy 218.025 168.684) (xy 217.89 169.56) (xy 217.920565 169.564481) (xy 217.934698 169.575851)
				(xy 217.935718 169.607584) (xy 217.934 169.62)
			)
		)
	)
	(zone
		(net 78)
		(net_name "+1V8")
		(layer "F.Cu")
		(name "$teardrop_padvia$")
		(hatch none 0.1)
		(priority 30219)
		(attr
			(teardrop
				(type padvia)
			)
		)
		(connect_pads yes
			(clearance 0)
		)
		(min_thickness 0.0254)
		(filled_areas_thickness no)
		(fill yes
			(thermal_gap 0.5)
			(thermal_bridge_width 0.5)
			(island_removal_mode 1)
			(island_area_min 10)
		)
		(polygon
			(pts
				(xy 124.532 147.927) (xy 124.52365 147.896391) (xy 124.513039 147.843406) (xy 124.526044 147.820274)
				(xy 124.562 147.803808) (xy 124.382 147.111) (xy 124.202 147.803808) (xy 124.231959 147.815742)
				(xy 124.247272 147.832064) (xy 124.249108 147.869738) (xy 124.24035 147.896391) (xy 124.232 147.927)
			)
		)
	)
	(zone
		(net 588)
		(net_name "/Misc/~{ADDREN}")
		(layer "F.Cu")
		(name "$teardrop_padvia$")
		(hatch none 0.1)
		(priority 30818)
		(attr
			(teardrop
				(type padvia)
			)
		)
		(connect_pads yes
			(clearance 0)
		)
		(min_thickness 0.0254)
		(filled_areas_thickness no)
		(fill yes
			(thermal_gap 0.5)
			(thermal_bridge_width 0.5)
			(island_removal_mode 1)
			(island_area_min 10)
		)
		(polygon
			(pts
				(xy 254.056 82.622499) (xy 254.082609 82.627862) (xy 254.107883 82.645399) (xy 254.125522 82.671693)
				(xy 254.13695 82.709839) (xy 254.14 82.748999) (xy 254.701 82.56) (xy 254.14 82.370999) (xy 254.135373 82.418362)
				(xy 254.122982 82.45341) (xy 254.105123 82.477348) (xy 254.083985 82.491545) (xy 254.056 82.497499)
			)
		)
	)
	(zone
		(net 285)
		(net_name "/2xUSB3.0+RJ45/GbE.MDI3-")
		(layer "F.Cu")
		(name "$teardrop_padvia$")
		(hatch none 0.1)
		(priority 31575)
		(attr
			(teardrop
				(type padvia)
			)
		)
		(connect_pads yes
			(clearance 0)
		)
		(min_thickness 0.0254)
		(filled_areas_thickness no)
		(fill yes
			(thermal_gap 0.5)
			(thermal_bridge_width 0.5)
			(island_removal_mode 1)
			(island_area_min 10)
		)
		(polygon
			(pts
				(xy 135.41204 99.175975) (xy 135.38674 99.155431) (xy 135.340765 99.1148) (xy 135.324885 99.088002)
				(xy 135.32 99.055267) (xy 134.834293 99.029293) (xy 134.852196 99.195) (xy 135.050579 99.196385)
				(xy 135.198309 99.220221) (xy 135.251952 99.242309) (xy 135.296271 99.272914) (xy 135.305975 99.28204)
			)
		)
	)
	(zone
		(net 899)
		(net_name "Net-(D4-C)")
		(layer "F.Cu")
		(name "$teardrop_padvia$")
		(hatch none 0.1)
		(priority 31133)
		(attr
			(teardrop
				(type padvia)
			)
		)
		(connect_pads yes
			(clearance 0)
		)
		(min_thickness 0.0254)
		(filled_areas_thickness no)
		(fill yes
			(thermal_gap 0.5)
			(thermal_bridge_width 0.5)
			(island_removal_mode 1)
			(island_area_min 10)
		)
		(polygon
			(pts
				(xy 154.406 165.4225) (xy 154.465412 165.442273) (xy 154.521497 165.505547) (xy 154.543199 165.554172)
				(xy 154.557873 165.613531) (xy 154.559653 165.6255) (xy 154.82 165.36) (xy 154.559653 165.0945)
				(xy 154.546804 165.154638) (xy 154.52687 165.204522) (xy 154.500945 165.244641) (xy 154.471125 165.273654)
				(xy 154.439707 165.291146) (xy 154.407896 165.297479) (xy 154.406 165.2975)
			)
		)
	)
	(zone
		(net 197)
		(net_name "/OCuLink/PCIe_{x4}.RX3-")
		(layer "F.Cu")
		(name "$teardrop_padvia$")
		(hatch none 0.1)
		(priority 32066)
		(attr
			(teardrop
				(type padvia)
			)
		)
		(connect_pads yes
			(clearance 0)
		)
		(min_thickness 0.0254)
		(filled_areas_thickness no)
		(fill yes
			(thermal_gap 0.5)
			(thermal_bridge_width 0.5)
			(island_removal_mode 1)
			(island_area_min 10)
		)
		(polygon
			(pts
				(xy 106.703 152.91) (xy 106.695802 152.889352) (xy 106.686208 152.857016) (xy 106.693035 152.842993)
				(xy 106.7145 152.833004) (xy 106.602 152.584) (xy 106.4895 152.833004) (xy 106.510676 152.842729)
				(xy 106.517731 152.856357) (xy 106.508198 152.889352) (xy 106.501 152.91)
			)
		)
	)
	(zone
		(net 216)
		(net_name "/Com Express 7 Interfaces/PCIe_{B1x4}.TX2+")
		(layer "F.Cu")
		(name "$teardrop_padvia$")
		(hatch none 0.1)
		(priority 31625)
		(attr
			(teardrop
				(type padvia)
			)
		)
		(connect_pads yes
			(clearance 0)
		)
		(min_thickness 0.0254)
		(filled_areas_thickness no)
		(fill yes
			(thermal_gap 0.5)
			(thermal_bridge_width 0.5)
			(island_removal_mode 1)
			(island_area_min 10)
		)
		(polygon
			(pts
				(xy 206.1815 166.714716) (xy 206.176754 166.657944) (xy 206.163534 166.613244) (xy 206.117846 166.548833)
				(xy 206.067747 166.507397) (xy 206.013795 166.462991) (xy 205.962973 166.402882) (xy 205.774786 166.524214)
				(xy 205.818681 166.745891) (xy 205.894286 166.711091) (xy 205.95403 166.68321) (xy 205.972612 166.688162)
				(xy 205.9795 166.714716)
			)
		)
	)
	(zone
		(net 1)
		(net_name "GND")
		(layer "F.Cu")
		(hatch edge 0.5)
		(priority 17)
		(connect_pads yes
			(clearance 0.15)
		)
		(min_thickness 0.25)
		(filled_areas_thickness no)
		(fill yes
			(thermal_gap 0.2)
			(thermal_bridge_width 0.5)
			(smoothing fillet)
			(radius 0.2)
		)
		(polygon
			(pts
				(xy 303.9 130.46) (xy 306.05 130.46) (xy 306.05 129.61) (xy 303.85 129.61) (xy 303.85 128.795263)
				(xy 304 128.62725) (xy 304 126.41) (xy 302.35 126.41) (xy 302.35 128.56) (xy 302.55 128.76) (xy 302.55 130.51)
				(xy 302.4 130.66) (xy 300.25 130.66) (xy 300.25 131.41) (xy 302.95 131.41)
			)
		)
	)
	(zone
		(net 88)
		(net_name "/Com Express 7 Interfaces/PCIe_{B2Ax4}.RX2-")
		(layer "F.Cu")
		(name "$teardrop_padvia$")
		(hatch none 0.1)
		(priority 31366)
		(attr
			(teardrop
				(type padvia)
			)
		)
		(connect_pads yes
			(clearance 0)
		)
		(min_thickness 0.0254)
		(filled_areas_thickness no)
		(fill yes
			(thermal_gap 0.5)
			(thermal_bridge_width 0.5)
			(island_removal_mode 1)
			(island_area_min 10)
		)
		(polygon
			(pts
				(xy 214.5705 161.867496) (xy 214.575235 161.82071) (xy 214.588379 161.785257) (xy 214.633387 161.73706)
				(xy 214.671608 161.712883) (xy 214.714774 161.685514) (xy 214.756731 161.648852) (xy 214.5935 161.499)
				(xy 214.372823 161.519859) (xy 214.377452 161.620536) (xy 214.374019 161.703908) (xy 214.373895 161.705963)
				(xy 214.3685 161.867496)
			)
		)
	)
	(zone
		(net 1)
		(net_name "GND")
		(layer "F.Cu")
		(name "$teardrop_padvia$")
		(hatch none 0.1)
		(priority 30783)
		(attr
			(teardrop
				(type padvia)
			)
		)
		(connect_pads yes
			(clearance 0)
		)
		(min_thickness 0.0254)
		(filled_areas_thickness no)
		(fill yes
			(thermal_gap 0.5)
			(thermal_bridge_width 0.5)
			(island_removal_mode 1)
			(island_area_min 10)
		)
		(polygon
			(pts
				(xy 304.097677 74.89) (xy 303.940106 74.883069) (xy 303.826578 74.854549) (xy 303.784778 74.8375)
				(xy 303.696 75.04) (xy 303.784778 75.2425) (xy 303.880817 75.208118) (xy 303.982689 75.1929) (xy 304.097677 75.19)
			)
		)
	)
	(zone
		(net 56)
		(net_name "/USB-C console/USB_D-")
		(layer "F.Cu")
		(name "$teardrop_padvia$")
		(hatch none 0.1)
		(priority 30415)
		(attr
			(teardrop
				(type padvia)
			)
		)
		(connect_pads yes
			(clearance 0)
		)
		(min_thickness 0.0254)
		(filled_areas_thickness no)
		(fill yes
			(thermal_gap 0.5)
			(thermal_bridge_width 0.5)
			(island_removal_mode 1)
			(island_area_min 10)
		)
		(polygon
			(pts
				(xy 109.384722 76.1085) (xy 109.410371 76.1178) (xy 109.429624 76.136241) (xy 109.449935 76.199698)
				(xy 109.445234 76.330961) (xy 109.437 76.387106) (xy 109.758 76.296) (xy 109.807183 76.001) (xy 109.682177 75.997221)
				(xy 109.501003 75.953364) (xy 109.384722 75.9235)
			)
		)
	)
	(zone
		(net 288)
		(net_name "/2xUSB3.0+RJ45/~{GBE0_LINK_1000}")
		(layer "F.Cu")
		(name "$teardrop_padvia$")
		(hatch none 0.1)
		(priority 31656)
		(attr
			(teardrop
				(type padvia)
			)
		)
		(connect_pads yes
			(clearance 0)
		)
		(min_thickness 0.0254)
		(filled_areas_thickness no)
		(fill yes
			(thermal_gap 0.5)
			(thermal_bridge_width 0.5)
			(island_removal_mode 1)
			(island_area_min 10)
		)
		(polygon
			(pts
				(xy 145.973005 150.015383) (xy 146.043062 149.938911) (xy 146.087191 149.878166) (xy 146.113482 149.835443)
				(xy 146.181592 149.730491) (xy 146.000707 149.599293) (xy 145.783762 149.654613) (xy 145.817235 149.721244)
				(xy 145.859794 149.770538) (xy 145.892532 149.80774) (xy 145.913499 149.844463) (xy 145.91382 149.883338)
				(xy 145.884617 149.926995)
			)
		)
	)
	(zone
		(net 1)
		(net_name "GND")
		(layer "F.Cu")
		(name "$teardrop_padvia$")
		(hatch none 0.1)
		(priority 30792)
		(attr
			(teardrop
				(type padvia)
			)
		)
		(connect_pads yes
			(clearance 0)
		)
		(min_thickness 0.0254)
		(filled_areas_thickness no)
		(fill yes
			(thermal_gap 0.5)
			(thermal_bridge_width 0.5)
			(island_removal_mode 1)
			(island_area_min 10)
		)
		(polygon
			(pts
				(xy 152.969177 86.4095) (xy 152.811606 86.402569) (xy 152.698078 86.374049) (xy 152.656278 86.357)
				(xy 152.5675 86.5595) (xy 152.656278 86.762) (xy 152.752317 86.727618) (xy 152.854189 86.7124) (xy 152.969177 86.7095)
			)
		)
	)
	(zone
		(net 605)
		(net_name "Net-(U37-~{OE3})")
		(layer "F.Cu")
		(name "$teardrop_padvia$")
		(hatch none 0.1)
		(priority 30940)
		(attr
			(teardrop
				(type padvia)
			)
		)
		(connect_pads yes
			(clearance 0)
		)
		(min_thickness 0.0254)
		(filled_areas_thickness no)
		(fill yes
			(thermal_gap 0.5)
			(thermal_bridge_width 0.5)
			(island_removal_mode 1)
			(island_area_min 10)
		)
		(polygon
			(pts
				(xy 218.868 132.5575) (xy 218.805134 132.537531) (xy 218.773156 132.511079) (xy 218.744642 132.473668)
				(xy 218.722118 132.426473) (xy 218.706907 132.368833) (xy 218.706798 132.368202) (xy 218.429 132.62)
				(xy 218.706798 132.871798) (xy 218.721095 132.816365) (xy 218.742175 132.77048) (xy 218.76954 132.732799)
				(xy 218.800448 132.705566) (xy 218.833735 132.688528) (xy 218.866566 132.682511) (xy 218.868 132.6825)
			)
		)
	)
	(zone
		(net 296)
		(net_name "/2xUSB3.0+RJ45/GbE.CTREF")
		(layer "F.Cu")
		(name "$teardrop_padvia$")
		(hatch none 0.1)
		(priority 31251)
		(attr
			(teardrop
				(type padvia)
			)
		)
		(connect_pads yes
			(clearance 0)
		)
		(min_thickness 0.0254)
		(filled_areas_thickness no)
		(fill yes
			(thermal_gap 0.5)
			(thermal_bridge_width 0.5)
			(island_removal_mode 1)
			(island_area_min 10)
		)
		(polygon
			(pts
				(xy 147.899323 122.9) (xy 147.977235 122.904713) (xy 148.03602 122.9177) (xy 148.127051 122.959802)
				(xy 148.212222 123.0025) (xy 148.301 122.8) (xy 148.212222 122.5975) (xy 148.12705 122.640199) (xy 148.034217 122.682867)
				(xy 147.976078 122.695444) (xy 147.899323 122.7)
			)
		)
	)
	(zone
		(net 160)
		(net_name "/2xUSB3.0+RJ45/USBSS_2.RX-")
		(layer "F.Cu")
		(name "$teardrop_padvia$")
		(hatch none 0.1)
		(priority 31485)
		(attr
			(teardrop
				(type padvia)
			)
		)
		(connect_pads yes
			(clearance 0)
		)
		(min_thickness 0.0254)
		(filled_areas_thickness no)
		(fill yes
			(thermal_gap 0.5)
			(thermal_bridge_width 0.5)
			(island_removal_mode 1)
			(island_area_min 10)
		)
		(polygon
			(pts
				(xy 181.4925 157.965416) (xy 181.48776 158.010027) (xy 181.474582 158.043424) (xy 181.429799 158.087019)
				(xy 181.38718 158.109851) (xy 181.339337 158.135508) (xy 181.293311 158.172104) (xy 181.4525 158.326)
				(xy 181.673177 158.312562) (xy 181.673316 158.129857) (xy 181.6775 157.965416)
			)
		)
	)
	(zone
		(net 989)
		(net_name "Net-(Q14-B)")
		(layer "F.Cu")
		(name "$teardrop_padvia$")
		(hatch none 0.1)
		(priority 30844)
		(attr
			(teardrop
				(type padvia)
			)
		)
		(connect_pads yes
			(clearance 0)
		)
		(min_thickness 0.0254)
		(filled_areas_thickness no)
		(fill yes
			(thermal_gap 0.5)
			(thermal_bridge_width 0.5)
			(island_removal_mode 1)
			(island_area_min 10)
		)
		(polygon
			(pts
				(xy 197.95 82.942) (xy 197.94379 82.988211) (xy 197.920323 83.03661) (xy 197.892416 83.064966) (xy 197.85219 83.088012)
				(xy 197.798202 83.103202) (xy 198.05 83.381) (xy 198.301798 83.103202) (xy 198.252946 83.090069)
				(xy 198.215436 83.070665) (xy 198.168013 83.018055) (xy 198.150257 82.951554) (xy 198.15 82.942)
			)
		)
	)
	(zone
		(net 375)
		(net_name "/2xUSB3.0+RJ45/USB_2.D+")
		(layer "F.Cu")
		(name "$teardrop_padvia$")
		(hatch none 0.1)
		(priority 30297)
		(attr
			(teardrop
				(type padvia)
			)
		)
		(connect_pads yes
			(clearance 0)
		)
		(min_thickness 0.0254)
		(filled_areas_thickness no)
		(fill yes
			(thermal_gap 0.5)
			(thermal_bridge_width 0.5)
			(island_removal_mode 1)
			(island_area_min 10)
		)
		(polygon
			(pts
				(xy 196.8725 162.2) (xy 196.881903 162.373917) (xy 196.894286 162.608968) (xy 196.890781 162.748506)
				(xy 196.875 162.906314) (xy 197.025 163.136) (xy 197.104123 162.26) (xy 197.072384 162.255516) (xy 197.057527 162.244131)
				(xy 197.055915 162.212189) (xy 197.0575 162.2)
			)
		)
	)
	(zone
		(net 532)
		(net_name "/Backplane/PCIe_{x2}.RX0+")
		(layer "F.Cu")
		(name "$teardrop_padvia$")
		(hatch none 0.1)
		(priority 31357)
		(attr
			(teardrop
				(type padvia)
			)
		)
		(connect_pads yes
			(clearance 0)
		)
		(min_thickness 0.0254)
		(filled_areas_thickness no)
		(fill yes
			(thermal_gap 0.5)
			(thermal_bridge_width 0.5)
			(island_removal_mode 1)
			(island_area_min 10)
		)
		(polygon
			(pts
				(xy 271.167496 157.9045) (xy 271.12071 157.899765) (xy 271.085258 157.886621) (xy 271.03706 157.841613)
				(xy 271.012884 157.803392) (xy 270.985514 157.760225) (xy 270.948852 157.718268) (xy 270.799 157.8815)
				(xy 270.81986 158.102177) (xy 270.920531 158.097548) (xy 271.003897 158.10098) (xy 271.005964 158.101105)
				(xy 271.167496 158.1065)
			)
		)
	)
	(zone
		(net 314)
		(net_name "/2xUSB3.0+RJ45/FLG_1")
		(layer "F.Cu")
		(name "$teardrop_padvia$")
		(hatch none 0.1)
		(priority 31847)
		(attr
			(teardrop
				(type padvia)
			)
		)
		(connect_pads yes
			(clearance 0)
		)
		(min_thickness 0.0254)
		(filled_areas_thickness no)
		(fill yes
			(thermal_gap 0.5)
			(thermal_bridge_width 0.5)
			(island_removal_mode 1)
			(island_area_min 10)
		)
		(polygon
			(pts
				(xy 166.239127 158.522485) (xy 166.186618 158.568181) (xy 166.140623 158.594768) (xy 166.054174 158.615152)
				(xy 166.038841 158.616988) (xy 165.956105 158.629323) (xy 165.999293 158.850707) (xy 166.220677 158.893895)
				(xy 166.233011 158.81116) (xy 166.253349 158.713881) (xy 166.280057 158.665841) (xy 166.327515 158.610873)
			)
		)
	)
	(zone
		(net 668)
		(net_name "Net-(Y3-EN)")
		(layer "F.Cu")
		(name "$teardrop_padvia$")
		(hatch none 0.1)
		(priority 30040)
		(attr
			(teardrop
				(type padvia)
			)
		)
		(connect_pads yes
			(clearance 0)
		)
		(min_thickness 0.0254)
		(filled_areas_thickness no)
		(fill yes
			(thermal_gap 0.5)
			(thermal_bridge_width 0.5)
			(island_removal_mode 1)
			(island_area_min 10)
		)
		(polygon
			(pts
				(xy 124.415699 136.474087) (xy 124.482291 136.567785) (xy 124.53334 136.708604) (xy 124.56488 136.911925)
				(xy 124.57 137.186981) (xy 125.030707 137.085707) (xy 125.121992 136.56) (xy 124.99259 136.555037)
				(xy 124.870374 136.540295) (xy 124.763154 136.517385) (xy 124.667128 136.486008) (xy 124.593027 136.45117)
				(xy 124.531176 136.40993) (xy 124.504087 136.385699)
			)
		)
	)
	(zone
		(net 2)
		(net_name "+3V3")
		(layer "F.Cu")
		(name "$teardrop_padvia$")
		(hatch none 0.1)
		(priority 30293)
		(attr
			(teardrop
				(type padvia)
			)
		)
		(connect_pads yes
			(clearance 0)
		)
		(min_thickness 0.0254)
		(filled_areas_thickness no)
		(fill yes
			(thermal_gap 0.5)
			(thermal_bridge_width 0.5)
			(island_removal_mode 1)
			(island_area_min 10)
		)
		(polygon
			(pts
				(xy 236.306707 78.523) (xy 236.316822 78.522847) (xy 236.347539 78.52346) (xy 236.380027 78.531782)
				(xy 236.409182 78.555675) (xy 236.429898 78.603) (xy 237.122707 78.423) (xy 236.429898 78.243) (xy 236.41654 78.278901)
				(xy 236.398308 78.302199) (xy 236.352983 78.321899) (xy 236.316822 78.323153) (xy 236.306707 78.323)
			)
		)
	)
	(zone
		(net 973)
		(net_name "/PCIe redriver/RX_SW")
		(layer "F.Cu")
		(name "$teardrop_padvia$")
		(hatch none 0.1)
		(priority 31022)
		(attr
			(teardrop
				(type padvia)
			)
		)
		(connect_pads yes
			(clearance 0)
		)
		(min_thickness 0.0254)
		(filled_areas_thickness no)
		(fill yes
			(thermal_gap 0.5)
			(thermal_bridge_width 0.5)
			(island_removal_mode 1)
			(island_area_min 10)
		)
		(polygon
			(pts
				(xy 191.650281 129.390715) (xy 191.619949 129.332142) (xy 191.616042 129.290826) (xy 191.622333 129.24421)
				(xy 191.639778 129.194911) (xy 191.66978 129.143398) (xy 191.670149 129.142875) (xy 191.295668 129.12449)
				(xy 191.314053 129.498971) (xy 191.363359 129.469883) (xy 191.41071 129.452344) (xy 191.456705 129.445049)
				(xy 191.497817 129.447648) (xy 191.533402 129.459137) (xy 191.560871 129.478097) (xy 191.561893 129.479103)
			)
		)
	)
	(zone
		(net 1)
		(net_name "GND")
		(layer "F.Cu")
		(hatch edge 0.5)
		(priority 26)
		(connect_pads yes
			(clearance 0.15)
		)
		(min_thickness 0.25)
		(filled_areas_thickness no)
		(fill yes
			(thermal_gap 0.2)
			(thermal_bridge_width 0.5)
			(smoothing fillet)
			(radius 0.2)
		)
		(polygon
			(pts
				(xy 177.45 109.66) (xy 176.299999 109.66) (xy 176.3 111.61) (xy 177.45 111.61)
			)
		)
	)
	(zone
		(net 1)
		(net_name "GND")
		(layer "F.Cu")
		(name "$teardrop_padvia$")
		(hatch none 0.1)
		(priority 30973)
		(attr
			(teardrop
				(type padvia)
			)
		)
		(connect_pads yes
			(clearance 0)
		)
		(min_thickness 0.0254)
		(filled_areas_thickness no)
		(fill yes
			(thermal_gap 0.5)
			(thermal_bridge_width 0.5)
			(island_removal_mode 1)
			(island_area_min 10)
		)
		(polygon
			(pts
				(xy 112.962 149.9425) (xy 113.024866 149.962469) (xy 113.056844 149.988921) (xy 113.085358 150.026332)
				(xy 113.107882 150.073527) (xy 113.123093 150.131167) (xy 113.123202 150.131798) (xy 113.401 149.88)
				(xy 113.123202 149.628202) (xy 113.108905 149.683635) (xy 113.087825 149.72952) (xy 113.06046 149.767201)
				(xy 113.029552 149.794434) (xy 112.996265 149.811472) (xy 112.963434 149.817489) (xy 112.962 149.8175)
			)
		)
	)
	(zone
		(net 1)
		(net_name "GND")
		(layer "F.Cu")
		(name "$teardrop_padvia$")
		(hatch none 0.1)
		(priority 31271)
		(attr
			(teardrop
				(type padvia)
			)
		)
		(connect_pads yes
			(clearance 0)
		)
		(min_thickness 0.0254)
		(filled_areas_thickness no)
		(fill yes
			(thermal_gap 0.5)
			(thermal_bridge_width 0.5)
			(island_removal_mode 1)
			(island_area_min 10)
		)
		(polygon
			(pts
				(xy 188.60861 77.701486) (xy 188.603897 77.779397) (xy 188.59091 77.838181) (xy 188.548809 77.929211)
				(xy 188.50611 78.014384) (xy 188.70861 78.103163) (xy 188.91111 78.014384) (xy 188.868411 77.929213)
				(xy 188.825743 77.83638) (xy 188.813166 77.778241) (xy 188.80861 77.701486)
			)
		)
	)
	(zone
		(net 371)
		(net_name "/Com Express 7 MGMT/I2C.SCL")
		(layer "F.Cu")
		(name "$teardrop_padvia$")
		(hatch none 0.1)
		(priority 32147)
		(attr
			(teardrop
				(type padvia)
			)
		)
		(connect_pads yes
			(clearance 0)
		)
		(min_thickness 0.0254)
		(filled_areas_thickness no)
		(fill yes
			(thermal_gap 0.5)
			(thermal_bridge_width 0.5)
			(island_removal_mode 1)
			(island_area_min 10)
		)
		(polygon
			(pts
				(xy 304.4645 151.280677) (xy 304.459863 151.296742) (xy 304.447404 151.30253) (xy 304.381069 151.282544)
				(xy 304.338635 151.266989) (xy 304.326632 151.268511) (xy 304.3245 151.280677) (xy 304.527 151.241)
				(xy 304.3245 151.280677) (xy 304.351846 151.326057) (xy 304.4161 151.360377) (xy 304.46142 151.368671)
				(xy 304.5062 151.366886) (xy 304.542871 151.355494) (xy 304.571148 151.334001) (xy 304.584638 151.310593)
				(xy 304.5895 151.280677)
			)
		)
	)
	(zone
		(net 1)
		(net_name "GND")
		(layer "F.Cu")
		(name "$teardrop_padvia$")
		(hatch none 0.1)
		(priority 30441)
		(attr
			(teardrop
				(type padvia)
			)
		)
		(connect_pads yes
			(clearance 0)
		)
		(min_thickness 0.0254)
		(filled_areas_thickness no)
		(fill yes
			(thermal_gap 0.5)
			(thermal_bridge_width 0.5)
			(island_removal_mode 1)
			(island_area_min 10)
		)
		(polygon
			(pts
				(xy 190.88539 138.391415) (xy 190.792241 138.371794) (xy 190.681166 138.306) (xy 190.562984 138.187058)
				(xy 190.552633 138.173823) (xy 190.393319 138.432702) (xy 190.573358 138.70621) (xy 190.677755 138.600416)
				(xy 190.735201 138.561887) (xy 190.791992 138.535068) (xy 190.88539 138.516415)
			)
		)
	)
	(zone
		(net 727)
		(net_name "Net-(U43C-PRBS_{PASS})")
		(layer "F.Cu")
		(name "$teardrop_padvia$")
		(hatch none 0.1)
		(priority 30118)
		(attr
			(teardrop
				(type padvia)
			)
		)
		(connect_pads yes
			(clearance 0)
		)
		(min_thickness 0.0254)
		(filled_areas_thickness no)
		(fill yes
			(thermal_gap 0.5)
			(thermal_bridge_width 0.5)
			(island_removal_mode 1)
			(island_area_min 10)
		)
		(polygon
			(pts
				(xy 149.2625 129.377794) (xy 149.267315 129.295733) (xy 149.281019 129.230388) (xy 149.327576 129.13712)
				(xy 149.395787 129.058657) (xy 149.451942 128.997158) (xy 149.511801 128.918339) (xy 149.2 128.709)
				(xy 148.888199 128.918339) (xy 148.985219 129.038517) (xy 149.004214 129.058658) (xy 149.057366 129.117541)
				(xy 149.099591 129.181624) (xy 149.127449 129.264008) (xy 149.1375 129.377794)
			)
		)
	)
	(zone
		(net 600)
		(net_name "Net-(U36-~{HOLD}(D3))")
		(layer "F.Cu")
		(name "$teardrop_padvia$")
		(hatch none 0.1)
		(priority 30066)
		(attr
			(teardrop
				(type padvia)
			)
		)
		(connect_pads yes
			(clearance 0)
		)
		(min_thickness 0.0254)
		(filled_areas_thickness no)
		(fill yes
			(thermal_gap 0.5)
			(thermal_bridge_width 0.5)
			(island_removal_mode 1)
			(island_area_min 10)
		)
		(polygon
			(pts
				(xy 250.277145 162.5025) (xy 250.213453 162.482855) (xy 250.180053 162.456417) (xy 250.149644 162.419306)
				(xy 250.123749 162.371169) (xy 250.104677 162.312767) (xy 250.09955 162.287595) (xy 249.321145 162.565)
				(xy 250.09955 162.842405) (xy 250.114599 162.782714) (xy 250.136615 162.732253) (xy 250.16515 162.68987)
				(xy 250.197591 162.658149) (xy 250.232183 162.637385) (xy 250.266966 162.62803) (xy 250.277145 162.6275)
			)
		)
	)
	(zone
		(net 293)
		(net_name "/2xUSB3.0+RJ45/GbE.MDI1+")
		(layer "F.Cu")
		(name "$teardrop_padvia$")
		(hatch none 0.1)
		(priority 31667)
		(attr
			(teardrop
				(type padvia)
			)
		)
		(connect_pads yes
			(clearance 0)
		)
		(min_thickness 0.0254)
		(filled_areas_thickness no)
		(fill yes
			(thermal_gap 0.5)
			(thermal_bridge_width 0.5)
			(island_removal_mode 1)
			(island_area_min 10)
		)
		(polygon
			(pts
				(xy 135.368285 103.4425) (xy 135.279515 103.495168) (xy 135.141927 103.529425) (xy 134.943559 103.536903)
				(xy 134.907856 103.535) (xy 134.894 103.705) (xy 135.32 103.701111) (xy 135.324053 103.657657) (xy 135.335356 103.628275)
				(xy 135.364468 103.595844) (xy 135.368285 103.5925)
			)
		)
	)
	(zone
		(net 90)
		(net_name "/Com Express 7 Interfaces/PCIe_{B2Ax4}.RX0+")
		(layer "F.Cu")
		(name "$teardrop_padvia$")
		(hatch none 0.1)
		(priority 31346)
		(attr
			(teardrop
				(type padvia)
			)
		)
		(connect_pads yes
			(clearance 0)
		)
		(min_thickness 0.0254)
		(filled_areas_thickness no)
		(fill yes
			(thermal_gap 0.5)
			(thermal_bridge_width 0.5)
			(island_removal_mode 1)
			(island_area_min 10)
		)
		(polygon
			(pts
				(xy 296.153 75.019852) (xy 296.148265 75.066638) (xy 296.135121 75.10209) (xy 296.090113 75.150287)
				(xy 296.051893 75.174463) (xy 296.008726 75.201832) (xy 295.966768 75.238495) (xy 296.13 75.388348)
				(xy 296.350677 75.367488) (xy 296.346048 75.266817) (xy 296.34948 75.18345) (xy 296.349605 75.181383)
				(xy 296.355 75.019852)
			)
		)
	)
	(zone
		(net 528)
		(net_name "/Backplane/~{PERST}")
		(layer "F.Cu")
		(name "$teardrop_padvia$")
		(hatch none 0.1)
		(priority 31768)
		(attr
			(teardrop
				(type padvia)
			)
		)
		(connect_pads yes
			(clearance 0)
		)
		(min_thickness 0.0254)
		(filled_areas_thickness no)
		(fill yes
			(thermal_gap 0.5)
			(thermal_bridge_width 0.5)
			(island_removal_mode 1)
			(island_area_min 10)
		)
		(polygon
			(pts
				(xy 290.724323 102.9225) (xy 290.793764 102.927318) (xy 290.845088 102.94104) (xy 290.920629 102.987755)
				(xy 290.932769 102.997299) (xy 290.999997 103.047081) (xy 291.126 102.86) (xy 290.999997 102.672919)
				(xy 290.932768 102.722702) (xy 290.849602 102.777106) (xy 290.796748 102.79219) (xy 290.724323 102.7975)
			)
		)
	)
	(zone
		(net 73)
		(net_name "+3V3_AON")
		(layer "F.Cu")
		(name "$teardrop_padvia$")
		(hatch none 0.1)
		(priority 30198)
		(attr
			(teardrop
				(type padvia)
			)
		)
		(connect_pads yes
			(clearance 0)
		)
		(min_thickness 0.0254)
		(filled_areas_thickness no)
		(fill yes
			(thermal_gap 0.5)
			(thermal_bridge_width 0.5)
			(island_removal_mode 1)
			(island_area_min 10)
		)
		(polygon
			(pts
				(xy 302.402 90.496111) (xy 302.385366 90.42611) (xy 302.356424 90.361704) (xy 302.304644 90.230194)
				(xy 302.297679 90.16222) (xy 302.315002 90.0949) (xy 302.020002 90.059) (xy 301.851704 90.375863)
				(xy 301.90882 90.380895) (xy 301.943099 90.39359) (xy 301.957994 90.408584) (xy 301.963479 90.426196)
				(xy 301.957247 90.468443) (xy 301.952 90.496111)
			)
		)
	)
	(zone
		(net 322)
		(net_name "/Com Express 7 Interfaces/SDIO.DAT1")
		(layer "F.Cu")
		(name "$teardrop_padvia$")
		(hatch none 0.1)
		(priority 31331)
		(attr
			(teardrop
				(type padvia)
			)
		)
		(connect_pads yes
			(clearance 0)
		)
		(min_thickness 0.0254)
		(filled_areas_thickness no)
		(fill yes
			(thermal_gap 0.5)
			(thermal_bridge_width 0.5)
			(island_removal_mode 1)
			(island_area_min 10)
		)
		(polygon
			(pts
				(xy 206.909 169.449323) (xy 206.904302 169.522825) (xy 206.891413 169.578637) (xy 206.846871 169.668627)
				(xy 206.7975 169.762221) (xy 207 169.851) (xy 207.2025 169.762221) (xy 207.153129 169.668629) (xy 207.109048 169.580015)
				(xy 207.095826 169.523711) (xy 207.091 169.449323)
			)
		)
	)
	(zone
		(net 976)
		(net_name "/PCIe redriver/RX_EQ2")
		(layer "F.Cu")
		(name "$teardrop_padvia$")
		(hatch none 0.1)
		(priority 31723)
		(attr
			(teardrop
				(type padvia)
			)
		)
		(connect_pads yes
			(clearance 0)
		)
		(min_thickness 0.0254)
		(filled_areas_thickness no)
		(fill yes
			(thermal_gap 0.5)
			(thermal_bridge_width 0.5)
			(island_removal_mode 1)
			(island_area_min 10)
		)
		(polygon
			(pts
				(xy 188.4375 136.649323) (xy 188.432682 136.718763) (xy 188.41896 136.770087) (xy 188.372245 136.845628)
				(xy 188.362702 136.857768) (xy 188.312919 136.924997) (xy 188.5 137.051) (xy 188.687081 136.924997)
				(xy 188.637299 136.857769) (xy 188.582894 136.774603) (xy 188.56781 136.721748) (xy 188.5625 136.649323)
			)
		)
	)
	(zone
		(net 954)
		(net_name "/2xSFP+/KR to SFI #1/BYP_TX+")
		(layer "F.Cu")
		(name "$teardrop_padvia$")
		(hatch none 0.1)
		(priority 31945)
		(attr
			(teardrop
				(type padvia)
			)
		)
		(connect_pads yes
			(clearance 0)
		)
		(min_thickness 0.0254)
		(filled_areas_thickness no)
		(fill yes
			(thermal_gap 0.5)
			(thermal_bridge_width 0.5)
			(island_removal_mode 1)
			(island_area_min 10)
		)
		(polygon
			(pts
				(xy 147.22 148.527721) (xy 147.231736 148.504685) (xy 147.254198 148.488987) (xy 147.330557 148.479864)
				(xy 147.388769 148.485) (xy 147.33 148.254) (xy 147.13 148.226463) (xy 147.125648 148.325256) (xy 147.084062 148.458347)
				(xy 147.06 148.527721)
			)
		)
	)
	(zone
		(net 254)
		(net_name "/Com Express 7 Interfaces/PCIe_{B2Bx4}.RX1+")
		(layer "F.Cu")
		(name "$teardrop_padvia$")
		(hatch none 0.1)
		(priority 30245)
		(attr
			(teardrop
				(type padvia)
			)
		)
		(connect_pads yes
			(clearance 0)
		)
		(min_thickness 0.0254)
		(filled_areas_thickness no)
		(fill yes
			(thermal_gap 0.5)
			(thermal_bridge_width 0.5)
			(island_removal_mode 1)
			(island_area_min 10)
		)
		(polygon
			(pts
				(xy 193.4795 162.2) (xy 193.48258 162.214227) (xy 193.484749 162.244527) (xy 193.471877 162.255628)
				(xy 193.441705 162.26) (xy 193.525 163.136) (xy 193.675 162.887021) (xy 193.655644 162.645818) (xy 193.670401 162.373112)
				(xy 193.6815 162.2)
			)
		)
	)
	(zone
		(net 771)
		(net_name "/Backplane/PCIe_{x2}.RX1+")
		(layer "F.Cu")
		(name "$teardrop_padvia$")
		(hatch none 0.1)
		(priority 32031)
		(attr
			(teardrop
				(type padvia)
			)
		)
		(connect_pads yes
			(clearance 0)
		)
		(min_thickness 0.0254)
		(filled_areas_thickness no)
		(fill yes
			(thermal_gap 0.5)
			(thermal_bridge_width 0.5)
			(island_removal_mode 1)
			(island_area_min 10)
		)
		(polygon
			(pts
				(xy 315.47923 161.370629) (xy 315.459675 161.374589) (xy 315.426626 161.379092) (xy 315.414683 161.369686)
				(xy 315.41 161.345757) (xy 315.13402 161.407805) (xy 315.190196 161.533) (xy 315.275918 161.523871)
				(xy 315.374725 161.550063) (xy 315.439835 161.568749)
			)
		)
	)
	(zone
		(net 892)
		(net_name "Net-(D14-A)")
		(layer "F.Cu")
		(name "$teardrop_padvia$")
		(hatch none 0.1)
		(priority 31100)
		(attr
			(teardrop
				(type padvia)
			)
		)
		(connect_pads yes
			(clearance 0)
		)
		(min_thickness 0.0254)
		(filled_areas_thickness no)
		(fill yes
			(thermal_gap 0.5)
			(thermal_bridge_width 0.5)
			(island_removal_mode 1)
			(island_area_min 10)
		)
		(polygon
			(pts
				(xy 283.2975 77.167) (xy 283.277727 77.226412) (xy 283.214453 77.282496) (xy 283.165828 77.304198)
				(xy 283.106469 77.318872) (xy 283.0945 77.320652) (xy 283.36 77.581) (xy 283.6255 77.320652) (xy 283.565362 77.307803)
				(xy 283.515478 77.287869) (xy 283.475358 77.261944) (xy 283.446345 77.232124) (xy 283.428854 77.200706)
				(xy 283.422521 77.168895) (xy 283.4225 77.167)
			)
		)
	)
	(zone
		(net 188)
		(net_name "/OCuLink/PCIe_{x4}.RX1+")
		(layer "F.Cu")
		(name "$teardrop_padvia$")
		(hatch none 0.1)
		(priority 32089)
		(attr
			(teardrop
				(type padvia)
			)
		)
		(connect_pads yes
			(clearance 0)
		)
		(min_thickness 0.0254)
		(filled_areas_thickness no)
		(fill yes
			(thermal_gap 0.5)
			(thermal_bridge_width 0.5)
			(island_removal_mode 1)
			(island_area_min 10)
		)
		(polygon
			(pts
				(xy 97.899 151.147) (xy 97.906198 151.167648) (xy 97.915792 151.199984) (xy 97.908965 151.214007)
				(xy 97.8875 151.223995) (xy 98 151.473) (xy 98.1125 151.223995) (xy 98.091324 151.214271) (xy 98.084269 151.200643)
				(xy 98.093802 151.167648) (xy 98.101 151.147)
			)
		)
	)
	(zone
		(net 491)
		(net_name "/2xSFP+/MDIO0.MDIO")
		(layer "F.Cu")
		(name "$teardrop_padvia$")
		(hatch none 0.1)
		(priority 30684)
		(attr
			(teardrop
				(type padvia)
			)
		)
		(connect_pads yes
			(clearance 0)
		)
		(min_thickness 0.0254)
		(filled_areas_thickness no)
		(fill yes
			(thermal_gap 0.5)
			(thermal_bridge_width 0.5)
			(island_removal_mode 1)
			(island_area_min 10)
		)
		(polygon
			(pts
				(xy 198.4625 150.2) (xy 198.451563 150.238823) (xy 198.429805 150.253933) (xy 198.39 150.26) (xy 198.525 151.136)
				(xy 198.66 150.26) (xy 198.624719 150.255483) (xy 198.603203 150.243862) (xy 198.588005 150.211039)
				(xy 198.5875 150.2)
			)
		)
	)
	(zone
		(net 731)
		(net_name "Net-(U43C-CLKOUTA-)")
		(layer "F.Cu")
		(name "$teardrop_padvia$")
		(hatch none 0.1)
		(priority 30114)
		(attr
			(teardrop
				(type padvia)
			)
		)
		(connect_pads yes
			(clearance 0)
		)
		(min_thickness 0.0254)
		(filled_areas_thickness no)
		(fill yes
			(thermal_gap 0.5)
			(thermal_bridge_width 0.5)
			(island_removal_mode 1)
			(island_area_min 10)
		)
		(polygon
			(pts
				(xy 148.6125 130.227794) (xy 148.617315 130.145733) (xy 148.631019 130.080388) (xy 148.677576 129.98712)
				(xy 148.745787 129.908657) (xy 148.801942 129.847158) (xy 148.861801 129.768339) (xy 148.55 129.559)
				(xy 148.238199 129.768339) (xy 148.335219 129.888517) (xy 148.354214 129.908658) (xy 148.407366 129.967541)
				(xy 148.449591 130.031624) (xy 148.477449 130.114008) (xy 148.4875 130.227794)
			)
		)
	)
	(zone
		(net 386)
		(net_name "/Com Express 7 Interfaces/SD_WP")
		(layer "F.Cu")
		(name "$teardrop_padvia$")
		(hatch none 0.1)
		(priority 31621)
		(attr
			(teardrop
				(type padvia)
			)
		)
		(connect_pads yes
			(clearance 0)
		)
		(min_thickness 0.0254)
		(filled_areas_thickness no)
		(fill yes
			(thermal_gap 0.5)
			(thermal_bridge_width 0.5)
			(island_removal_mode 1)
			(island_area_min 10)
		)
		(polygon
			(pts
				(xy 203.87338 162.261767) (xy 203.888571 162.261179) (xy 203.875 162.26) (xy 204.025707 163.135707)
				(xy 204.058503 162.26) (xy 204.017672 162.243537) (xy 203.981752 162.199689) (xy 203.961767 162.17338)
			)
		)
	)
	(zone
		(net 700)
		(net_name "/USB-C console/FTDI_TX")
		(layer "F.Cu")
		(name "$teardrop_padvia$")
		(hatch none 0.1)
		(priority 31636)
		(attr
			(teardrop
				(type padvia)
			)
		)
		(connect_pads yes
			(clearance 0)
		)
		(min_thickness 0.0254)
		(filled_areas_thickness no)
		(fill yes
			(thermal_gap 0.5)
			(thermal_bridge_width 0.5)
			(island_removal_mode 1)
			(island_area_min 10)
		)
		(polygon
			(pts
				(xy 117.539999 75.4375) (xy 117.512927 75.431978) (xy 117.487388 75.413322) (xy 117.471219 75.386703)
				(xy 117.4616 75.347962) (xy 117.459999 75.32) (xy 117.058999 75.5) (xy 117.459999 75.68) (xy 117.464612 75.6345)
				(xy 117.476899 75.601532) (xy 117.515054 75.567156) (xy 117.539999 75.5625)
			)
		)
	)
	(zone
		(net 270)
		(net_name "/M.2 key M #2/~{PERST_D}")
		(layer "F.Cu")
		(name "$teardrop_padvia$")
		(hatch none 0.1)
		(priority 30857)
		(attr
			(teardrop
				(type padvia)
			)
		)
		(connect_pads yes
			(clearance 0)
		)
		(min_thickness 0.0254)
		(filled_areas_thickness no)
		(fill yes
			(thermal_gap 0.5)
			(thermal_bridge_width 0.5)
			(island_removal_mode 1)
			(island_area_min 10)
		)
		(polygon
			(pts
				(xy 298.5115 82.418) (xy 298.522438 82.379177) (xy 298.544195 82.364067) (xy 298.584 82.358) (xy 298.449 81.582)
				(xy 298.314 82.358) (xy 298.349281 82.362517) (xy 298.370797 82.374138) (xy 298.385995 82.406961)
				(xy 298.3865 82.418)
			)
		)
	)
	(zone
		(net 277)
		(net_name "Net-(J8-SUSCLK)")
		(layer "F.Cu")
		(name "$teardrop_padvia$")
		(hatch none 0.1)
		(priority 30858)
		(attr
			(teardrop
				(type padvia)
			)
		)
		(connect_pads yes
			(clearance 0)
		)
		(min_thickness 0.0254)
		(filled_areas_thickness no)
		(fill yes
			(thermal_gap 0.5)
			(thermal_bridge_width 0.5)
			(island_removal_mode 1)
			(island_area_min 10)
		)
		(polygon
			(pts
				(xy 303.0105 82.418) (xy 303.021438 82.379177) (xy 303.043195 82.364067) (xy 303.083 82.358) (xy 302.948 81.582)
				(xy 302.813 82.358) (xy 302.848281 82.362517) (xy 302.869797 82.374138) (xy 302.884995 82.406961)
				(xy 302.8855 82.418)
			)
		)
	)
	(zone
		(net 286)
		(net_name "/2xUSB3.0+RJ45/GbE.MDI3+")
		(layer "F.Cu")
		(name "$teardrop_padvia$")
		(hatch none 0.1)
		(priority 31639)
		(attr
			(teardrop
				(type padvia)
			)
		)
		(connect_pads yes
			(clearance 0)
		)
		(min_thickness 0.0254)
		(filled_areas_thickness no)
		(fill yes
			(thermal_gap 0.5)
			(thermal_bridge_width 0.5)
			(island_removal_mode 1)
			(island_area_min 10)
		)
		(polygon
			(pts
				(xy 177.025 167.742084) (xy 177.029756 167.702162) (xy 177.04305 167.673745) (xy 177.087129 167.641329)
				(xy 177.132262 167.62605) (xy 177.178541 167.610756) (xy 177.225003 167.587081) (xy 177.1 167.399)
				(xy 176.879323 167.398242) (xy 176.877203 167.536699) (xy 176.875 167.742084)
			)
		)
	)
	(zone
		(net 984)
		(net_name "Net-(D32-C)")
		(layer "F.Cu")
		(name "$teardrop_padvia$")
		(hatch none 0.1)
		(priority 30886)
		(attr
			(teardrop
				(type padvia)
			)
		)
		(connect_pads yes
			(clearance 0)
		)
		(min_thickness 0.0254)
		(filled_areas_thickness no)
		(fill yes
			(thermal_gap 0.5)
			(thermal_bridge_width 0.5)
			(island_removal_mode 1)
			(island_area_min 10)
		)
		(polygon
			(pts
				(xy 193.60861 76.259163) (xy 193.602838 76.2999) (xy 193.582434 76.341815) (xy 193.555259 76.370116)
				(xy 193.515713 76.393544) (xy 193.44311 76.412815) (xy 193.70861 76.673163) (xy 193.97411 76.412815)
				(xy 193.920968 76.400948) (xy 193.879929 76.382501) (xy 193.828228 76.331827) (xy 193.808892 76.268258)
				(xy 193.80861 76.259163)
			)
		)
	)
	(zone
		(net 401)
		(net_name "/Com Express 7 MGMT/FAM_TACH")
		(layer "F.Cu")
		(name "$teardrop_padvia$")
		(hatch none 0.1)
		(priority 30352)
		(attr
			(teardrop
				(type padvia)
			)
		)
		(connect_pads yes
			(clearance 0)
		)
		(min_thickness 0.0254)
		(filled_areas_thickness no)
		(fill yes
			(thermal_gap 0.5)
			(thermal_bridge_width 0.5)
			(island_removal_mode 1)
			(island_area_min 10)
		)
		(polygon
			(pts
				(xy 236.306707 79.1345) (xy 236.34057 79.140281) (xy 236.375191 79.160745) (xy 236.397013 79.18781)
				(xy 236.412707 79.22715) (xy 236.415996 79.242711) (xy 237.122707 79.072) (xy 236.415996 78.901289)
				(xy 236.404407 78.94151) (xy 236.386823 78.970984) (xy 236.339241 79.004173) (xy 236.306707 79.0095)
			)
		)
	)
	(zone
		(net 231)
		(net_name "/M.2 key M #1/PCIE_{REF}.CK+")
		(layer "F.Cu")
		(name "$teardrop_padvia$")
		(hatch none 0.1)
		(priority 31353)
		(attr
			(teardrop
				(type padvia)
			)
		)
		(connect_pads yes
			(clearance 0)
		)
		(min_thickness 0.0254)
		(filled_areas_thickness no)
		(fill yes
			(thermal_gap 0.5)
			(thermal_bridge_width 0.5)
			(island_removal_mode 1)
			(island_area_min 10)
		)
		(polygon
			(pts
				(xy 207.767496 128.0245) (xy 207.72071 128.019765) (xy 207.685258 128.006621) (xy 207.63706 127.961613)
				(xy 207.612884 127.923392) (xy 207.585514 127.880225) (xy 207.548852 127.838268) (xy 207.399 128.0015)
				(xy 207.41986 128.222177) (xy 207.520531 128.217548) (xy 207.603897 128.22098) (xy 207.605964 128.221105)
				(xy 207.767496 128.2265)
			)
		)
	)
	(zone
		(net 1)
		(net_name "GND")
		(layer "F.Cu")
		(name "$teardrop_padvia$")
		(hatch none 0.1)
		(priority 31317)
		(attr
			(teardrop
				(type padvia)
			)
		)
		(connect_pads yes
			(clearance 0)
		)
		(min_thickness 0.0254)
		(filled_areas_thickness no)
		(fill yes
			(thermal_gap 0.5)
			(thermal_bridge_width 0.5)
			(island_removal_mode 1)
			(island_area_min 10)
		)
		(polygon
			(pts
				(xy 184.425 151.862207) (xy 184.420269 151.917803) (xy 184.40715 151.960353) (xy 184.361978 152.022225)
				(xy 184.338296 152.044609) (xy 184.269305 152.11861) (xy 184.45 152.251) (xy 184.666731 152.196578)
				(xy 184.664817 152.188815) (xy 184.633194 152.039946) (xy 184.625 151.862207)
			)
		)
	)
	(zone
		(net 688)
		(net_name "/2xSFP+/KR to SFI #2/KR_R.RX-")
		(layer "F.Cu")
		(name "$teardrop_padvia$")
		(hatch none 0.1)
		(priority 31177)
		(attr
			(teardrop
				(type padvia)
			)
		)
		(connect_pads yes
			(clearance 0)
		)
		(min_thickness 0.0254)
		(filled_areas_thickness no)
		(fill yes
			(thermal_gap 0.5)
			(thermal_bridge_width 0.5)
			(island_removal_mode 1)
			(island_area_min 10)
		)
		(polygon
			(pts
				(xy 134.68 143.17679) (xy 134.675347 143.112802) (xy 134.662777 143.062121) (xy 134.618645 142.980204)
				(xy 134.607609 142.964616) (xy 134.566024 142.899819) (xy 134.535196 142.811227) (xy 134.29 142.859)
				(xy 134.241227 143.105196) (xy 134.328185 143.107002) (xy 134.371073 143.101889) (xy 134.428443 143.095867)
				(xy 134.475848 143.099993) (xy 134.508097 143.123792) (xy 134.52 143.17679)
			)
		)
	)
	(zone
		(net 73)
		(net_name "+3V3_AON")
		(layer "F.Cu")
		(name "$teardrop_padvia$")
		(hatch none 0.1)
		(priority 30325)
		(attr
			(teardrop
				(type padvia)
			)
		)
		(connect_pads yes
			(clearance 0)
		)
		(min_thickness 0.0254)
		(filled_areas_thickness no)
		(fill yes
			(thermal_gap 0.5)
			(thermal_bridge_width 0.5)
			(island_removal_mode 1)
			(island_area_min 10)
		)
		(polygon
			(pts
				(xy 253.864 127.234248) (xy 253.89063 127.239259) (xy 253.916148 127.254332) (xy 253.939358 127.280202)
				(xy 253.957909 127.316717) (xy 253.974 127.417178) (xy 254.475 127.16) (xy 253.974 126.922087) (xy 253.969296 126.981244)
				(xy 253.956366 127.029191) (xy 253.937063 127.065824) (xy 253.91311 127.091335) (xy 253.864 127.109248)
			)
		)
	)
	(zone
		(net 756)
		(net_name "Net-(U45A-LS_OK_{OUT_A})")
		(layer "F.Cu")
		(name "$teardrop_padvia$")
		(hatch none 0.1)
		(priority 30124)
		(attr
			(teardrop
				(type padvia)
			)
		)
		(connect_pads yes
			(clearance 0)
		)
		(min_thickness 0.0254)
		(filled_areas_thickness no)
		(fill yes
			(thermal_gap 0.5)
			(thermal_bridge_width 0.5)
			(island_removal_mode 1)
			(island_area_min 10)
		)
		(polygon
			(pts
				(xy 132.4025 129.377794) (xy 132.407315 129.295733) (xy 132.421019 129.230388) (xy 132.467576 129.13712)
				(xy 132.535787 129.058657) (xy 132.591942 128.997158) (xy 132.651801 128.918339) (xy 132.34 128.709)
				(xy 132.028199 128.918339) (xy 132.125219 129.038517) (xy 132.144214 129.058658) (xy 132.197366 129.117541)
				(xy 132.239591 129.181624) (xy 132.267449 129.264008) (xy 132.2775 129.377794)
			)
		)
	)
	(zone
		(net 771)
		(net_name "/Backplane/PCIe_{x2}.RX1+")
		(layer "F.Cu")
		(name "$teardrop_padvia$")
		(hatch none 0.1)
		(priority 30250)
		(attr
			(teardrop
				(type padvia)
			)
		)
		(connect_pads yes
			(clearance 0)
		)
		(min_thickness 0.0254)
		(filled_areas_thickness no)
		(fill yes
			(thermal_gap 0.5)
			(thermal_bridge_width 0.5)
			(island_removal_mode 1)
			(island_area_min 10)
		)
		(polygon
			(pts
				(xy 202.9795 155.75) (xy 202.98258 155.764227) (xy 202.984749 155.794527) (xy 202.971877 155.805628)
				(xy 202.941705 155.81) (xy 203.025 156.686) (xy 203.175 156.437021) (xy 203.155644 156.195818) (xy 203.170401 155.923112)
				(xy 203.1815 155.75)
			)
		)
	)
	(zone
		(net 525)
		(net_name "Net-(J14-Pad2)")
		(layer "F.Cu")
		(name "$teardrop_padvia$")
		(hatch none 0.1)
		(priority 30849)
		(attr
			(teardrop
				(type padvia)
			)
		)
		(connect_pads yes
			(clearance 0)
		)
		(min_thickness 0.0254)
		(filled_areas_thickness no)
		(fill yes
			(thermal_gap 0.5)
			(thermal_bridge_width 0.5)
			(island_removal_mode 1)
			(island_area_min 10)
		)
		(polygon
			(pts
				(xy 208.359 77.672) (xy 208.35279 77.718211) (xy 208.329323 77.76661) (xy 208.301416 77.794966)
				(xy 208.26119 77.818012) (xy 208.207202 77.833202) (xy 208.459 78.111) (xy 208.710798 77.833202)
				(xy 208.661946 77.820069) (xy 208.624436 77.800665) (xy 208.577013 77.748055) (xy 208.559257 77.681554)
				(xy 208.559 77.672)
			)
		)
	)
	(zone
		(net 1)
		(net_name "GND")
		(layer "F.Cu")
		(hatch edge 0.5)
		(priority 1)
		(connect_pads
			(clearance 0.15)
		)
		(min_thickness 0.25)
		(filled_areas_thickness no)
		(fill yes
			(thermal_gap 0.15)
			(thermal_bridge_width 0.3)
		)
		(polygon
			(pts
				(xy 190.624836 137.673269) (xy 191.862273 138.910706) (xy 196.557462 134.215517) (xy 195.320026 132.97808)
			)
		)
	)
	(zone
		(net 2)
		(net_name "+3V3")
		(layer "F.Cu")
		(name "$teardrop_padvia$")
		(hatch none 0.1)
		(priority 31748)
		(attr
			(teardrop
				(type padvia)
			)
		)
		(connect_pads yes
			(clearance 0)
		)
		(min_thickness 0.0254)
		(filled_areas_thickness no)
		(fill yes
			(thermal_gap 0.5)
			(thermal_bridge_width 0.5)
			(island_removal_mode 1)
			(island_area_min 10)
		)
		(polygon
			(pts
				(xy 138.749323 157.1725) (xy 138.818764 157.177318) (xy 138.870088 157.19104) (xy 138.945629 157.237755)
				(xy 138.957769 157.247299) (xy 139.024997 157.297081) (xy 139.151 157.11) (xy 139.024997 156.922919)
				(xy 138.957768 156.972702) (xy 138.874602 157.027106) (xy 138.821748 157.04219) (xy 138.749323 157.0475)
			)
		)
	)
	(zone
		(net 1)
		(net_name "GND")
		(layer "F.Cu")
		(name "$teardrop_padvia$")
		(hatch none 0.1)
		(priority 31237)
		(attr
			(teardrop
				(type padvia)
			)
		)
		(connect_pads yes
			(clearance 0)
		)
		(min_thickness 0.0254)
		(filled_areas_thickness no)
		(fill yes
			(thermal_gap 0.5)
			(thermal_bridge_width 0.5)
			(island_removal_mode 1)
			(island_area_min 10)
		)
		(polygon
			(pts
				(xy 217.125 162.000677) (xy 217.129737 161.909676) (xy 217.142896 161.842587) (xy 217.175418 161.755855)
				(xy 217.207644 161.675358) (xy 217 161.599) (xy 216.803541 161.702363) (xy 216.855343 161.785863)
				(xy 216.904833 161.871955) (xy 216.919614 161.92716) (xy 216.925 162.000677)
			)
		)
	)
	(zone
		(net 73)
		(net_name "+3V3_AON")
		(layer "F.Cu")
		(name "$teardrop_padvia$")
		(hatch none 0.1)
		(priority 30081)
		(attr
			(teardrop
				(type padvia)
			)
		)
		(connect_pads yes
			(clearance 0)
		)
		(min_thickness 0.0254)
		(filled_areas_thickness no)
		(fill yes
			(thermal_gap 0.5)
			(thermal_bridge_width 0.5)
			(island_removal_mode 1)
			(island_area_min 10)
		)
		(polygon
			(pts
				(xy 190.80861 73.469957) (xy 190.813461 73.37858) (xy 190.827419 73.306651) (xy 190.87436 73.2051)
				(xy 190.93378 73.126257) (xy 191.020411 73.010502) (xy 190.70861 72.801163) (xy 190.396809 73.010502)
				(xy 190.48344 73.126258) (xy 190.53478 73.19314) (xy 190.574276 73.262875) (xy 190.599646 73.350226)
				(xy 190.60861 73.469957)
			)
		)
	)
	(zone
		(net 1)
		(net_name "GND")
		(layer "F.Cu")
		(name "$teardrop_padvia$")
		(hatch none 0.1)
		(priority 31019)
		(attr
			(teardrop
				(type padvia)
			)
		)
		(connect_pads yes
			(clearance 0)
		)
		(min_thickness 0.0254)
		(filled_areas_thickness no)
		(fill yes
			(thermal_gap 0.5)
			(thermal_bridge_width 0.5)
			(island_removal_mode 1)
			(island_area_min 10)
		)
		(polygon
			(pts
				(xy 192.984806 141.577558) (xy 193.043379 141.547226) (xy 193.084695 141.543319) (xy 193.131311 141.54961)
				(xy 193.18061 141.567055) (xy 193.232123 141.597057) (xy 193.232646 141.597426) (xy 193.251031 141.222945)
				(xy 192.87655 141.24133) (xy 192.905638 141.290636) (xy 192.923177 141.337987) (xy 192.930472 141.383982)
				(xy 192.927873 141.425094) (xy 192.916384 141.460679) (xy 192.897424 141.488148) (xy 192.896418 141.48917)
			)
		)
	)
	(zone
		(net 753)
		(net_name "Net-(U45C-CLKOUTB-)")
		(layer "F.Cu")
		(name "$teardrop_padvia$")
		(hatch none 0.1)
		(priority 30139)
		(attr
			(teardrop
				(type padvia)
			)
		)
		(connect_pads yes
			(clearance 0)
		)
		(min_thickness 0.0254)
		(filled_areas_thickness no)
		(fill yes
			(thermal_gap 0.5)
			(thermal_bridge_width 0.5)
			(island_removal_mode 1)
			(island_area_min 10)
		)
		(polygon
			(pts
				(xy 139.366396 129.138007) (xy 139.311775 129.076577) (xy 139.275259 129.02068) (xy 139.242229 128.921809)
				(xy 139.23498 128.818095) (xy 139.231201 128.7349) (xy 139.217794 128.636841) (xy 138.849293 128.709293)
				(xy 138.776841 129.077794) (xy 138.930423 129.094169) (xy 138.958095 129.09498) (xy 139.037316 129.099032)
				(xy 139.112488 129.114488) (xy 139.190441 129.153043) (xy 139.278007 129.226396)
			)
		)
	)
	(zone
		(net 1)
		(net_name "GND")
		(layer "F.Cu")
		(name "$teardrop_padvia$")
		(hatch none 0.1)
		(priority 31209)
		(attr
			(teardrop
				(type padvia)
			)
		)
		(connect_pads yes
			(clearance 0)
		)
		(min_thickness 0.0254)
		(filled_areas_thickness no)
		(fill yes
			(thermal_gap 0.5)
			(thermal_bridge_width 0.5)
			(island_removal_mode 1)
			(island_area_min 10)
		)
		(polygon
			(pts
				(xy 194.425 169.498323) (xy 194.42028 169.567646) (xy 194.407244 169.620549) (xy 194.355344 169.713135)
				(xy 194.303541 169.796636) (xy 194.5 169.9) (xy 194.707644 169.823641) (xy 194.675418 169.743142)
				(xy 194.639035 169.641683) (xy 194.625 169.498323)
			)
		)
	)
	(zone
		(net 77)
		(net_name "+5V_AON")
		(layer "F.Cu")
		(name "$teardrop_padvia$")
		(hatch none 0.1)
		(priority 30089)
		(attr
			(teardrop
				(type padvia)
			)
		)
		(connect_pads yes
			(clearance 0)
		)
		(min_thickness 0.0254)
		(filled_areas_thickness no)
		(fill yes
			(thermal_gap 0.5)
			(thermal_bridge_width 0.5)
			(island_removal_mode 1)
			(island_area_min 10)
		)
		(polygon
			(pts
				(xy 188.80861 73.469957) (xy 188.813461 73.37858) (xy 188.827419 73.306651) (xy 188.874359 73.205101)
				(xy 188.93378 73.126258) (xy 189.020412 73.010502) (xy 188.708611 72.801164) (xy 188.39681 73.010502)
				(xy 188.483442 73.126259) (xy 188.534781 73.19314) (xy 188.574277 73.262874) (xy 188.599647 73.350225)
				(xy 188.608611 73.469956)
			)
		)
	)
	(zone
		(net 331)
		(net_name "/Com Express 7 Interfaces/PCIe_{B2Ax4}.TX3-")
		(layer "F.Cu")
		(name "$teardrop_padvia$")
		(hatch none 0.1)
		(priority 31440)
		(attr
			(teardrop
				(type padvia)
			)
		)
		(connect_pads yes
			(clearance 0)
		)
		(min_thickness 0.0254)
		(filled_areas_thickness no)
		(fill yes
			(thermal_gap 0.5)
			(thermal_bridge_width 0.5)
			(island_removal_mode 1)
			(island_area_min 10)
		)
		(polygon
			(pts
				(xy 233.263584 148.5045) (xy 233.217781 148.499765) (xy 233.1832 148.486619) (xy 233.136711 148.441671)
				(xy 233.113184 148.402419) (xy 233.086772 148.358424) (xy 233.050918 148.315834) (xy 232.899 148.477)
				(xy 232.915931 148.697677) (xy 233.093351 148.699528) (xy 233.263584 148.7065)
			)
		)
	)
	(zone
		(net 277)
		(net_name "Net-(J8-SUSCLK)")
		(layer "F.Cu")
		(name "$teardrop_padvia$")
		(hatch none 0.1)
		(priority 31150)
		(attr
			(teardrop
				(type padvia)
			)
		)
		(connect_pads yes
			(clearance 0)
		)
		(min_thickness 0.0254)
		(filled_areas_thickness no)
		(fill yes
			(thermal_gap 0.5)
			(thermal_bridge_width 0.5)
			(island_removal_mode 1)
			(island_area_min 10)
		)
		(polygon
			(pts
				(xy 302.8855 83.117) (xy 302.865717 83.176665) (xy 302.839411 83.206588) (xy 302.802397 83.233129)
				(xy 302.75384 83.254968) (xy 302.694562 83.269776) (xy 302.683243 83.271492) (xy 302.95 83.531)
				(xy 303.214241 83.269811) (xy 303.153829 83.25714) (xy 303.103716 83.237354) (xy 303.063471 83.211584)
				(xy 303.034369 83.181888) (xy 303.016865 83.150623) (xy 303.010521 83.118909) (xy 303.0105 83.117)
			)
		)
	)
	(zone
		(net 225)
		(net_name "/Com Express 7 Interfaces/PCIe_{B1x4}.TX0-")
		(layer "F.Cu")
		(name "$teardrop_padvia$")
		(hatch none 0.1)
		(priority 31414)
		(attr
			(teardrop
				(type padvia)
			)
		)
		(connect_pads yes
			(clearance 0)
		)
		(min_thickness 0.0254)
		(filled_areas_thickness no)
		(fill yes
			(thermal_gap 0.5)
			(thermal_bridge_width 0.5)
			(island_removal_mode 1)
			(island_area_min 10)
		)
		(polygon
			(pts
				(xy 210.682504 170.4815) (xy 210.844035 170.476105) (xy 210.928445 170.472554) (xy 211.03014 170.477177)
				(xy 211.051 170.2565) (xy 210.901147 170.093268) (xy 210.847007 170.161935) (xy 210.837115 170.178393)
				(xy 210.812615 170.217065) (xy 210.783109 170.249279) (xy 210.741953 170.271327) (xy 210.682504 170.2795)
			)
		)
	)
	(zone
		(net 110)
		(net_name "/2xSFP+/KR to SFI #1/REFCLK-")
		(layer "F.Cu")
		(name "$teardrop_padvia$")
		(hatch none 0.1)
		(priority 31161)
		(attr
			(teardrop
				(type padvia)
			)
		)
		(connect_pads yes
			(clearance 0)
		)
		(min_thickness 0.0254)
		(filled_areas_thickness no)
		(fill yes
			(thermal_gap 0.5)
			(thermal_bridge_width 0.5)
			(island_removal_mode 1)
			(island_area_min 10)
		)
		(polygon
			(pts
				(xy 145.13321 141.63) (xy 145.170305 141.634788) (xy 145.194569 141.648304) (xy 145.213295 141.690007)
				(xy 145.20811 141.778926) (xy 145.201285 141.844222) (xy 145.204804 141.908773) (xy 145.451 141.86)
				(xy 145.498773 141.614804) (xy 145.400798 141.578876) (xy 145.345383 141.54239) (xy 145.261398 141.492365)
				(xy 145.205772 141.476125) (xy 145.13321 141.47)
			)
		)
	)
	(zone
		(net 672)
		(net_name "/2xSFP+/KR to SFI #2/MDC")
		(layer "F.Cu")
		(name "$teardrop_padvia$")
		(hatch none 0.1)
		(priority 31785)
		(attr
			(teardrop
				(type padvia)
			)
		)
		(connect_pads yes
			(clearance 0)
		)
		(min_thickness 0.0254)
		(filled_areas_thickness no)
		(fill yes
			(thermal_gap 0.5)
			(thermal_bridge_width 0.5)
			(island_removal_mode 1)
			(island_area_min 10)
		)
		(polygon
			(pts
				(xy 125.7525 143.510677) (xy 125.757318 143.441236) (xy 125.77104 143.389912) (xy 125.817755 143.31437)
				(xy 125.827299 143.302229) (xy 125.877081 143.235003) (xy 125.69 143.109) (xy 125.502919 143.235003)
				(xy 125.552701 143.302231) (xy 125.607106 143.385397) (xy 125.62219 143.438251) (xy 125.6275 143.510677)
			)
		)
	)
	(zone
		(net 488)
		(net_name "/2xSFP+/I2C_{SFP0}.SCL")
		(layer "F.Cu")
		(name "$teardrop_padvia$")
		(hatch none 0.1)
		(priority 30681)
		(attr
			(teardrop
				(type padvia)
			)
		)
		(connect_pads yes
			(clearance 0)
		)
		(min_thickness 0.0254)
		(filled_areas_thickness no)
		(fill yes
			(thermal_gap 0.5)
			(thermal_bridge_width 0.5)
			(island_removal_mode 1)
			(island_area_min 10)
		)
		(polygon
			(pts
				(xy 194.9625 150.2) (xy 194.951563 150.238823) (xy 194.929805 150.253933) (xy 194.89 150.26) (xy 195.025 151.136)
				(xy 195.16 150.26) (xy 195.124719 150.255483) (xy 195.103203 150.243862) (xy 195.088005 150.211039)
				(xy 195.0875 150.2)
			)
		)
	)
	(zone
		(net 893)
		(net_name "Net-(J2B-TX_{DISABLE})")
		(layer "F.Cu")
		(name "$teardrop_padvia$")
		(hatch none 0.1)
		(priority 30062)
		(attr
			(teardrop
				(type padvia)
			)
		)
		(connect_pads yes
			(clearance 0)
		)
		(min_thickness 0.0254)
		(filled_areas_thickness no)
		(fill yes
			(thermal_gap 0.5)
			(thermal_bridge_width 0.5)
			(island_removal_mode 1)
			(island_area_min 10)
		)
		(polygon
			(pts
				(xy 142.395652 164.607264) (xy 142.337595 164.542385) (xy 142.297584 164.482904) (xy 142.259114 164.377939)
				(xy 142.249873 164.241643) (xy 142.246966 164.142859) (xy 142.231738 164.026111) (xy 141.809293 164.109293)
				(xy 141.726111 164.531738) (xy 141.888348 164.549046) (xy 141.941643 164.549873) (xy 142.031997 164.552904)
				(xy 142.118036 164.569259) (xy 142.207284 164.612365) (xy 142.307264 164.695652)
			)
		)
	)
	(zone
		(net 587)
		(net_name "/M.2 key E/SUSCLK")
		(layer "F.Cu")
		(name "$teardrop_padvia$")
		(hatch none 0.1)
		(priority 31983)
		(attr
			(teardrop
				(type padvia)
			)
		)
		(connect_pads yes
			(clearance 0)
		)
		(min_thickness 0.0254)
		(filled_areas_thickness no)
		(fill yes
			(thermal_gap 0.5)
			(thermal_bridge_width 0.5)
			(island_removal_mode 1)
			(island_area_min 10)
		)
		(polygon
			(pts
				(xy 308.5815 83.722) (xy 308.592438 83.683177) (xy 308.614195 83.668067) (xy 308.654 83.662) (xy 308.519 83.286)
				(xy 308.384 83.662) (xy 308.419281 83.666517) (xy 308.440797 83.678138) (xy 308.455995 83.710961)
				(xy 308.4565 83.722)
			)
		)
	)
	(zone
		(net 1)
		(net_name "GND")
		(layer "F.Cu")
		(name "$teardrop_padvia$")
		(hatch none 0.1)
		(priority 31201)
		(attr
			(teardrop
				(type padvia)
			)
		)
		(connect_pads yes
			(clearance 0)
		)
		(min_thickness 0.0254)
		(filled_areas_thickness no)
		(fill yes
			(thermal_gap 0.5)
			(thermal_bridge_width 0.5)
			(island_removal_mode 1)
			(island_area_min 10)
		)
		(polygon
			(pts
				(xy 184.425 157.499323) (xy 184.42028 157.568646) (xy 184.407244 157.621549) (xy 184.355344 157.714135)
				(xy 184.303541 157.797636) (xy 184.5 157.901) (xy 184.707644 157.824641) (xy 184.675418 157.744142)
				(xy 184.639035 157.642683) (xy 184.625 157.499323)
			)
		)
	)
	(zone
		(net 550)
		(net_name "Net-(R15-Pad2)")
		(layer "F.Cu")
		(name "$teardrop_padvia$")
		(hatch none 0.1)
		(priority 30335)
		(attr
			(teardrop
				(type padvia)
			)
		)
		(connect_pads yes
			(clearance 0)
		)
		(min_thickness 0.0254)
		(filled_areas_thickness no)
		(fill yes
			(thermal_gap 0.5)
			(thermal_bridge_width 0.5)
			(island_removal_mode 1)
			(island_area_min 10)
		)
		(polygon
			(pts
				(xy 135.845461 105.715961) (xy 135.89417 105.675415) (xy 135.957976 105.640465) (xy 136.016861 105.621669)
				(xy 136.084441 105.61303) (xy 136.175474 105.62) (xy 136.120707 105.299293) (xy 135.825 105.219526)
				(xy 135.819956 105.352711) (xy 135.781148 105.46805) (xy 135.714323 105.563873) (xy 135.704039 105.574539)
			)
		)
	)
	(zone
		(net 627)
		(net_name "/PCIe redriver/TX_FG1")
		(layer "F.Cu")
		(name "$teardrop_padvia$")
		(hatch none 0.1)
		(priority 31069)
		(attr
			(teardrop
				(type padvia)
			)
		)
		(connect_pads yes
			(clearance 0)
		)
		(min_thickness 0.0254)
		(filled_areas_thickness no)
		(fill yes
			(thermal_gap 0.5)
			(thermal_bridge_width 0.5)
			(island_removal_mode 1)
			(island_area_min 10)
		)
		(polygon
			(pts
				(xy 115.4625 151.253) (xy 115.482273 151.193588) (xy 115.545547 151.137503) (xy 115.594172 151.115801)
				(xy 115.653532 151.101127) (xy 115.6655 151.099347) (xy 115.4 150.839) (xy 115.1345 151.099347)
				(xy 115.194639 151.112197) (xy 115.244523 151.132131) (xy 115.284642 151.158056) (xy 115.313655 151.187876)
				(xy 115.331146 151.219294) (xy 115.337479 151.251105) (xy 115.3375 151.253)
			)
		)
	)
	(zone
		(net 756)
		(net_name "Net-(U45A-LS_OK_{OUT_A})")
		(layer "F.Cu")
		(name "$teardrop_padvia$")
		(hatch none 0.1)
		(priority 31733)
		(attr
			(teardrop
				(type padvia)
			)
		)
		(connect_pads yes
			(clearance 0)
		)
		(min_thickness 0.0254)
		(filled_areas_thickness no)
		(fill yes
			(thermal_gap 0.5)
			(thermal_bridge_width 0.5)
			(island_removal_mode 1)
			(island_area_min 10)
		)
		(polygon
			(pts
				(xy 132.2775 129.749323) (xy 132.272682 129.818763) (xy 132.25896 129.870087) (xy 132.212245 129.945628)
				(xy 132.202702 129.957768) (xy 132.152919 130.024997) (xy 132.34 130.151) (xy 132.527081 130.024997)
				(xy 132.477299 129.957769) (xy 132.422894 129.874603) (xy 132.40781 129.821748) (xy 132.4025 129.749323)
			)
		)
	)
	(zone
		(net 78)
		(net_name "+1V8")
		(layer "F.Cu")
		(name "$teardrop_padvia$")
		(hatch none 0.1)
		(priority 31295)
		(attr
			(teardrop
				(type padvia)
			)
		)
		(connect_pads yes
			(clearance 0)
		)
		(min_thickness 0.0254)
		(filled_areas_thickness no)
		(fill yes
			(thermal_gap 0.5)
			(thermal_bridge_width 0.5)
			(island_removal_mode 1)
			(island_area_min 10)
		)
		(polygon
			(pts
				(xy 203.962641 76.014773) (xy 203.910882 75.956349) (xy 203.878499 75.905599) (xy 203.8439 75.81146)
				(xy 203.813867 75.721042) (xy 203.607903 75.801456) (xy 203.527489 76.00742) (xy 203.617907 76.037453)
				(xy 203.713721 76.072925) (xy 203.763724 76.105142) (xy 203.82122 76.156194)
			)
		)
	)
	(zone
		(net 1)
		(net_name "GND")
		(layer "F.Cu")
		(name "$teardrop_padvia$")
		(hatch none 0.1)
		(priority 31227)
		(attr
			(teardrop
				(type padvia)
			)
		)
		(connect_pads yes
			(clearance 0)
		)
		(min_thickness 0.0254)
		(filled_areas_thickness no)
		(fill yes
			(thermal_gap 0.5)
			(thermal_bridge_width 0.5)
			(island_removal_mode 1)
			(island_area_min 10)
		)
		(polygon
			(pts
				(xy 212.125 167.900677) (xy 212.129737 167.809676) (xy 212.142896 167.742587) (xy 212.175418 167.655855)
				(xy 212.207644 167.575358) (xy 212 167.499) (xy 211.803541 167.602363) (xy 211.855343 167.685863)
				(xy 211.904833 167.771955) (xy 211.919614 167.82716) (xy 211.925 167.900677)
			)
		)
	)
	(zone
		(net 999)
		(net_name "Net-(C101-Pad1)")
		(layer "F.Cu")
		(name "$teardrop_padvia$")
		(hatch none 0.1)
		(priority 31014)
		(attr
			(teardrop
				(type padvia)
			)
		)
		(connect_pads yes
			(clearance 0)
		)
		(min_thickness 0.0254)
		(filled_areas_thickness no)
		(fill yes
			(thermal_gap 0.5)
			(thermal_bridge_width 0.5)
			(island_removal_mode 1)
			(island_area_min 10)
		)
		(polygon
			(pts
				(xy 247.788001 127.7675) (xy 247.725135 127.747531) (xy 247.693157 127.721079) (xy 247.664642 127.683668)
				(xy 247.642118 127.636473) (xy 247.626908 127.578833) (xy 247.626799 127.578203) (xy 247.349001 127.830001)
				(xy 247.626799 128.081799) (xy 247.641096 128.026366) (xy 247.662176 127.980481) (xy 247.689541 127.942799)
				(xy 247.72045 127.915566) (xy 247.753736 127.898528) (xy 247.786567 127.892511) (xy 247.788001 127.8925)
			)
		)
	)
	(zone
		(net 624)
		(net_name "/PCIe redriver/TX_EQ1")
		(layer "F.Cu")
		(name "$teardrop_padvia$")
		(hatch none 0.1)
		(priority 31546)
		(attr
			(teardrop
				(type padvia)
			)
		)
		(connect_pads yes
			(clearance 0)
		)
		(min_thickness 0.0254)
		(filled_areas_thickness no)
		(fill yes
			(thermal_gap 0.5)
			(thermal_bridge_width 0.5)
			(island_removal_mode 1)
			(island_area_min 10)
		)
		(polygon
			(pts
				(xy 111.975401 147.873788) (xy 112.048199 147.91539) (xy 112.085747 147.954299) (xy 112.117386 148.003132)
				(xy 112.137007 148.051696) (xy 112.147498 148.105813) (xy 112.420707 147.860707) (xy 112.136228 147.631054)
				(xy 112.127478 147.709404) (xy 112.11063 147.760735) (xy 112.093967 147.780812) (xy 112.073692 147.787031)
				(xy 112.063788 147.785401)
			)
		)
	)
	(zone
		(net 568)
		(net_name "/USB-C console/FTDI_D+")
		(layer "F.Cu")
		(name "$teardrop_padvia$")
		(hatch none 0.1)
		(priority 30443)
		(attr
			(teardrop
				(type padvia)
			)
		)
		(connect_pads yes
			(clearance 0)
		)
		(min_thickness 0.0254)
		(filled_areas_thickness no)
		(fill yes
			(thermal_gap 0.5)
			(thermal_bridge_width 0.5)
			(island_removal_mode 1)
			(island_area_min 10)
		)
		(polygon
			(pts
				(xy 112.047851 75.5425) (xy 112.021124 75.524233) (xy 112.001076 75.498103) (xy 111.978301 75.417753)
				(xy 111.981999 75.229634) (xy 111.685999 75.326) (xy 111.651885 75.646) (xy 111.769596 75.640855)
				(xy 111.905054 75.669466) (xy 112.047851 75.7275)
			)
		)
	)
	(zone
		(net 604)
		(net_name "Net-(U37-~{OE2})")
		(layer "F.Cu")
		(name "$teardrop_padvia$")
		(hatch none 0.1)
		(priority 32098)
		(attr
			(teardrop
				(type padvia)
			)
		)
		(connect_pads yes
			(clearance 0)
		)
		(min_thickness 0.0254)
		(filled_areas_thickness no)
		(fill yes
			(thermal_gap 0.5)
			(thermal_bridge_width 0.5)
			(island_removal_mode 1)
			(island_area_min 10)
		)
		(polygon
			(pts
				(xy 215.1425 131.615) (xy 215.141048 131.603203) (xy 215.140871 131.574919) (xy 215.149847 131.562347)
				(xy 215.17 131.553403) (xy 215.08 131.199) (xy 214.99 131.553403) (xy 215.010956 131.563008) (xy 215.01963 131.576553)
				(xy 215.018952 131.603203) (xy 215.0175 131.615)
			)
		)
	)
	(zone
		(net 130)
		(net_name "Net-(D17-C_{G})")
		(layer "F.Cu")
		(name "$teardrop_padvia$")
		(hatch none 0.1)
		(priority 31811)
		(attr
			(teardrop
				(type padvia)
			)
		)
		(connect_pads yes
			(clearance 0)
		)
		(min_thickness 0.0254)
		(filled_areas_thickness no)
		(fill yes
			(thermal_gap 0.5)
			(thermal_bridge_width 0.5)
			(island_removal_mode 1)
			(island_area_min 10)
		)
		(polygon
			(pts
				(xy 100.180677 76.7475) (xy 100.111236 76.742682) (xy 100.059913 76.72896) (xy 99.984371 76.682246)
				(xy 99.972231 76.672701) (xy 99.905003 76.622919) (xy 99.779 76.81) (xy 99.905003 76.997081) (xy 99.972229 76.947299)
				(xy 100.055396 76.892894) (xy 100.108251 76.87781) (xy 100.180677 76.8725)
			)
		)
	)
	(zone
		(net 312)
		(net_name "/2xUSB3.0+RJ45/USB_1.D-")
		(layer "F.Cu")
		(name "$teardrop_padvia$")
		(hatch none 0.1)
		(priority 30290)
		(attr
			(teardrop
				(type padvia)
			)
		)
		(connect_pads yes
			(clearance 0)
		)
		(min_thickness 0.0254)
		(filled_areas_thickness no)
		(fill yes
			(thermal_gap 0.5)
			(thermal_bridge_width 0.5)
			(island_removal_mode 1)
			(island_area_min 10)
		)
		(polygon
			(pts
				(xy 196.4925 167.75) (xy 196.494085 167.762189) (xy 196.492704 167.793738) (xy 196.477931 167.805396)
				(xy 196.445877 167.81) (xy 196.525 168.686) (xy 196.675 168.456314) (xy 196.655715 168.1969) (xy 196.668097 167.923917)
				(xy 196.6775 167.75)
			)
		)
	)
	(zone
		(net 1)
		(net_name "GND")
		(layer "F.Cu")
		(name "$teardrop_padvia$")
		(hatch none 0.1)
		(priority 31266)
		(attr
			(teardrop
				(type padvia)
			)
		)
		(connect_pads yes
			(clearance 0)
		)
		(min_thickness 0.0254)
		(filled_areas_thickness no)
		(fill yes
			(thermal_gap 0.5)
			(thermal_bridge_width 0.5)
			(island_removal_mode 1)
			(island_area_min 10)
		)
		(polygon
			(pts
				(xy 214.850677 78.01) (xy 214.772765 78.005287) (xy 214.713981 77.9923) (xy 214.622949 77.950198)
				(xy 214.537778 77.9075) (xy 214.449 78.11) (xy 214.537778 78.3125) (xy 214.622947 78.269802) (xy 214.715782 78.227133)
				(xy 214.773921 78.214556) (xy 214.850677 78.21)
			)
		)
	)
	(zone
		(net 107)
		(net_name "/2xSFP+/KR to SFI #1/CLK+")
		(layer "F.Cu")
		(name "$teardrop_padvia$")
		(hatch none 0.1)
		(priority 30632)
		(attr
			(teardrop
				(type padvia)
			)
		)
		(connect_pads yes
			(clearance 0)
		)
		(min_thickness 0.0254)
		(filled_areas_thickness no)
		(fill yes
			(thermal_gap 0.5)
			(thermal_bridge_width 0.5)
			(island_removal_mode 1)
			(island_area_min 10)
		)
		(polygon
			(pts
				(xy 142.156343 141.63) (xy 142.20195 141.685193) (xy 142.225457 141.779328) (xy 142.225 141.956839)
				(xy 142.521 141.86) (xy 142.554492 141.54) (xy 142.426107 141.552255) (xy 142.288236 141.529889)
				(xy 142.165029 141.475763) (xy 142.156343 141.47)
			)
		)
	)
	(zone
		(net 546)
		(net_name "/Com Express 7 MGMT/~{COM7}")
		(layer "F.Cu")
		(name "$teardrop_padvia$")
		(hatch none 0.1)
		(priority 30209)
		(attr
			(teardrop
				(type padvia)
			)
		)
		(connect_pads yes
			(clearance 0)
		)
		(min_thickness 0.0254)
		(filled_areas_thickness no)
		(fill yes
			(thermal_gap 0.5)
			(thermal_bridge_width 0.5)
			(island_removal_mode 1)
			(island_area_min 10)
		)
		(polygon
			(pts
				(xy 257.1115 131.99) (xy 257.091779 132.04726) (xy 257.028967 132.099784) (xy 256.980347 132.11955)
				(xy 256.921049 132.132076) (xy 256.904 132.133927) (xy 257.174 132.611) (xy 257.444 132.133927)
				(xy 257.382756 132.123751) (xy 257.33183 132.106075) (xy 257.290987 132.082177) (xy 257.261303 132.053978)
				(xy 257.24337 132.023988) (xy 257.23656 131.993138) (xy 257.2365 131.99)
			)
		)
	)
	(zone
		(net 322)
		(net_name "/Com Express 7 Interfaces/SDIO.DAT1")
		(layer "F.Cu")
		(name "$teardrop_padvia$")
		(hatch none 0.1)
		(priority 31581)
		(attr
			(teardrop
				(type padvia)
			)
		)
		(connect_pads yes
			(clearance 0)
		)
		(min_thickness 0.0254)
		(filled_areas_thickness no)
		(fill yes
			(thermal_gap 0.5)
			(thermal_bridge_width 0.5)
			(island_removal_mode 1)
			(island_area_min 10)
		)
		(polygon
			(pts
				(xy 113.757019 131.991) (xy 113.789927 131.995757) (xy 113.811133 132.009057) (xy 113.827632 132.051376)
				(xy 113.827131 132.113486) (xy 113.829323 132.203895) (xy 114.051 132.16) (xy 114.093895 131.939323)
				(xy 114.001072 131.904669) (xy 113.955293 131.875032) (xy 113.876373 131.829454) (xy 113.824408 131.814607)
				(xy 113.757019 131.809)
			)
		)
	)
	(zone
		(net 582)
		(net_name "Net-(U20-~{MR})")
		(layer "F.Cu")
		(name "$teardrop_padvia$")
		(hatch none 0.1)
		(priority 31114)
		(attr
			(teardrop
				(type padvia)
			)
		)
		(connect_pads yes
			(clearance 0)
		)
		(min_thickness 0.0254)
		(filled_areas_thickness no)
		(fill yes
			(thermal_gap 0.5)
			(thermal_bridge_width 0.5)
			(island_removal_mode 1)
			(island_area_min 10)
		)
		(polygon
			(pts
				(xy 305.247 131.1025) (xy 305.306412 131.122273) (xy 305.362497 131.185547) (xy 305.384199 131.234172)
				(xy 305.398873 131.293531) (xy 305.400653 131.3055) (xy 305.661 131.04) (xy 305.400653 130.7745)
				(xy 305.387804 130.834638) (xy 305.36787 130.884522) (xy 305.341945 130.924641) (xy 305.312125 130.953654)
				(xy 305.280707 130.971146) (xy 305.248896 130.977479) (xy 305.247 130.9775)
			)
		)
	)
	(zone
		(net 692)
		(net_name "/2xUSB3.0+RJ45/DB_FL-")
		(layer "F.Cu")
		(name "$teardrop_padvia$")
		(hatch none 0.1)
		(priority 31917)
		(attr
			(teardrop
				(type padvia)
			)
		)
		(connect_pads yes
			(clearance 0)
		)
		(min_thickness 0.0254)
		(filled_areas_thickness no)
		(fill yes
			(thermal_gap 0.5)
			(thermal_bridge_width 0.5)
			(island_removal_mode 1)
			(island_area_min 10)
		)
		(polygon
			(pts
				(xy 130.282428 105.4) (xy 130.363593 105.382068) (xy 130.516854 105.351156) (xy 130.607147 105.342998)
				(xy 130.707959 105.345) (xy 130.746 105.205) (xy 130.32 105.185121) (xy 130.319693 105.222722) (xy 130.310451 105.241116)
				(xy 130.288136 105.249129) (xy 130.282428 105.25)
			)
		)
	)
	(zone
		(net 939)
		(net_name "/2xSFP+/SFP0_LEDY")
		(layer "F.Cu")
		(name "$teardrop_padvia$")
		(hatch none 0.1)
		(priority 31115)
		(attr
			(teardrop
				(type padvia)
			)
		)
		(connect_pads yes
			(clearance 0)
		)
		(min_thickness 0.0254)
		(filled_areas_thickness no)
		(fill yes
			(thermal_gap 0.5)
			(thermal_bridge_width 0.5)
			(island_removal_mode 1)
			(island_area_min 10)
		)
		(polygon
			(pts
				(xy 154.406 158.1725) (xy 154.465412 158.192273) (xy 154.521497 158.255547) (xy 154.543199 158.304172)
				(xy 154.557873 158.363531) (xy 154.559653 158.3755) (xy 154.82 158.11) (xy 154.559653 157.8445)
				(xy 154.546804 157.904638) (xy 154.52687 157.954522) (xy 154.500945 157.994641) (xy 154.471125 158.023654)
				(xy 154.439707 158.041146) (xy 154.407896 158.047479) (xy 154.406 158.0475)
			)
		)
	)
	(zone
		(net 42)
		(net_name "/2xUSB3.0+RJ45/P1_VBUS")
		(layer "F.Cu")
		(hatch edge 0.5)
		(priority 34)
		(connect_pads yes
			(clearance 0.15)
		)
		(min_thickness 0.25)
		(filled_areas_thickness no)
		(fill yes
			(thermal_gap 0.5)
			(thermal_bridge_width 0.5)
			(smoothing fillet)
			(radius 0.2)
		)
		(polygon
			(pts
				(xy 116.25 86.31) (xy 116.3 86.26) (xy 116.3 84.66) (xy 109.3 84.66) (xy 109.3 86.76) (xy 112.3 86.76)
				(xy 112.75 86.31)
			)
		)
	)
	(zone
		(net 285)
		(net_name "/2xUSB3.0+RJ45/GbE.MDI3-")
		(layer "F.Cu")
		(name "$teardrop_padvia$")
		(hatch none 0.1)
		(priority 31648)
		(attr
			(teardrop
				(type padvia)
			)
		)
		(connect_pads yes
			(clearance 0)
		)
		(min_thickness 0.0254)
		(filled_areas_thickness no)
		(fill yes
			(thermal_gap 0.5)
			(thermal_bridge_width 0.5)
			(island_removal_mode 1)
			(island_area_min 10)
		)
		(polygon
			(pts
				(xy 176.675 167.742084) (xy 176.672797 167.536718) (xy 176.670677 167.398242) (xy 176.45 167.399)
				(xy 176.324997 167.587081) (xy 176.401138 167.620995) (xy 176.417738 167.62605) (xy 176.459281 167.639844)
				(xy 176.493398 167.659262) (xy 176.516501 167.691083) (xy 176.525 167.742084)
			)
		)
	)
	(zone
		(net 337)
		(net_name "/Com Express 7 Interfaces/PCIE_{REF}.CK-")
		(layer "F.Cu")
		(name "$teardrop_padvia$")
		(hatch none 0.1)
		(priority 31394)
		(attr
			(teardrop
				(type padvia)
			)
		)
		(connect_pads yes
			(clearance 0)
		)
		(min_thickness 0.0254)
		(filled_areas_thickness no)
		(fill yes
			(thermal_gap 0.5)
			(thermal_bridge_width 0.5)
			(island_removal_mode 1)
			(island_area_min 10)
		)
		(polygon
			(pts
				(xy 215.1855 122.967496) (xy 215.180105 122.805964) (xy 215.176555 122.721553) (xy 215.181177 122.619859)
				(xy 214.9605 122.599) (xy 214.797268 122.748852) (xy 214.865936 122.802992) (xy 214.882392 122.812884)
				(xy 214.921064 122.837384) (xy 214.953279 122.86689) (xy 214.975327 122.908046) (xy 214.9835 122.967496)
			)
		)
	)
	(zone
		(net 575)
		(net_name "Net-(U18-MODE)")
		(layer "F.Cu")
		(name "$teardrop_padvia$")
		(hatch none 0.1)
		(priority 32136)
		(attr
			(teardrop
				(type padvia)
			)
		)
		(connect_pads yes
			(clearance 0)
		)
		(min_thickness 0.0254)
		(filled_areas_thickness no)
		(fill yes
			(thermal_gap 0.5)
			(thermal_bridge_width 0.5)
			(island_removal_mode 1)
			(island_area_min 10)
		)
		(polygon
			(pts
				(xy 309.97692 121.524499) (xy 309.993646 121.523084) (xy 310.03397 121.523109) (xy 310.054265 121.532236)
				(xy 310.072521 121.552564) (xy 310.315999 121.463999) (xy 310.079358 121.372602) (xy 310.060468 121.391759)
				(xy 310.039973 121.400813) (xy 309.995139 121.40104) (xy 309.97692 121.399499)
			)
		)
	)
	(zone
		(net 73)
		(net_name "+3V3_AON")
		(layer "F.Cu")
		(name "$teardrop_padvia$")
		(hatch none 0.1)
		(priority 30845)
		(attr
			(teardrop
				(type padvia)
			)
		)
		(connect_pads yes
			(clearance 0)
		)
		(min_thickness 0.0254)
		(filled_areas_thickness no)
		(fill yes
			(thermal_gap 0.5)
			(thermal_bridge_width 0.5)
			(island_removal_mode 1)
			(island_area_min 10)
		)
		(polygon
			(pts
				(xy 244.43 126.272) (xy 244.42379 126.318211) (xy 244.400323 126.36661) (xy 244.372416 126.394966)
				(xy 244.33219 126.418012) (xy 244.278202 126.433202) (xy 244.53 126.711) (xy 244.781798 126.433202)
				(xy 244.732946 126.420069) (xy 244.695436 126.400665) (xy 244.648013 126.348055) (xy 244.630257 126.281554)
				(xy 244.63 126.272)
			)
		)
	)
	(zone
		(net 537)
		(net_name "/Backplane/PCIe_{x2}.RX0-")
		(layer "F.Cu")
		(name "$teardrop_padvia$")
		(hatch none 0.1)
		(priority 32036)
		(attr
			(teardrop
				(type padvia)
			)
		)
		(connect_pads yes
			(clearance 0)
		)
		(min_thickness 0.0254)
		(filled_areas_thickness no)
		(fill yes
			(thermal_gap 0.5)
			(thermal_bridge_width 0.5)
			(island_removal_mode 1)
			(island_area_min 10)
		)
		(polygon
			(pts
				(xy 315.439923 160.252151) (xy 315.375098 160.27007) (xy 315.293474 160.293166) (xy 315.246221 160.295255)
				(xy 315.193992 160.285) (xy 315.13402 160.410195) (xy 315.40958 160.474606) (xy 315.41417 160.45102)
				(xy 315.425751 160.441479) (xy 315.459831 160.446117) (xy 315.47933 160.450268)
			)
		)
	)
	(zone
		(net 208)
		(net_name "/Backplane/UART.RX")
		(layer "F.Cu")
		(name "$teardrop_padvia$")
		(hatch none 0.1)
		(priority 32107)
		(attr
			(teardrop
				(type padvia)
			)
		)
		(connect_pads yes
			(clearance 0)
		)
		(min_thickness 0.0254)
		(filled_areas_thickness no)
		(fill yes
			(thermal_gap 0.5)
			(thermal_bridge_width 0.5)
			(island_removal_mode 1)
			(island_area_min 10)
		)
		(polygon
			(pts
				(xy 314.038 167.5705) (xy 314.044322 167.570404) (xy 314.083825 167.575989) (xy 314.102047 167.590922)
				(xy 314.114995 167.6205) (xy 314.364 167.508) (xy 314.114995 167.3955) (xy 314.103879 167.422493)
				(xy 314.088352 167.437595) (xy 314.044322 167.445596) (xy 314.038 167.4455)
			)
		)
	)
	(zone
		(net 1)
		(net_name "GND")
		(layer "F.Cu")
		(name "$teardrop_padvia$")
		(hatch none 0.1)
		(priority 30868)
		(attr
			(teardrop
				(type padvia)
			)
		)
		(connect_pads yes
			(clearance 0)
		)
		(min_thickness 0.0254)
		(filled_areas_thickness no)
		(fill yes
			(thermal_gap 0.5)
			(thermal_bridge_width 0.5)
			(island_removal_mode 1)
			(island_area_min 10)
		)
		(polygon
			(pts
				(xy 188.80861 78.045163) (xy 188.814382 78.004426) (xy 188.834786 77.962511) (xy 188.861961 77.93421)
				(xy 188.901507 77.910781) (xy 188.97411 77.89151) (xy 188.70861 77.631163) (xy 188.44311 77.89151)
				(xy 188.496252 77.903377) (xy 188.537291 77.921825) (xy 188.588992 77.972499) (xy 188.608328 78.036068)
				(xy 188.60861 78.045163)
			)
		)
	)
	(zone
		(net 73)
		(net_name "+3V3_AON")
		(layer "F.Cu")
		(name "$teardrop_padvia$")
		(hatch none 0.1)
		(priority 30925)
		(attr
			(teardrop
				(type padvia)
			)
		)
		(connect_pads yes
			(clearance 0)
		)
		(min_thickness 0.0254)
		(filled_areas_thickness no)
		(fill yes
			(thermal_gap 0.5)
			(thermal_bridge_width 0.5)
			(island_removal_mode 1)
			(island_area_min 10)
		)
		(polygon
			(pts
				(xy 253.76625 127.109248) (xy 253.703384 127.089279) (xy 253.671406 127.062827) (xy 253.642892 127.025416)
				(xy 253.620368 126.978221) (xy 253.605157 126.920581) (xy 253.605048 126.91995) (xy 253.32725 127.171748)
				(xy 253.605048 127.423546) (xy 253.619345 127.368113) (xy 253.640425 127.322228) (xy 253.66779 127.284547)
				(xy 253.698698 127.257314) (xy 253.731985 127.240276) (xy 253.764816 127.234259) (xy 253.76625 127.234248)
			)
		)
	)
	(zone
		(net 583)
		(net_name "Net-(U22-EN)")
		(layer "F.Cu")
		(name "$teardrop_padvia$")
		(hatch none 0.1)
		(priority 32039)
		(attr
			(teardrop
				(type padvia)
			)
		)
		(connect_pads yes
			(clearance 0)
		)
		(min_thickness 0.0254)
		(filled_areas_thickness no)
		(fill yes
			(thermal_gap 0.5)
			(thermal_bridge_width 0.5)
			(island_removal_mode 1)
			(island_area_min 10)
		)
		(polygon
			(pts
				(xy 312.486999 135.317) (xy 312.49576 135.270297) (xy 312.515286 135.248785) (xy 312.552532 135.235033)
				(xy 312.424499 134.956) (xy 312.296466 135.235033) (xy 312.327234 135.24492) (xy 312.346459 135.260183)
				(xy 312.361393 135.300135) (xy 312.361999 135.317)
			)
		)
	)
	(zone
		(net 269)
		(net_name "/Com Express 7 Interfaces/PCIe_{B2Bx4}.TX0+")
		(layer "F.Cu")
		(name "$teardrop_padvia$")
		(hatch none 0.1)
		(priority 31433)
		(attr
			(teardrop
				(type padvia)
			)
		)
		(connect_pads yes
			(clearance 0)
		)
		(min_thickness 0.0254)
		(filled_areas_thickness no)
		(fill yes
			(thermal_gap 0.5)
			(thermal_bridge_width 0.5)
			(island_removal_mode 1)
			(island_area_min 10)
		)
		(polygon
			(pts
				(xy 191.517496 165.1935) (xy 191.355964 165.198895) (xy 191.271554 165.202445) (xy 191.16986 165.197823)
				(xy 191.149 165.4185) (xy 191.298852 165.581731) (xy 191.352992 165.513062) (xy 191.362883 165.496608)
				(xy 191.387383 165.457935) (xy 191.41689 165.425721) (xy 191.458046 165.403673) (xy 191.517496 165.3955)
			)
		)
	)
	(zone
		(net 187)
		(net_name "/OCuLink/PCIe_{x4}.RX0-")
		(layer "F.Cu")
		(name "$teardrop_padvia$")
		(hatch none 0.1)
		(priority 32087)
		(attr
			(teardrop
				(type padvia)
			)
		)
		(connect_pads yes
			(clearance 0)
		)
		(min_thickness 0.0254)
		(filled_areas_thickness no)
		(fill yes
			(thermal_gap 0.5)
			(thermal_bridge_width 0.5)
			(island_removal_mode 1)
			(island_area_min 10)
		)
		(polygon
			(pts
				(xy 96.901 151.147) (xy 96.908198 151.167648) (xy 96.917792 151.199984) (xy 96.910965 151.214007)
				(xy 96.8895 151.223995) (xy 97.002 151.473) (xy 97.1145 151.223995) (xy 97.093324 151.214271) (xy 97.086269 151.200643)
				(xy 97.095802 151.167648) (xy 97.103 151.147)
			)
		)
	)
	(zone
		(net 1)
		(net_name "GND")
		(layer "F.Cu")
		(name "$teardrop_padvia$")
		(hatch none 0.1)
		(priority 30784)
		(attr
			(teardrop
				(type padvia)
			)
		)
		(connect_pads yes
			(clearance 0)
		)
		(min_thickness 0.0254)
		(filled_areas_thickness no)
		(fill yes
			(thermal_gap 0.5)
			(thermal_bridge_width 0.5)
			(island_removal_mode 1)
			(island_area_min 10)
		)
		(polygon
			(pts
				(xy 152.969177 78.9095) (xy 152.811606 78.902569) (xy 152.698078 78.874049) (xy 152.656278 78.857)
				(xy 152.5675 79.0595) (xy 152.656278 79.262) (xy 152.752317 79.227618) (xy 152.854189 79.2124) (xy 152.969177 79.2095)
			)
		)
	)
	(zone
		(net 1)
		(net_name "GND")
		(layer "F.Cu")
		(name "$teardrop_padvia$")
		(hatch none 0.1)
		(priority 31922)
		(attr
			(teardrop
				(type padvia)
			)
		)
		(connect_pads yes
			(clearance 0)
		)
		(min_thickness 0.0254)
		(filled_areas_thickness no)
		(fill yes
			(thermal_gap 0.5)
			(thermal_bridge_width 0.5)
			(island_removal_mode 1)
			(island_area_min 10)
		)
		(polygon
			(pts
				(xy 97.602 151.055) (xy 97.601847 151.044885) (xy 97.60246 151.014168) (xy 97.610782 150.98168)
				(xy 97.634675 150.952525) (xy 97.682 150.931808) (xy 97.502 150.699) (xy 97.322 150.931808) (xy 97.357901 150.945167)
				(xy 97.381199 150.963398) (xy 97.400899 151.008724) (xy 97.402153 151.044885) (xy 97.402 151.055)
			)
		)
	)
	(zone
		(net 62)
		(net_name "+12V_AON")
		(layer "F.Cu")
		(name "$teardrop_padvia$")
		(hatch none 0.1)
		(priority 30158)
		(attr
			(teardrop
				(type padvia)
			)
		)
		(connect_pads yes
			(clearance 0)
		)
		(min_thickness 0.0254)
		(filled_areas_thickness no)
		(fill yes
			(thermal_gap 0.5)
			(thermal_bridge_width 0.5)
			(island_removal_mode 1)
			(island_area_min 10)
		)
		(polygon
			(pts
				(xy 186.60861 73.542163) (xy 186.60355 73.575682) (xy 186.588129 73.608588) (xy 186.562347 73.6389)
				(xy 186.525738 73.665407) (xy 186.478562 73.68631) (xy 186.420127 73.700395) (xy 186.34861 73.706141)
				(xy 186.70861 74.103163) (xy 187.06861 73.706141) (xy 186.998539 73.700621) (xy 186.940004 73.686759)
				(xy 186.892657 73.666073) (xy 186.856184 73.640095) (xy 186.8301 73.610127) (xy 186.814368 73.577901)
				(xy 186.80861 73.542163)
			)
		)
	)
	(zone
		(net 336)
		(net_name "/Com Express 7 Interfaces/PCIE_{REF}.CK+")
		(layer "F.Cu")
		(name "$teardrop_padvia$")
		(hatch none 0.1)
		(priority 30264)
		(attr
			(teardrop
				(type padvia)
			)
		)
		(connect_pads yes
			(clearance 0)
		)
		(min_thickness 0.0254)
		(filled_areas_thickness no)
		(fill yes
			(thermal_gap 0.5)
			(thermal_bridge_width 0.5)
			(island_removal_mode 1)
			(island_area_min 10)
		)
		(polygon
			(pts
				(xy 219.6815 169.62) (xy 219.670401 169.446888) (xy 219.655784 169.21949) (xy 219.658819 169.084862)
				(xy 219.675 168.932978) (xy 219.525 168.684) (xy 219.441705 169.56) (xy 219.472136 169.564477) (xy 219.484903 169.575815)
				(xy 219.48258 169.605773) (xy 219.4795 169.62)
			)
		)
	)
	(zone
		(net 239)
		(net_name "/Com Express 7 Interfaces/PCIe_{B2Bx4}.RX3+")
		(layer "F.Cu")
		(name "$teardrop_padvia$")
		(hatch none 0.1)
		(priority 30254)
		(attr
			(teardrop
				(type padvia)
			)
		)
		(connect_pads yes
			(clearance 0)
		)
		(min_thickness 0.0254)
		(filled_areas_thickness no)
		(fill yes
			(thermal_gap 0.5)
			(thermal_bridge_width 0.5)
			(island_removal_mode 1)
			(island_area_min 10)
		)
		(polygon
			(pts
				(xy 186.4795 162.2) (xy 186.48258 162.214227) (xy 186.484749 162.244527) (xy 186.471877 162.255628)
				(xy 186.441705 162.26) (xy 186.525 163.136) (xy 186.675 162.887021) (xy 186.655644 162.645818) (xy 186.670401 162.373112)
				(xy 186.6815 162.2)
			)
		)
	)
	(zone
		(net 1)
		(net_name "GND")
		(layer "F.Cu")
		(name "$teardrop_padvia$")
		(hatch none 0.1)
		(priority 30573)
		(attr
			(teardrop
				(type padvia)
			)
		)
		(connect_pads yes
			(clearance 0)
		)
		(min_thickness 0.0254)
		(filled_areas_thickness no)
		(fill yes
			(thermal_gap 0.5)
			(thermal_bridge_width 0.5)
			(island_removal_mode 1)
			(island_area_min 10)
		)
		(polygon
			(pts
				(xy 215.425 155.75) (xy 215.428333 155.764486) (xy 215.43119 155.79461) (xy 215.419036 155.805651)
				(xy 215.39 155.81) (xy 215.525 156.686) (xy 215.66 155.81) (xy 215.630666 155.805525) (xy 215.618642 155.794199)
				(xy 215.621667 155.764486) (xy 215.625 155.75)
			)
		)
	)
	(zone
		(net 1)
		(net_name "GND")
		(layer "F.Cu")
		(name "$teardrop_padvia$")
		(hatch none 0.1)
		(priority 30774)
		(attr
			(teardrop
				(type padvia)
			)
		)
		(connect_pads yes
			(clearance 0)
		)
		(min_thickness 0.0254)
		(filled_areas_thickness no)
		(fill yes
			(thermal_gap 0.5)
			(thermal_bridge_width 0.5)
			(island_removal_mode 1)
			(island_area_min 10)
		)
		(polygon
			(pts
				(xy 225.789387 159.577255) (xy 225.682869 159.460934) (xy 225.622759 159.360491) (xy 225.605257 159.318879)
				(xy 225.399293 159.399293) (xy 225.318879 159.605257) (xy 225.411105 159.648858) (xy 225.493905 159.710138)
				(xy 225.577255 159.789387)
			)
		)
	)
	(zone
		(net 790)
		(net_name "Net-(U38-1A)")
		(layer "F.Cu")
		(name "$teardrop_padvia$")
		(hatch none 0.1)
		(priority 31990)
		(attr
			(teardrop
				(type padvia)
			)
		)
		(connect_pads yes
			(clearance 0)
		)
		(min_thickness 0.0254)
		(filled_areas_thickness no)
		(fill yes
			(thermal_gap 0.5)
			(thermal_bridge_width 0.5)
			(island_removal_mode 1)
			(island_area_min 10)
		)
		(polygon
			(pts
				(xy 308.4565 80.103) (xy 308.445563 80.141823) (xy 308.423805 80.156933) (xy 308.384 80.163) (xy 308.519 80.539)
				(xy 308.654 80.163) (xy 308.618719 80.158483) (xy 308.597203 80.146862) (xy 308.582005 80.114039)
				(xy 308.5815 80.103)
			)
		)
	)
	(zone
		(net 439)
		(net_name "Net-(J12L-RAPID_SHUTDOWN)")
		(layer "F.Cu")
		(name "$teardrop_padvia$")
		(hatch none 0.1)
		(priority 30666)
		(attr
			(teardrop
				(type padvia)
			)
		)
		(connect_pads yes
			(clearance 0)
		)
		(min_thickness 0.0254)
		(filled_areas_thickness no)
		(fill yes
			(thermal_gap 0.5)
			(thermal_bridge_width 0.5)
			(island_removal_mode 1)
			(island_area_min 10)
		)
		(polygon
			(pts
				(xy 209.0875 157.62) (xy 209.098438 157.581177) (xy 209.120195 157.566067) (xy 209.16 157.56) (xy 209.025 156.684)
				(xy 208.89 157.56) (xy 208.925281 157.564517) (xy 208.946797 157.576138) (xy 208.961995 157.608961)
				(xy 208.9625 157.62)
			)
		)
	)
	(zone
		(net 970)
		(net_name "/M.2 key M #2/M2_3V3")
		(layer "F.Cu")
		(name "$teardrop_padvia$")
		(hatch none 0.1)
		(priority 30764)
		(attr
			(teardrop
				(type padvia)
			)
		)
		(connect_pads yes
			(clearance 0)
		)
		(min_thickness 0.0254)
		(filled_areas_thickness no)
		(fill yes
			(thermal_gap 0.5)
			(thermal_bridge_width 0.5)
			(island_removal_mode 1)
			(island_area_min 10)
		)
		(polygon
			(pts
				(xy 289.598 80.978677) (xy 289.604932 80.8211) (xy 289.633456 80.707565) (xy 289.6505 80.665778)
				(xy 289.448 80.577) (xy 289.2455 80.665778) (xy 289.279883 80.761822) (xy 289.295101 80.863702)
				(xy 289.298 80.978677)
			)
		)
	)
	(zone
		(net 73)
		(net_name "+3V3_AON")
		(layer "F.Cu")
		(name "$teardrop_padvia$")
		(hatch none 0.1)
		(priority 31813)
		(attr
			(teardrop
				(type padvia)
			)
		)
		(connect_pads yes
			(clearance 0)
		)
		(min_thickness 0.0254)
		(filled_areas_thickness no)
		(fill yes
			(thermal_gap 0.5)
			(thermal_bridge_width 0.5)
			(island_removal_mode 1)
			(island_area_min 10)
		)
		(polygon
			(pts
				(xy 253.728927 127.109248) (xy 253.659486 127.10443) (xy 253.608163 127.090708) (xy 253.532621 127.043994)
				(xy 253.520481 127.034449) (xy 253.453253 126.984667) (xy 253.32725 127.171748) (xy 253.453253 127.358829)
				(xy 253.520479 127.309047) (xy 253.603646 127.254642) (xy 253.656501 127.239558) (xy 253.728927 127.234248)
			)
		)
	)
	(zone
		(net 327)
		(net_name "/Com Express 7 Interfaces/PCIe_{B2Ax4}.TX1-")
		(layer "F.Cu")
		(name "$teardrop_padvia$")
		(hatch none 0.1)
		(priority 30379)
		(attr
			(teardrop
				(type padvia)
			)
		)
		(connect_pads yes
			(clearance 0)
		)
		(min_thickness 0.0254)
		(filled_areas_thickness no)
		(fill yes
			(thermal_gap 0.5)
			(thermal_bridge_width 0.5)
			(island_removal_mode 1)
			(island_area_min 10)
		)
		(polygon
			(pts
				(xy 295.0425 73.2) (xy 295.053603 73.355527) (xy 295.068217 73.559681) (xy 295.06518 73.679806)
				(xy 295.049 73.814533) (xy 295.199 74.036) (xy 295.28278 73.26) (xy 295.252191 73.255523) (xy 295.239299 73.244182)
				(xy 295.241476 73.214169) (xy 295.2445 73.2)
			)
		)
	)
	(zone
		(net 2)
		(net_name "+3V3")
		(layer "F.Cu")
		(name "$teardrop_padvia$")
		(hatch none 0.1)
		(priority 30406)
		(attr
			(teardrop
				(type padvia)
			)
		)
		(connect_pads yes
			(clearance 0)
		)
		(min_thickness 0.0254)
		(filled_areas_thickness no)
		(fill yes
			(thermal_gap 0.5)
			(thermal_bridge_width 0.5)
			(island_removal_mode 1)
			(island_area_min 10)
		)
		(polygon
			(pts
				(xy 118.65 145.408) (xy 118.670403 145.452645) (xy 118.689221 145.486192) (xy 118.697795 145.518655)
				(xy 118.683697 145.545365) (xy 118.6345 145.561652) (xy 118.9 145.822) (xy 119.1655 145.561652)
				(xy 119.127407 145.551832) (xy 119.107642 145.536425) (xy 119.104648 145.5021) (xy 119.129597 145.452645)
				(xy 119.15 145.408)
			)
		)
	)
	(zone
		(net 1)
		(net_name "GND")
		(layer "F.Cu")
		(hatch edge 0.5)
		(priority 13)
		(connect_pads yes
			(clearance 0.15)
		)
		(min_thickness 0.25)
		(filled_areas_thickness no)
		(fill yes
			(thermal_gap 0.2)
			(thermal_bridge_width 0.5)
			(smoothing fillet)
			(radius 0.2)
		)
		(polygon
			(pts
				(xy 312.114501 94.1365) (xy 312.114501 94.6365) (xy 312.314501 94.8365) (xy 313.364501 94.8365)
				(xy 313.714501 95.1865) (xy 318.75 95.1865) (xy 318.75 102.96) (xy 311.5 102.96) (xy 309.682391 104.22)
				(xy 308.924999 104.22) (xy 308.804999 104.1) (xy 308.804999 99.56) (xy 309.454999 98.91) (xy 314.9 98.91)
				(xy 315.239501 98.56) (xy 315.239501 98.1115) (xy 313.564501 96.4365) (xy 313.564501 95.9365) (xy 313.064501 95.4365)
				(xy 312.314501 95.4365) (xy 312.114501 95.6365) (xy 312.114501 97.2115) (xy 312.039501 97.2865)
				(xy 311.364501 97.2865) (xy 311.264501 97.3865) (xy 311.264501 97.7365) (xy 310.864501 98.1365)
				(xy 309.914501 98.1365) (xy 309.614501 97.8365) (xy 309.614501 95.6365) (xy 310.414501 94.8365)
				(xy 310.414501 94.0365) (xy 310.564501 93.8865) (xy 311.864501 93.8865)
			)
		)
	)
	(zone
		(net 703)
		(net_name "Net-(U24-GPIO3)")
		(layer "F.Cu")
		(name "$teardrop_padvia$")
		(hatch none 0.1)
		(priority 30815)
		(attr
			(teardrop
				(type padvia)
			)
		)
		(connect_pads yes
			(clearance 0)
		)
		(min_thickness 0.0254)
		(filled_areas_thickness no)
		(fill yes
			(thermal_gap 0.5)
			(thermal_bridge_width 0.5)
			(island_removal_mode 1)
			(island_area_min 10)
		)
		(polygon
			(pts
				(xy 260.624 85.037499) (xy 260.597391 85.032136) (xy 260.572117 85.014599) (xy 260.554478 84.988305)
				(xy 260.54305 84.950159) (xy 260.54 84.910999) (xy 259.979 85.1) (xy 260.54 85.288999) (xy 260.544627 85.241636)
				(xy 260.557018 85.206588) (xy 260.574877 85.18265) (xy 260.596015 85.168453) (xy 260.624 85.162499)
			)
		)
	)
	(zone
		(net 538)
		(net_name "Net-(Q5-D)")
		(layer "F.Cu")
		(name "$teardrop_padvia$")
		(hatch none 0.1)
		(priority 31540)
		(attr
			(teardrop
				(type padvia)
			)
		)
		(connect_pads yes
			(clearance 0)
		)
		(min_thickness 0.0254)
		(filled_areas_thickness no)
		(fill yes
			(thermal_gap 0.5)
			(thermal_bridge_width 0.5)
			(island_removal_mode 1)
			(island_area_min 10)
		)
		(polygon
			(pts
				(xy 260.7605 93.722) (xy 260.780545 93.670069) (xy 260.806406 93.646949) (xy 260.842879 93.628433)
				(xy 260.9455 93.612) (xy 260.698 93.336) (xy 260.4505 93.612) (xy 260.508882 93.616701) (xy 260.55618 93.629606)
				(xy 260.592425 93.648916) (xy 260.617668 93.672838) (xy 260.6355 93.722)
			)
		)
	)
	(zone
		(net 310)
		(net_name "/Com Express 7 MGMT/~{BIOS_DIS0}")
		(layer "F.Cu")
		(name "$teardrop_padvia$")
		(hatch none 0.1)
		(priority 31783)
		(attr
			(teardrop
				(type padvia)
			)
		)
		(connect_pads yes
			(clearance 0)
		)
		(min_thickness 0.0254)
		(filled_areas_thickness no)
		(fill yes
			(thermal_gap 0.5)
			(thermal_bridge_width 0.5)
			(island_removal_mode 1)
			(island_area_min 10)
		)
		(polygon
			(pts
				(xy 217.8625 143.250677) (xy 217.867318 143.181236) (xy 217.88104 143.129912) (xy 217.927755 143.05437)
				(xy 217.937299 143.042229) (xy 217.987081 142.975003) (xy 217.8 142.849) (xy 217.612919 142.975003)
				(xy 217.662701 143.042231) (xy 217.717106 143.125397) (xy 217.73219 143.178251) (xy 217.7375 143.250677)
			)
		)
	)
	(zone
		(net 751)
		(net_name "Net-(U45C-CLKOUTA-)")
		(layer "F.Cu")
		(name "$teardrop_padvia$")
		(hatch none 0.1)
		(priority 30128)
		(attr
			(teardrop
				(type padvia)
			)
		)
		(connect_pads yes
			(clearance 0)
		)
		(min_thickness 0.0254)
		(filled_areas_thickness no)
		(fill yes
			(thermal_gap 0.5)
			(thermal_bridge_width 0.5)
			(island_removal_mode 1)
			(island_area_min 10)
		)
		(polygon
			(pts
				(xy 130.4525 130.227794) (xy 130.457315 130.145733) (xy 130.471019 130.080388) (xy 130.517576 129.98712)
				(xy 130.585787 129.908657) (xy 130.641942 129.847158) (xy 130.701801 129.768339) (xy 130.39 129.559)
				(xy 130.078199 129.768339) (xy 130.175219 129.888517) (xy 130.194214 129.908658) (xy 130.247366 129.967541)
				(xy 130.289591 130.031624) (xy 130.317449 130.114008) (xy 130.3275 130.227794)
			)
		)
	)
	(zone
		(net 1)
		(net_name "GND")
		(layer "F.Cu")
		(name "$teardrop_padvia$")
		(hatch none 0.1)
		(priority 31205)
		(attr
			(teardrop
				(type padvia)
			)
		)
		(connect_pads yes
			(clearance 0)
		)
		(min_thickness 0.0254)
		(filled_areas_thickness no)
		(fill yes
			(thermal_gap 0.5)
			(thermal_bridge_width 0.5)
			(island_removal_mode 1)
			(island_area_min 10)
		)
		(polygon
			(pts
				(xy 185.925 157.499323) (xy 185.92028 157.568646) (xy 185.907244 157.621549) (xy 185.855344 157.714135)
				(xy 185.803541 157.797636) (xy 186 157.901) (xy 186.207644 157.824641) (xy 186.175418 157.744142)
				(xy 186.139035 157.642683) (xy 186.125 157.499323)
			)
		)
	)
	(zone
		(net 754)
		(net_name "Net-(U45A-LOSA)")
		(layer "F.Cu")
		(name "$teardrop_padvia$")
		(hatch none 0.1)
		(priority 30127)
		(attr
			(teardrop
				(type padvia)
			)
		)
		(connect_pads yes
			(clearance 0)
		)
		(min_thickness 0.0254)
		(filled_areas_thickness no)
		(fill yes
			(thermal_gap 0.5)
			(thermal_bridge_width 0.5)
			(island_removal_mode 1)
			(island_area_min 10)
		)
		(polygon
			(pts
				(xy 131.7525 130.227794) (xy 131.757315 130.145733) (xy 131.771019 130.080388) (xy 131.817576 129.98712)
				(xy 131.885787 129.908657) (xy 131.941942 129.847158) (xy 132.001801 129.768339) (xy 131.69 129.559)
				(xy 131.378199 129.768339) (xy 131.475219 129.888517) (xy 131.494214 129.908658) (xy 131.547366 129.967541)
				(xy 131.589591 130.031624) (xy 131.617449 130.114008) (xy 131.6275 130.227794)
			)
		)
	)
	(zone
		(net 717)
		(net_name "Net-(U40-SCL)")
		(layer "F.Cu")
		(name "$teardrop_padvia$")
		(hatch none 0.1)
		(priority 30099)
		(attr
			(teardrop
				(type padvia)
			)
		)
		(connect_pads yes
			(clearance 0)
		)
		(min_thickness 0.0254)
		(filled_areas_thickness no)
		(fill yes
			(thermal_gap 0.5)
			(thermal_bridge_width 0.5)
			(island_removal_mode 1)
			(island_area_min 10)
		)
		(polygon
			(pts
				(xy 196.7375 132.332206) (xy 196.732685 132.414266) (xy 196.718981 132.479611) (xy 196.672424 132.572879)
				(xy 196.604214 132.651341) (xy 196.548058 132.712841) (xy 196.488199 132.791661) (xy 196.8 133.001)
				(xy 197.111801 132.791661) (xy 197.014781 132.671482) (xy 196.995786 132.651341) (xy 196.942634 132.592458)
				(xy 196.900408 132.528375) (xy 196.87255 132.445992) (xy 196.8625 132.332206)
			)
		)
	)
	(zone
		(net 532)
		(net_name "/Backplane/PCIe_{x2}.RX0+")
		(layer "F.Cu")
		(name "$teardrop_padvia$")
		(hatch none 0.1)
		(priority 32040)
		(attr
			(teardrop
				(type padvia)
			)
		)
		(connect_pads yes
			(clearance 0)
		)
		(min_thickness 0.0254)
		(filled_areas_thickness no)
		(fill yes
			(thermal_gap 0.5)
			(thermal_bridge_width 0.5)
			(island_removal_mode 1)
			(island_area_min 10)
		)
		(polygon
			(pts
				(xy 315.420707 159.857457) (xy 315.415464 159.865586) (xy 315.410415 159.870945) (xy 315.407665 159.835766)
				(xy 315.134035 159.910258) (xy 315.211576 160.035) (xy 315.288302 160.025517) (xy 315.375617 160.04195)
				(xy 315.428109 160.053488) (xy 315.472967 160.052579)
			)
		)
	)
	(zone
		(net 9)
		(net_name "/Com Express 7 Interfaces/PCIe_{B1x2}.TX0+")
		(layer "F.Cu")
		(name "$teardrop_padvia$")
		(hatch none 0.1)
		(priority 31442)
		(attr
			(teardrop
				(type padvia)
			)
		)
		(connect_pads yes
			(clearance 0)
		)
		(min_thickness 0.0254)
		(filled_areas_thickness no)
		(fill yes
			(thermal_gap 0.5)
			(thermal_bridge_width 0.5)
			(island_removal_mode 1)
			(island_area_min 10)
		)
		(polygon
			(pts
				(xy 203.433957 124.151858) (xy 203.462996 124.187594) (xy 203.478152 124.221341) (xy 203.479242 124.285996)
				(xy 203.468123 124.330387) (xy 203.45569 124.380172) (xy 203.450927 124.43564) (xy 203.672311 124.429103)
				(xy 203.816381 124.261089) (xy 203.692236 124.134325) (xy 203.576793 124.009022)
			)
		)
	)
	(zone
		(net 294)
		(net_name "/2xUSB3.0+RJ45/GbE.MDI0-")
		(layer "F.Cu")
		(name "$teardrop_padvia$")
		(hatch none 0.1)
		(priority 31582)
		(attr
			(teardrop
				(type padvia)
			)
		)
		(connect_pads yes
			(clearance 0)
		)
		(min_thickness 0.0254)
		(filled_areas_thickness no)
		(fill yes
			(thermal_gap 0.5)
			(thermal_bridge_width 0.5)
			(island_removal_mode 1)
			(island_area_min 10)
		)
		(polygon
			(pts
				(xy 135.41879 110.860225) (xy 135.390556 110.837953) (xy 135.343313 110.798167) (xy 135.326442 110.772093)
				(xy 135.32 110.740273) (xy 134.834293 110.729293) (xy 134.859028 110.895) (xy 135.073068 110.889518)
				(xy 135.157232 110.89706) (xy 135.227353 110.91411) (xy 135.274034 110.935991) (xy 135.312725 110.96629)
			)
		)
	)
	(zone
		(net 371)
		(net_name "/Com Express 7 MGMT/I2C.SCL")
		(layer "F.Cu")
		(name "$teardrop_padvia$")
		(hatch none 0.1)
		(priority 31900)
		(attr
			(teardrop
				(type padvia)
			)
		)
		(connect_pads yes
			(clearance 0)
		)
		(min_thickness 0.0254)
		(filled_areas_thickness no)
		(fill yes
			(thermal_gap 0.5)
			(thermal_bridge_width 0.5)
			(island_removal_mode 1)
			(island_area_min 10)
		)
		(polygon
			(pts
				(xy 192.0875 162.022123) (xy 192.092272 161.987385) (xy 192.10568 161.964833) (xy 192.14786 161.947104)
				(xy 192.21704 161.947773) (xy 192.318895 161.945677) (xy 192.275 161.724) (xy 192.054323 161.681105)
				(xy 192.01662 161.798191) (xy 192.008216 161.816868) (xy 191.976383 161.90006) (xy 191.9625 162.022123)
			)
		)
	)
	(zone
		(net 533)
		(net_name "/Com Express 7 MGMT/PSON")
		(layer "F.Cu")
		(name "$teardrop_padvia$")
		(hatch none 0.1)
		(priority 30998)
		(attr
			(teardrop
				(type padvia)
			)
		)
		(connect_pads yes
			(clearance 0)
		)
		(min_thickness 0.0254)
		(filled_areas_thickness no)
		(fill yes
			(thermal_gap 0.5)
			(thermal_bridge_width 0.5)
			(island_removal_mode 1)
			(island_area_min 10)
		)
		(polygon
			(pts
				(xy 302.137 137.8675) (xy 302.199866 137.887469) (xy 302.231844 137.913921) (xy 302.260358 137.951332)
				(xy 302.282882 137.998527) (xy 302.298093 138.056167) (xy 302.298202 138.056798) (xy 302.576 137.805)
				(xy 302.298202 137.553202) (xy 302.283905 137.608635) (xy 302.262825 137.65452) (xy 302.23546 137.692201)
				(xy 302.204552 137.719434) (xy 302.171265 137.736472) (xy 302.138434 137.742489) (xy 302.137 137.7425)
			)
		)
	)
	(zone
		(net 684)
		(net_name "Net-(U45C-ST)")
		(layer "F.Cu")
		(name "$teardrop_padvia$")
		(hatch none 0.1)
		(priority 31067)
		(attr
			(teardrop
				(type padvia)
			)
		)
		(connect_pads yes
			(clearance 0)
		)
		(min_thickness 0.0254)
		(filled_areas_thickness no)
		(fill yes
			(thermal_gap 0.5)
			(thermal_bridge_width 0.5)
			(island_removal_mode 1)
			(island_area_min 10)
		)
		(polygon
			(pts
				(xy 125.733 134.8175) (xy 125.673588 134.797727) (xy 125.617503 134.734453) (xy 125.595801 134.685828)
				(xy 125.581127 134.626468) (xy 125.579347 134.6145) (xy 125.319 134.88) (xy 125.579347 135.1455)
				(xy 125.592197 135.085361) (xy 125.612131 135.035477) (xy 125.638056 134.995358) (xy 125.667876 134.966345)
				(xy 125.699294 134.948854) (xy 125.731105 134.942521) (xy 125.733 134.9425)
			)
		)
	)
	(zone
		(net 688)
		(net_name "/2xSFP+/KR to SFI #2/KR_R.RX-")
		(layer "F.Cu")
		(name "$teardrop_padvia$")
		(hatch none 0.1)
		(priority 31951)
		(attr
			(teardrop
				(type padvia)
			)
		)
		(connect_pads yes
			(clearance 0)
		)
		(min_thickness 0.0254)
		(filled_areas_thickness no)
		(fill yes
			(thermal_gap 0.5)
			(thermal_bridge_width 0.5)
			(island_removal_mode 1)
			(island_area_min 10)
		)
		(polygon
			(pts
				(xy 134.52 146.717279) (xy 134.508264 146.740315) (xy 134.485802 146.756014) (xy 134.409443 146.765137)
				(xy 134.351231 146.76) (xy 134.41 146.991) (xy 134.61 147.018536) (xy 134.614353 146.919743) (xy 134.655938 146.786651)
				(xy 134.68 146.717279)
			)
		)
	)
	(zone
		(net 74)
		(net_name "+1V0")
		(layer "F.Cu")
		(name "$teardrop_padvia$")
		(hatch none 0.1)
		(priority 30086)
		(attr
			(teardrop
				(type padvia)
			)
		)
		(connect_pads yes
			(clearance 0)
		)
		(min_thickness 0.0254)
		(filled_areas_thickness no)
		(fill yes
			(thermal_gap 0.5)
			(thermal_bridge_width 0.5)
			(island_removal_mode 1)
			(island_area_min 10)
		)
		(polygon
			(pts
				(xy 202.376404 72.702163) (xy 202.285027 72.697312) (xy 202.213098 72.683354) (xy 202.111548 72.636414)
				(xy 202.032705 72.576993) (xy 201.916949 72.490362) (xy 201.70761 72.802163) (xy 201.916949 73.113964)
				(xy 202.032704 73.027333) (xy 202.099586 72.975993) (xy 202.169321 72.936497) (xy 202.256673 72.911127)
				(xy 202.376404 72.902163)
			)
		)
	)
	(zone
		(net 1)
		(net_name "GND")
		(layer "F.Cu")
		(name "$teardrop_padvia$")
		(hatch none 0.1)
		(priority 30554)
		(attr
			(teardrop
				(type padvia)
			)
		)
		(connect_pads yes
			(clearance 0)
		)
		(min_thickness 0.0254)
		(filled_areas_thickness no)
		(fill yes
			(thermal_gap 0.5)
			(thermal_bridge_width 0.5)
			(island_removal_mode 1)
			(island_area_min 10)
		)
		(polygon
			(pts
				(xy 213.425 155.75) (xy 213.428333 155.764486) (xy 213.43119 155.79461) (xy 213.419036 155.805651)
				(xy 213.39 155.81) (xy 213.525 156.686) (xy 213.66 155.81) (xy 213.630666 155.805525) (xy 213.618642 155.794199)
				(xy 213.621667 155.764486) (xy 213.625 155.75)
			)
		)
	)
	(zone
		(net 749)
		(net_name "Net-(U45C-AMUXB)")
		(layer "F.Cu")
		(name "$teardrop_padvia$")
		(hatch none 0.1)
		(priority 30130)
		(attr
			(teardrop
				(type padvia)
			)
		)
		(connect_pads yes
			(clearance 0)
		)
		(min_thickness 0.0254)
		(filled_areas_thickness no)
		(fill yes
			(thermal_gap 0.5)
			(thermal_bridge_width 0.5)
			(island_removal_mode 1)
			(island_area_min 10)
		)
		(polygon
			(pts
				(xy 136.3025 129.377794) (xy 136.307315 129.295733) (xy 136.321019 129.230388) (xy 136.367576 129.13712)
				(xy 136.435787 129.058657) (xy 136.491942 128.997158) (xy 136.551801 128.918339) (xy 136.24 128.709)
				(xy 135.928199 128.918339) (xy 136.025219 129.038517) (xy 136.044214 129.058658) (xy 136.097366 129.117541)
				(xy 136.139591 129.181624) (xy 136.167449 129.264008) (xy 136.1775 129.377794)
			)
		)
	)
	(zone
		(net 2)
		(net_name "+3V3")
		(layer "F.Cu")
		(name "$teardrop_padvia$")
		(hatch none 0.1)
		(priority 30389)
		(attr
			(teardrop
				(type padvia)
			)
		)
		(connect_pads yes
			(clearance 0)
		)
		(min_thickness 0.0254)
		(filled_areas_thickness no)
		(fill yes
			(thermal_gap 0.5)
			(thermal_bridge_width 0.5)
			(island_removal_mode 1)
			(island_area_min 10)
		)
		(polygon
			(pts
				(xy 192.034808 134.738775) (xy 192.080473 134.755814) (xy 192.117366 134.76622) (xy 192.146228 134.783113)
				(xy 192.154938 134.811981) (xy 192.131377 134.858313) (xy 192.502912 134.856155) (xy 192.508037 134.48403)
				(xy 192.474233 134.503793) (xy 192.4494 134.506744) (xy 192.422984 134.484443) (xy 192.405604 134.43155)
				(xy 192.38836 134.385222)
			)
		)
	)
	(zone
		(net 1)
		(net_name "GND")
		(layer "F.Cu")
		(name "$teardrop_padvia$")
		(hatch none 0.1)
		(priority 30567)
		(attr
			(teardrop
				(type padvia)
			)
		)
		(connect_pads yes
			(clearance 0)
		)
		(min_thickness 0.0254)
		(filled_areas_thickness no)
		(fill yes
			(thermal_gap 0.5)
			(thermal_bridge_width 0.5)
			(island_removal_mode 1)
			(island_area_min 10)
		)
		(polygon
			(pts
				(xy 194.425 167.75) (xy 194.428333 167.764486) (xy 194.43119 167.79461) (xy 194.419036 167.805651)
				(xy 194.39 167.81) (xy 194.525 168.686) (xy 194.66 167.81) (xy 194.630666 167.805525) (xy 194.618642 167.794199)
				(xy 194.621667 167.764486) (xy 194.625 167.75)
			)
		)
	)
	(zone
		(net 1)
		(net_name "GND")
		(layer "F.Cu")
		(name "$teardrop_padvia$")
		(hatch none 0.1)
		(priority 31933)
		(attr
			(teardrop
				(type padvia)
			)
		)
		(connect_pads yes
			(clearance 0)
		)
		(min_thickness 0.0254)
		(filled_areas_thickness no)
		(fill yes
			(thermal_gap 0.5)
			(thermal_bridge_width 0.5)
			(island_removal_mode 1)
			(island_area_min 10)
		)
		(polygon
			(pts
				(xy 97.402 151.117) (xy 97.402153 151.127115) (xy 97.40154 151.157832) (xy 97.393218 151.19032)
				(xy 97.369325 151.219475) (xy 97.322 151.240191) (xy 97.502 151.473) (xy 97.682 151.240191) (xy 97.646099 151.226833)
				(xy 97.622801 151.208601) (xy 97.603101 151.163276) (xy 97.601847 151.127115) (xy 97.602 151.117)
			)
		)
	)
	(zone
		(net 947)
		(net_name "/2xSFP+/KR to SFI #2/SFI_R.TX+")
		(layer "F.Cu")
		(name "$teardrop_padvia$")
		(hatch none 0.1)
		(priority 31170)
		(attr
			(teardrop
				(type padvia)
			)
		)
		(connect_pads yes
			(clearance 0)
		)
		(min_thickness 0.0254)
		(filled_areas_thickness no)
		(fill yes
			(thermal_gap 0.5)
			(thermal_bridge_width 0.5)
			(island_removal_mode 1)
			(island_area_min 10)
		)
		(polygon
			(pts
				(xy 129.06 143.17679) (xy 129.064788 143.139695) (xy 129.078304 143.115431) (xy 129.120007 143.096705)
				(xy 129.208927 143.101889) (xy 129.274222 143.108714) (xy 129.338773 143.105196) (xy 129.29 142.859)
				(xy 129.044804 142.811227) (xy 129.008876 142.909201) (xy 128.972391 142.964616) (xy 128.922365 143.048601)
				(xy 128.906125 143.104227) (xy 128.9 143.17679)
			)
		)
	)
	(zone
		(net 785)
		(net_name "Net-(U33-1Y)")
		(layer "F.Cu")
		(name "$teardrop_padvia$")
		(hatch none 0.1)
		(priority 31989)
		(attr
			(teardrop
				(type padvia)
			)
		)
		(connect_pads yes
			(clearance 0)
		)
		(min_thickness 0.0254)
		(filled_areas_thickness no)
		(fill yes
			(thermal_gap 0.5)
			(thermal_bridge_width 0.5)
			(island_removal_mode 1)
			(island_area_min 10)
		)
		(polygon
			(pts
				(xy 249.9065 132.452) (xy 249.895563 132.490823) (xy 249.873805 132.505933) (xy 249.834 132.512)
				(xy 249.969 132.888) (xy 250.104 132.512) (xy 250.068719 132.507483) (xy 250.047203 132.495862)
				(xy 250.032005 132.463039) (xy 250.0315 132.452)
			)
		)
	)
	(zone
		(net 627)
		(net_name "/PCIe redriver/TX_FG1")
		(layer "F.Cu")
		(name "$teardrop_padvia$")
		(hatch none 0.1)
		(priority 32046)
		(attr
			(teardrop
				(type padvia)
			)
		)
		(connect_pads yes
			(clearance 0)
		)
		(min_thickness 0.0254)
		(filled_areas_thickness no)
		(fill yes
			(thermal_gap 0.5)
			(thermal_bridge_width 0.5)
			(island_removal_mode 1)
			(island_area_min 10)
		)
		(polygon
			(pts
				(xy 112.859323 151.437499) (xy 112.827186 151.442236) (xy 112.800616 151.455393) (xy 112.762231 151.504413)
				(xy 112.748469 151.581271) (xy 112.755051 151.623692) (xy 112.771448 151.660998) (xy 112.809829 151.696357)
				(xy 112.899 151.51) (xy 112.908817 151.303641) (xy 112.862145 151.319531) (xy 112.817184 151.374636)
				(xy 112.790136 151.465275) (xy 112.792254 151.505897) (xy 112.806243 151.538506) (xy 112.825113 151.55473)
				(xy 112.851951 151.562211) (xy 112.859323 151.562499)
			)
		)
	)
	(zone
		(net 2)
		(net_name "+3V3")
		(layer "F.Cu")
		(name "$teardrop_padvia$")
		(hatch none 0.1)
		(priority 31458)
		(attr
			(teardrop
				(type padvia)
			)
		)
		(connect_pads yes
			(clearance 0)
		)
		(min_thickness 0.0254)
		(filled_areas_thickness no)
		(fill yes
			(thermal_gap 0.5)
			(thermal_bridge_width 0.5)
			(island_removal_mode 1)
			(island_area_min 10)
		)
		(polygon
			(pts
				(xy 215.98 125.949283) (xy 215.984732 125.899835) (xy 215.997857 125.862139) (xy 216.042935 125.809474)
				(xy 216.076182 125.785129) (xy 216.156204 125.716502) (xy 215.986207 125.573416) (xy 215.76553 125.618311)
				(xy 215.78043 125.718303) (xy 215.782502 125.801779) (xy 215.781659 125.838753) (xy 215.78 125.949283)
			)
		)
	)
	(zone
		(net 333)
		(net_name "/Com Express 7 Interfaces/SDIO.DAT3")
		(layer "F.Cu")
		(name "$teardrop_padvia$")
		(hatch none 0.1)
		(priority 30044)
		(attr
			(teardrop
				(type padvia)
			)
		)
		(connect_pads yes
			(clearance 0)
		)
		(min_thickness 0.0254)
		(filled_areas_thickness no)
		(fill yes
			(thermal_gap 0.5)
			(thermal_bridge_width 0.5)
			(island_removal_mode 1)
			(island_area_min 10)
		)
		(polygon
			(pts
				(xy 110.595 137.819) (xy 110.563366 137.813903) (xy 110.532489 137.798222) (xy 110.505162 137.772417)
				(xy 110.482138 137.735622) (xy 110.465474 137.688468) (xy 110.456279 137.629788) (xy 110.455 137.595)
				(xy 109.504 137.91) (xy 110.455 138.225) (xy 110.459723 138.160141) (xy 110.472784 138.107088) (xy 110.492459 138.065444)
				(xy 110.517125 138.034553) (xy 110.545573 138.013687) (xy 110.575742 138.002878) (xy 110.595 138.001)
			)
		)
	)
	(zone
		(net 527)
		(net_name "/Backplane/GPIO")
		(layer "F.Cu")
		(name "$teardrop_padvia$")
		(hatch none 0.1)
		(priority 30031)
		(attr
			(teardrop
				(type padvia)
			)
		)
		(connect_pads yes
			(clearance 0)
		)
		(min_thickness 0.0254)
		(filled_areas_thickness no)
		(fill yes
			(thermal_gap 0.5)
			(thermal_bridge_width 0.5)
			(island_removal_mode 1)
			(island_area_min 10)
		)
		(polygon
			(pts
				(xy 317.84 165.7725) (xy 317.902625 165.792823) (xy 317.933436 165.819267) (xy 317.960377 165.856912)
				(xy 317.990273 165.944727) (xy 319.451 165.71) (xy 317.990273 165.475273) (xy 317.976502 165.527739)
				(xy 317.956084 165.570431) (xy 317.929557 165.604843) (xy 317.89976 165.629005) (xy 317.84 165.6475)
			)
		)
	)
	(zone
		(net 288)
		(net_name "/2xUSB3.0+RJ45/~{GBE0_LINK_1000}")
		(layer "F.Cu")
		(name "$teardrop_padvia$")
		(hatch none 0.1)
		(priority 31742)
		(attr
			(teardrop
				(type padvia)
			)
		)
		(connect_pads yes
			(clearance 0)
		)
		(min_thickness 0.0254)
		(filled_areas_thickness no)
		(fill yes
			(thermal_gap 0.5)
			(thermal_bridge_width 0.5)
			(island_removal_mode 1)
			(island_area_min 10)
		)
		(polygon
			(pts
				(xy 126.099323 111.2625) (xy 126.168764 111.267318) (xy 126.220088 111.28104) (xy 126.295629 111.327755)
				(xy 126.307769 111.337299) (xy 126.374997 111.387081) (xy 126.501 111.2) (xy 126.374997 111.012919)
				(xy 126.307768 111.062702) (xy 126.224602 111.117106) (xy 126.171748 111.13219) (xy 126.099323 111.1375)
			)
		)
	)
	(zone
		(net 532)
		(net_name "/Backplane/PCIe_{x2}.RX0+")
		(layer "F.Cu")
		(name "$teardrop_padvia$")
		(hatch none 0.1)
		(priority 30253)
		(attr
			(teardrop
				(type padvia)
			)
		)
		(connect_pads yes
			(clearance 0)
		)
		(min_thickness 0.0254)
		(filled_areas_thickness no)
		(fill yes
			(thermal_gap 0.5)
			(thermal_bridge_width 0.5)
			(island_removal_mode 1)
			(island_area_min 10)
		)
		(polygon
			(pts
				(xy 201.4795 155.75) (xy 201.48258 155.764227) (xy 201.484749 155.794527) (xy 201.471877 155.805628)
				(xy 201.441705 155.81) (xy 201.525 156.686) (xy 201.675 156.437021) (xy 201.655644 156.195818) (xy 201.670401 155.923112)
				(xy 201.6815 155.75)
			)
		)
	)
	(zone
		(net 698)
		(net_name "Net-(U5-IO0_7)")
		(layer "F.Cu")
		(name "$teardrop_padvia$")
		(hatch none 0.1)
		(priority 32006)
		(attr
			(teardrop
				(type padvia)
			)
		)
		(connect_pads yes
			(clearance 0)
		)
		(min_thickness 0.0254)
		(filled_areas_thickness no)
		(fill yes
			(thermal_gap 0.5)
			(thermal_bridge_width 0.5)
			(island_removal_mode 1)
			(island_area_min 10)
		)
		(polygon
			(pts
				(xy 158.6125 163.0095) (xy 158.612404 163.003178) (xy 158.617989 162.963675) (xy 158.632922 162.945452)
				(xy 158.6625 162.932504) (xy 158.55 162.546) (xy 158.4375 162.932504) (xy 158.464493 162.94362)
				(xy 158.479595 162.959147) (xy 158.487596 163.003178) (xy 158.4875 163.0095)
			)
		)
	)
	(zone
		(net 626)
		(net_name "/PCIe redriver/TX_FG0")
		(layer "F.Cu")
		(name "$teardrop_padvia$")
		(hatch none 0.1)
		(priority 30927)
		(attr
			(teardrop
				(type padvia)
			)
		)
		(connect_pads yes
			(clearance 0)
		)
		(min_thickness 0.0254)
		(filled_areas_thickness no)
		(fill yes
			(thermal_gap 0.5)
			(thermal_bridge_width 0.5)
			(island_removal_mode 1)
			(island_area_min 10)
		)
		(polygon
			(pts
				(xy 113.962 150.9025) (xy 114.024866 150.922469) (xy 114.056844 150.948921) (xy 114.085358 150.986332)
				(xy 114.107882 151.033527) (xy 114.123093 151.091167) (xy 114.123202 151.091798) (xy 114.401 150.84)
				(xy 114.123202 150.588202) (xy 114.108905 150.643635) (xy 114.087825 150.68952) (xy 114.06046 150.727201)
				(xy 114.029552 150.754434) (xy 113.996265 150.771472) (xy 113.963434 150.777489) (xy 113.962 150.7775)
			)
		)
	)
	(zone
		(net 1)
		(net_name "GND")
		(layer "F.Cu")
		(name "$teardrop_padvia$")
		(hatch none 0.1)
		(priority 31296)
		(attr
			(teardrop
				(type padvia)
			)
		)
		(connect_pads yes
			(clearance 0)
		)
		(min_thickness 0.0254)
		(filled_areas_thickness no)
		(fill yes
			(thermal_gap 0.5)
			(thermal_bridge_width 0.5)
			(island_removal_mode 1)
			(island_area_min 10)
		)
		(polygon
			(pts
				(xy 240.304031 131.02261) (xy 240.252272 130.964186) (xy 240.219889 130.913436) (xy 240.18529 130.819297)
				(xy 240.155257 130.728879) (xy 239.949293 130.809293) (xy 239.868879 131.015257) (xy 239.959297 131.04529)
				(xy 240.055111 131.080762) (xy 240.105114 131.112979) (xy 240.16261 131.164031)
			)
		)
	)
	(zone
		(net 603)
		(net_name "Net-(U37-~{OE1})")
		(layer "F.Cu")
		(name "$teardrop_padvia$")
		(hatch none 0.1)
		(priority 31011)
		(attr
			(teardrop
				(type padvia)
			)
		)
		(connect_pads yes
			(clearance 0)
		)
		(min_thickness 0.0254)
		(filled_areas_thickness no)
		(fill yes
			(thermal_gap 0.5)
			(thermal_bridge_width 0.5)
			(island_removal_mode 1)
			(island_area_min 10)
		)
		(polygon
			(pts
				(xy 213.1325 132.698) (xy 213.152469 132.635134) (xy 213.178921 132.603156) (xy 213.216332 132.574642)
				(xy 213.263527 132.552118) (xy 213.321167 132.536907) (xy 213.321798 132.536798) (xy 213.07 132.259)
				(xy 212.818202 132.536798) (xy 212.873635 132.551095) (xy 212.91952 132.572175) (xy 212.957201 132.59954)
				(xy 212.984434 132.630448) (xy 213.001472 132.663735) (xy 213.007489 132.696566) (xy 213.0075 132.698)
			)
		)
	)
	(zone
		(net 52)
		(net_name "+5V")
		(layer "F.Cu")
		(name "$teardrop_padvia$")
		(hatch none 0.1)
		(priority 30770)
		(attr
			(teardrop
				(type padvia)
			)
		)
		(connect_pads yes
			(clearance 0)
		)
		(min_thickness 0.0254)
		(filled_areas_thickness no)
		(fill yes
			(thermal_gap 0.5)
			(thermal_bridge_width 0.5)
			(island_removal_mode 1)
			(island_area_min 10)
		)
		(polygon
			(pts
				(xy 249.325708 76.160677) (xy 249.33264 76.0031) (xy 249.361164 75.889565) (xy 249.378208 75.847778)
				(xy 249.175708 75.759) (xy 248.973208 75.847778) (xy 249.007591 75.943822) (xy 249.022809 76.045702)
				(xy 249.025708 76.160677)
			)
		)
	)
	(zone
		(net 666)
		(net_name "/2xSFP+/KR to SFI #1/SFI_R.TX+")
		(layer "F.Cu")
		(name "$teardrop_padvia$")
		(hatch none 0.1)
		(priority 31965)
		(attr
			(teardrop
				(type padvia)
			)
		)
		(connect_pads yes
			(clearance 0)
		)
		(min_thickness 0.0254)
		(filled_areas_thickness no)
		(fill yes
			(thermal_gap 0.5)
			(thermal_bridge_width 0.5)
			(island_removal_mode 1)
			(island_area_min 10)
		)
		(polygon
			(pts
				(xy 147.06 146.717279) (xy 147.084062 146.786651) (xy 147.120577 146.896598) (xy 147.130888 146.956686)
				(xy 147.13 147.018536) (xy 147.33 146.991) (xy 147.388769 146.76) (xy 147.307423 146.765298) (xy 147.255406 146.756508)
				(xy 147.233886 146.742657) (xy 147.221647 146.722599) (xy 147.22 146.717279)
			)
		)
	)
	(zone
		(net 207)
		(net_name "/Backplane/UART.TX")
		(layer "F.Cu")
		(name "$teardrop_padvia$")
		(hatch none 0.1)
		(priority 31751)
		(attr
			(teardrop
				(type padvia)
			)
		)
		(connect_pads yes
			(clearance 0)
		)
		(min_thickness 0.0254)
		(filled_areas_thickness no)
		(fill yes
			(thermal_gap 0.5)
			(thermal_bridge_width 0.5)
			(island_removal_mode 1)
			(island_area_min 10)
		)
		(polygon
			(pts
				(xy 230.799323 170.9625) (xy 230.868764 170.967318) (xy 230.920088 170.98104) (xy 230.995629 171.027755)
				(xy 231.007769 171.037299) (xy 231.074997 171.087081) (xy 231.201 170.9) (xy 231.074997 170.712919)
				(xy 231.007768 170.762702) (xy 230.924602 170.817106) (xy 230.871748 170.83219) (xy 230.799323 170.8375)
			)
		)
	)
	(zone
		(net 62)
		(net_name "+12V_AON")
		(layer "F.Cu")
		(hatch edge 0.5)
		(priority 1)
		(connect_pads yes
			(clearance 0.15)
		)
		(min_thickness 0.25)
		(filled_areas_thickness no)
		(fill yes
			(thermal_gap 0.2)
			(thermal_bridge_width 0.5)
			(smoothing fillet)
			(radius 0.2)
		)
		(polygon
			(pts
				(xy 318.75 130.67) (xy 318.75 134.06) (xy 313.775499 134.06) (xy 313.475499 133.76) (xy 312.725499 133.76)
				(xy 312.725499 133.21) (xy 314.984999 130.9505) (xy 314.984999 121.44) (xy 314.464999 120.92) (xy 313.794999 120.92)
				(xy 313.604999 121.11) (xy 313.544998 121.11) (xy 313.544999 119.12) (xy 318.75 119.119999)
			)
		)
	)
	(zone
		(net 208)
		(net_name "/Backplane/UART.RX")
		(layer "F.Cu")
		(name "$teardrop_padvia$")
		(hatch none 0.1)
		(priority 30030)
		(attr
			(teardrop
				(type padvia)
			)
		)
		(connect_pads yes
			(clearance 0)
		)
		(min_thickness 0.0254)
		(filled_areas_thickness no)
		(fill yes
			(thermal_gap 0.5)
			(thermal_bridge_width 0.5)
			(island_removal_mode 1)
			(island_area_min 10)
		)
		(polygon
			(pts
				(xy 317.84 166.5725) (xy 317.902625 166.592823) (xy 317.933436 166.619267) (xy 317.960377 166.656912)
				(xy 317.990273 166.744727) (xy 319.451 166.51) (xy 317.990273 166.275273) (xy 317.976502 166.327739)
				(xy 317.956084 166.370431) (xy 317.929557 166.404843) (xy 317.89976 166.429005) (xy 317.84 166.4475)
			)
		)
	)
	(zone
		(net 47)
		(net_name "/2xUSB3.0+RJ45/USBSS_1.TX-")
		(layer "F.Cu")
		(name "$teardrop_padvia$")
		(hatch none 0.1)
		(priority 31497)
		(attr
			(teardrop
				(type padvia)
			)
		)
		(connect_pads yes
			(clearance 0)
		)
		(min_thickness 0.0254)
		(filled_areas_thickness no)
		(fill yes
			(thermal_gap 0.5)
			(thermal_bridge_width 0.5)
			(island_removal_mode 1)
			(island_area_min 10)
		)
		(polygon
			(pts
				(xy 180.1775 149.909584) (xy 180.173316 149.745141) (xy 180.173177 149.562437) (xy 179.9525 149.549)
				(xy 179.793311 149.702895) (xy 179.860836 149.751773) (xy 179.887179 149.765148) (xy 179.927443 149.786523)
				(xy 179.961001 149.813232) (xy 179.983979 149.852007) (xy 179.9925 149.909584)
			)
		)
	)
	(zone
		(net 867)
		(net_name "/Backplane/PCIe_{x2}.TX0-")
		(layer "F.Cu")
		(name "$teardrop_padvia$")
		(hatch none 0.1)
		(priority 31385)
		(attr
			(teardrop
				(type padvia)
			)
		)
		(connect_pads yes
			(clearance 0)
		)
		(min_thickness 0.0254)
		(filled_areas_thickness no)
		(fill yes
			(thermal_gap 0.5)
			(thermal_bridge_width 0.5)
			(island_removal_mode 1)
			(island_area_min 10)
		)
		(polygon
			(pts
				(xy 268.632504 139.3955) (xy 268.67929 139.400235) (xy 268.714742 139.413379) (xy 268.762939 139.458387)
				(xy 268.787116 139.496608) (xy 268.814485 139.539773) (xy 268.851147 139.581731) (xy 269.001 139.4185)
				(xy 268.98014 139.197823) (xy 268.879466 139.202452) (xy 268.796096 139.199019) (xy 268.794035 139.198895)
				(xy 268.632504 139.1935)
			)
		)
	)
	(zone
		(net 707)
		(net_name "Net-(U24-TACH3)")
		(layer "F.Cu")
		(name "$teardrop_padvia$")
		(hatch none 0.1)
		(priority 31754)
		(attr
			(teardrop
				(type padvia)
			)
		)
		(connect_pads yes
			(clearance 0)
		)
		(min_thickness 0.0254)
		(filled_areas_thickness no)
		(fill yes
			(thermal_gap 0.5)
			(thermal_bridge_width 0.5)
			(island_removal_mode 1)
			(island_area_min 10)
		)
		(polygon
			(pts
				(xy 260.439323 84.522499) (xy 260.508764 84.527317) (xy 260.560088 84.541039) (xy 260.635629 84.587754)
				(xy 260.647769 84.597298) (xy 260.714997 84.64708) (xy 260.841 84.459999) (xy 260.714997 84.272918)
				(xy 260.647768 84.322701) (xy 260.564602 84.377105) (xy 260.511748 84.392189) (xy 260.439323 84.397499)
			)
		)
	)
	(zone
		(net 165)
		(net_name "/2xSFP+/SCL0")
		(layer "F.Cu")
		(name "$teardrop_padvia$")
		(hatch none 0.1)
		(priority 31120)
		(attr
			(teardrop
				(type padvia)
			)
		)
		(connect_pads yes
			(clearance 0)
		)
		(min_thickness 0.0254)
		(filled_areas_thickness no)
		(fill yes
			(thermal_gap 0.5)
			(thermal_bridge_width 0.5)
			(island_removal_mode 1)
			(island_area_min 10)
		)
		(polygon
			(pts
				(xy 177.507 147.0625) (xy 177.566412 147.082273) (xy 177.622497 147.145547) (xy 177.644199 147.194172)
				(xy 177.658873 147.253531) (xy 177.660653 147.2655) (xy 177.921 147) (xy 177.660653 146.7345) (xy 177.647804 146.794638)
				(xy 177.62787 146.844522) (xy 177.601945 146.884641) (xy 177.572125 146.913654) (xy 177.540707 146.931146)
				(xy 177.508896 146.937479) (xy 177.507 146.9375)
			)
		)
	)
	(zone
		(net 750)
		(net_name "Net-(U45C-CLKOUTA+)")
		(layer "F.Cu")
		(name "$teardrop_padvia$")
		(hatch none 0.1)
		(priority 30129)
		(attr
			(teardrop
				(type padvia)
			)
		)
		(connect_pads yes
			(clearance 0)
		)
		(min_thickness 0.0254)
		(filled_areas_thickness no)
		(fill yes
			(thermal_gap 0.5)
			(thermal_bridge_width 0.5)
			(island_removal_mode 1)
			(island_area_min 10)
		)
		(polygon
			(pts
				(xy 136.9525 130.227794) (xy 136.957315 130.145733) (xy 136.971019 130.080388) (xy 137.017576 129.98712)
				(xy 137.085787 129.908657) (xy 137.141942 129.847158) (xy 137.201801 129.768339) (xy 136.89 129.559)
				(xy 136.578199 129.768339) (xy 136.675219 129.888517) (xy 136.694214 129.908658) (xy 136.747366 129.967541)
				(xy 136.789591 130.031624) (xy 136.817449 130.114008) (xy 136.8275 130.227794)
			)
		)
	)
	(zone
		(net 211)
		(net_name "/Com Express 7 Interfaces/PCIe_{B1x4}.TX3-")
		(layer "F.Cu")
		(name "$teardrop_padvia$")
		(hatch none 0.1)
		(priority 30267)
		(attr
			(teardrop
				(type padvia)
			)
		)
		(connect_pads yes
			(clearance 0)
		)
		(min_thickness 0.0254)
		(filled_areas_thickness no)
		(fill yes
			(thermal_gap 0.5)
			(thermal_bridge_width 0.5)
			(island_removal_mode 1)
			(island_area_min 10)
		)
		(polygon
			(pts
				(xy 204.8685 167.75) (xy 204.879599 167.923112) (xy 204.894216 168.15051) (xy 204.891181 168.285138)
				(xy 204.875 168.437021) (xy 205.025 168.686) (xy 205.108295 167.81) (xy 205.077864 167.805523) (xy 205.065097 167.794185)
				(xy 205.06742 167.764227) (xy 205.0705 167.75)
			)
		)
	)
	(zone
		(net 530)
		(net_name "/M.2 key M #2/~{CLKREQ}")
		(layer "F.Cu")
		(name "$teardrop_padvia$")
		(hatch none 0.1)
		(priority 31313)
		(attr
			(teardrop
				(type padvia)
			)
		)
		(connect_pads yes
			(clearance 0)
		)
		(min_thickness 0.0254)
		(filled_areas_thickness no)
		(fill yes
			(thermal_gap 0.5)
			(thermal_bridge_width 0.5)
			(island_removal_mode 1)
			(island_area_min 10)
		)
		(polygon
			(pts
				(xy 298.8865 83.142964) (xy 298.891091 83.204505) (xy 298.897183 83.299705) (xy 298.893086 83.344703)
				(xy 298.88 83.3825) (xy 299.2 83.531) (xy 299.324736 83.235) (xy 299.206601 83.237943) (xy 299.112492 83.227954)
				(xy 299.062951 83.212264) (xy 299.029206 83.188799) (xy 299.0115 83.142964)
			)
		)
	)
	(zone
		(net 50)
		(net_name "Net-(C12-Pad2)")
		(layer "F.Cu")
		(name "$teardrop_padvia$")
		(hatch none 0.1)
		(priority 31305)
		(attr
			(teardrop
				(type padvia)
			)
		)
		(connect_pads yes
			(clearance 0)
		)
		(min_thickness 0.0254)
		(filled_areas_thickness no)
		(fill yes
			(thermal_gap 0.5)
			(thermal_bridge_width 0.5)
			(island_removal_mode 1)
			(island_area_min 10)
		)
		(polygon
			(pts
				(xy 137.399323 101.51) (xy 137.481742 101.514716) (xy 137.543451 101.527728) (xy 137.633097 101.565944)
				(xy 137.717397 101.604643) (xy 137.801 101.4) (xy 137.706705 101.199785) (xy 137.621625 101.246274)
				(xy 137.53159 101.291638) (xy 137.474667 101.305106) (xy 137.399323 101.31)
			)
		)
	)
	(zone
		(net 1)
		(net_name "GND")
		(layer "F.Cu")
		(hatch edge 0.5)
		(priority 30)
		(connect_pads yes
			(clearance 0.15)
		)
		(min_thickness 0.25)
		(filled_areas_thickness no)
		(fill yes
			(thermal_gap 0.5)
			(thermal_bridge_width 0.5)
			(smoothing fillet)
			(radius 0.2)
			(island_removal_mode 1)
			(island_area_min 10)
		)
		(polygon
			(pts
				(xy 289.95 102.31) (xy 291.7 102.31) (xy 291.7 101.66) (xy 291.45 101.41) (xy 290.75 101.41) (xy 290.75 99.91)
				(xy 289.95 99.91)
			)
		)
	)
	(zone
		(net 55)
		(net_name "/USB-C console/USB_D+")
		(layer "F.Cu")
		(name "$teardrop_padvia$")
		(hatch none 0.1)
		(priority 30214)
		(attr
			(teardrop
				(type padvia)
			)
		)
		(connect_pads yes
			(clearance 0)
		)
		(min_thickness 0.0254)
		(filled_areas_thickness no)
		(fill yes
			(thermal_gap 0.5)
			(thermal_bridge_width 0.5)
			(island_removal_mode 1)
			(island_area_min 10)
		)
		(polygon
			(pts
				(xy 106.959555 78.80026) (xy 107.01146 78.755974) (xy 107.077097 78.715393) (xy 107.147077 78.685119)
				(xy 107.227786 78.662918) (xy 107.360838 78.65) (xy 107.279707 78.349293) (xy 106.979 78.268163)
				(xy 106.960961 78.424302) (xy 106.910442 78.557908) (xy 106.834326 78.663748) (xy 106.82874 78.669445)
			)
		)
	)
	(zone
		(net 290)
		(net_name "/2xUSB3.0+RJ45/GbE.MDI2+")
		(layer "F.Cu")
		(name "$teardrop_padvia$")
		(hatch none 0.1)
		(priority 31644)
		(attr
			(teardrop
				(type padvia)
			)
		)
		(connect_pads yes
			(clearance 0)
		)
		(min_thickness 0.0254)
		(filled_areas_thickness no)
		(fill yes
			(thermal_gap 0.5)
			(thermal_bridge_width 0.5)
			(island_removal_mode 1)
			(island_area_min 10)
		)
		(polygon
			(pts
				(xy 166.15 149.457916) (xy 166.145244 149.497838) (xy 166.13195 149.526255) (xy 166.087871 149.558671)
				(xy 166.042738 149.573949) (xy 165.996459 149.589244) (xy 165.949997 149.612919) (xy 166.075 149.801)
				(xy 166.295677 149.801757) (xy 166.297797 149.663281) (xy 166.3 149.457916)
			)
		)
	)
	(zone
		(net 2)
		(net_name "+3V3")
		(layer "F.Cu")
		(name "$teardrop_padvia$")
		(hatch none 0.1)
		(priority 30291)
		(attr
			(teardrop
				(type padvia)
			)
		)
		(connect_pads yes
			(clearance 0)
		)
		(min_thickness 0.0254)
		(filled_areas_thickness no)
		(fill yes
			(thermal_gap 0.5)
			(thermal_bridge_width 0.5)
			(island_removal_mode 1)
			(island_area_min 10)
		)
		(polygon
			(pts
				(xy 233.637707 78.323) (xy 233.627592 78.323153) (xy 233.596876 78.32254) (xy 233.564387 78.314218)
				(xy 233.535233 78.290325) (xy 233.514516 78.243) (xy 232.821707 78.423) (xy 233.514516 78.603) (xy 233.527875 78.567099)
				(xy 233.546106 78.543801) (xy 233.591432 78.524101) (xy 233.627592 78.522847) (xy 233.637707 78.523)
			)
		)
	)
	(zone
		(net 603)
		(net_name "Net-(U37-~{OE1})")
		(layer "F.Cu")
		(name "$teardrop_padvia$")
		(hatch none 0.1)
		(priority 30992)
		(attr
			(teardrop
				(type padvia)
			)
		)
		(connect_pads yes
			(clearance 0)
		)
		(min_thickness 0.0254)
		(filled_areas_thickness no)
		(fill yes
			(thermal_gap 0.5)
			(thermal_bridge_width 0.5)
			(island_removal_mode 1)
			(island_area_min 10)
		)
		(polygon
			(pts
				(xy 213.0075 132.822) (xy 212.987531 132.884866) (xy 212.961079 132.916844) (xy 212.923668 132.945358)
				(xy 212.876473 132.967882) (xy 212.818833 132.983093) (xy 212.818202 132.983202) (xy 213.07 133.261)
				(xy 213.321798 132.983202) (xy 213.266365 132.968905) (xy 213.22048 132.947825) (xy 213.182799 132.92046)
				(xy 213.155566 132.889552) (xy 213.138528 132.856265) (xy 213.132511 132.823434) (xy 213.1325 132.822)
			)
		)
	)
	(zone
		(net 323)
		(net_name "/Com Express 7 Interfaces/SDIO.DAT2")
		(layer "F.Cu")
		(name "$teardrop_padvia$")
		(hatch none 0.1)
		(priority 31330)
		(attr
			(teardrop
				(type padvia)
			)
		)
		(connect_pads yes
			(clearance 0)
		)
		(min_thickness 0.0254)
		(filled_areas_thickness no)
		(fill yes
			(thermal_gap 0.5)
			(thermal_bridge_width 0.5)
			(island_removal_mode 1)
			(island_area_min 10)
		)
		(polygon
			(pts
				(xy 112.959323 138.495352) (xy 113.032826 138.50005) (xy 113.088638 138.512939) (xy 113.178629 138.557481)
				(xy 113.272222 138.606852) (xy 113.361 138.404352) (xy 113.272222 138.201852) (xy 113.178627 138.251224)
				(xy 113.090015 138.295304) (xy 113.033711 138.308526) (xy 112.959323 138.313352)
			)
		)
	)
	(zone
		(net 609)
		(net_name "Net-(U37-~{CKPWRGD_PD})")
		(layer "F.Cu")
		(name "$teardrop_padvia$")
		(hatch none 0.1)
		(priority 31126)
		(attr
			(teardrop
				(type padvia)
			)
		)
		(connect_pads yes
			(clearance 0)
		)
		(min_thickness 0.0254)
		(filled_areas_thickness no)
		(fill yes
			(thermal_gap 0.5)
			(thermal_bridge_width 0.5)
			(island_removal_mode 1)
			(island_area_min 10)
		)
		(polygon
			(pts
				(xy 218.837 124.9625) (xy 218.896412 124.982273) (xy 218.952497 125.045547) (xy 218.974199 125.094172)
				(xy 218.988873 125.153531) (xy 218.990653 125.1655) (xy 219.251 124.9) (xy 218.990653 124.6345)
				(xy 218.977804 124.694638) (xy 218.95787 124.744522) (xy 218.931945 124.784641) (xy 218.902125 124.813654)
				(xy 218.870707 124.831146) (xy 218.838896 124.837479) (xy 218.837 124.8375)
			)
		)
	)
	(zone
		(net 83)
		(net_name "Net-(Q11-D)")
		(layer "F.Cu")
		(name "$teardrop_padvia$")
		(hatch none 0.1)
		(priority 30004)
		(attr
			(teardrop
				(type padvia)
			)
		)
		(connect_pads yes
			(clearance 0)
		)
		(min_thickness 0.0254)
		(filled_areas_thickness no)
		(fill yes
			(thermal_gap 0.5)
			(thermal_bridge_width 0.5)
			(island_removal_mode 1)
			(island_area_min 10)
		)
		(polygon
			(pts
				(xy 180.7715 72.123667) (xy 180.776371 72.004177) (xy 180.790465 71.901096) (xy 180.811818 71.815884)
				(xy 180.840196 71.741549) (xy 180.917758 71.614403) (xy 181.03525 71.489563) (xy 181.098032 71.432294)
				(xy 181.25418 71.283519) (xy 181.335059 71.191721) (xy 181.415749 71.082235) (xy 180.709 70.609)
				(xy 180.002251 71.082235) (xy 180.139827 71.257784) (xy 180.319968 71.432295) (xy 180.448348 71.554288)
				(xy 180.503867 71.619091) (xy 180.551998 71.691181) (xy 180.591533 71.774122) (xy 180.621266 71.871474)
				(xy 180.63999 71.986802) (xy 180.6465 72.123667)
			)
		)
	)
	(zone
		(net 953)
		(net_name "/2xSFP+/KR to SFI #2/SFI_R.RX-")
		(layer "F.Cu")
		(name "$teardrop_padvia$")
		(hatch none 0.1)
		(priority 31165)
		(attr
			(teardrop
				(type padvia)
			)
		)
		(connect_pads yes
			(clearance 0)
		)
		(min_thickness 0.0254)
		(filled_areas_thickness no)
		(fill yes
			(thermal_gap 0.5)
			(thermal_bridge_width 0.5)
			(island_removal_mode 1)
			(island_area_min 10)
		)
		(polygon
			(pts
				(xy 132.06 143.17679) (xy 132.064788 143.139695) (xy 132.078304 143.115431) (xy 132.120007 143.096705)
				(xy 132.208927 143.101889) (xy 132.274222 143.108714) (xy 132.338773 143.105196) (xy 132.29 142.859)
				(xy 132.044804 142.811227) (xy 132.008876 142.909201) (xy 131.972391 142.964616) (xy 131.922365 143.048601)
				(xy 131.906125 143.104227) (xy 131.9 143.17679)
			)
		)
	)
	(zone
		(net 1)
		(net_name "GND")
		(layer "F.Cu")
		(name "$teardrop_padvia$")
		(hatch none 0.1)
		(priority 30568)
		(attr
			(teardrop
				(type padvia)
			)
		)
		(connect_pads yes
			(clearance 0)
		)
		(min_thickness 0.0254)
		(filled_areas_thickness no)
		(fill yes
			(thermal_gap 0.5)
			(thermal_bridge_width 0.5)
			(island_removal_mode 1)
			(island_area_min 10)
		)
		(polygon
			(pts
				(xy 181.125 169.62) (xy 181.121667 169.605514) (xy 181.11881 169.57539) (xy 181.130964 169.564349)
				(xy 181.16 169.56) (xy 181.025 168.684) (xy 180.89 169.56) (xy 180.919334 169.564475) (xy 180.931358 169.575801)
				(xy 180.928333 169.605514) (xy 180.925 169.62)
			)
		)
	)
	(zone
		(net 1)
		(net_name "GND")
		(layer "F.Cu")
		(name "$teardrop_padvia$")
		(hatch none 0.1)
		(priority 31192)
		(attr
			(teardrop
				(type padvia)
			)
		)
		(connect_pads yes
			(clearance 0)
		)
		(min_thickness 0.0254)
		(filled_areas_thickness no)
		(fill yes
			(thermal_gap 0.5)
			(thermal_bridge_width 0.5)
			(island_removal_mode 1)
			(island_area_min 10)
		)
		(polygon
			(pts
				(xy 215.625 167.900677) (xy 215.62972 167.831353) (xy 215.642756 167.778449) (xy 215.694658 167.68586)
				(xy 215.746458 167.602363) (xy 215.55 167.499) (xy 215.342355 167.575358) (xy 215.374583 167.655861)
				(xy 215.410965 167.757318) (xy 215.425 167.900677)
			)
		)
	)
	(zone
		(net 1)
		(net_name "GND")
		(layer "F.Cu")
		(name "$teardrop_padvia$")
		(hatch none 0.1)
		(priority 31222)
		(attr
			(teardrop
				(type padvia)
			)
		)
		(connect_pads yes
			(clearance 0)
		)
		(min_thickness 0.0254)
		(filled_areas_thickness no)
		(fill yes
			(thermal_gap 0.5)
			(thermal_bridge_width 0.5)
			(island_removal_mode 1)
			(island_area_min 10)
		)
		(polygon
			(pts
				(xy 201.125 162.300677) (xy 201.129737 162.209676) (xy 201.142896 162.142587) (xy 201.175418 162.055855)
				(xy 201.207644 161.975358) (xy 201 161.899) (xy 200.803541 162.002363) (xy 200.855343 162.085863)
				(xy 200.904833 162.171955) (xy 200.919614 162.22716) (xy 200.925 162.300677)
			)
		)
	)
	(zone
		(net 1)
		(net_name "GND")
		(layer "F.Cu")
		(name "$teardrop_padvia$")
		(hatch none 0.1)
		(priority 31920)
		(attr
			(teardrop
				(type padvia)
			)
		)
		(connect_pads yes
			(clearance 0)
		)
		(min_thickness 0.0254)
		(filled_areas_thickness no)
		(fill yes
			(thermal_gap 0.5)
			(thermal_bridge_width 0.5)
			(island_removal_mode 1)
			(island_area_min 10)
		)
		(polygon
			(pts
				(xy 97.602 151.827) (xy 97.601847 151.816885) (xy 97.60246 151.786168) (xy 97.610782 151.75368)
				(xy 97.634675 151.724525) (xy 97.682 151.703808) (xy 97.502 151.471) (xy 97.322 151.703808) (xy 97.357901 151.717167)
				(xy 97.381199 151.735398) (xy 97.400899 151.780724) (xy 97.402153 151.816885) (xy 97.402 151.827)
			)
		)
	)
	(zone
		(net 292)
		(net_name "/2xUSB3.0+RJ45/GbE.MDI1-")
		(layer "F.Cu")
		(name "$teardrop_padvia$")
		(hatch none 0.1)
		(priority 30302)
		(attr
			(teardrop
				(type padvia)
			)
		)
		(connect_pads yes
			(clearance 0)
		)
		(min_thickness 0.0254)
		(filled_areas_thickness no)
		(fill yes
			(thermal_gap 0.5)
			(thermal_bridge_width 0.5)
			(island_removal_mode 1)
			(island_area_min 10)
		)
		(polygon
			(pts
				(xy 180.025 167.75) (xy 180.025035 167.754084) (xy 180.017242 167.790449) (xy 179.997831 167.804416)
				(xy 179.959759 167.81) (xy 180.025 168.686) (xy 180.175 168.504204) (xy 180.158334 168.198008) (xy 180.167809 167.932252)
				(xy 180.175 167.75)
			)
		)
	)
	(zone
		(net 138)
		(net_name "Net-(U33-1A)")
		(layer "F.Cu")
		(name "$teardrop_padvia$")
		(hatch none 0.1)
		(priority 31987)
		(attr
			(teardrop
				(type padvia)
			)
		)
		(connect_pads yes
			(clearance 0)
		)
		(min_thickness 0.0254)
		(filled_areas_thickness no)
		(fill yes
			(thermal_gap 0.5)
			(thermal_bridge_width 0.5)
			(island_removal_mode 1)
			(island_area_min 10)
		)
		(polygon
			(pts
				(xy 249.9065 129.703) (xy 249.895563 129.741823) (xy 249.873805 129.756933) (xy 249.834 129.763)
				(xy 249.969 130.139) (xy 250.104 129.763) (xy 250.068719 129.758483) (xy 250.047203 129.746862)
				(xy 250.032005 129.714039) (xy 250.0315 129.703)
			)
		)
	)
	(zone
		(net 875)
		(net_name "/2xSFP+/SCL1")
		(layer "F.Cu")
		(name "$teardrop_padvia$")
		(hatch none 0.1)
		(priority 31814)
		(attr
			(teardrop
				(type padvia)
			)
		)
		(connect_pads yes
			(clearance 0)
		)
		(min_thickness 0.0254)
		(filled_areas_thickness no)
		(fill yes
			(thermal_gap 0.5)
			(thermal_bridge_width 0.5)
			(island_removal_mode 1)
			(island_area_min 10)
		)
		(polygon
			(pts
				(xy 176.000677 147.9375) (xy 175.931236 147.932682) (xy 175.879913 147.91896) (xy 175.804371 147.872246)
				(xy 175.792231 147.862701) (xy 175.725003 147.812919) (xy 175.599 148) (xy 175.725003 148.187081)
				(xy 175.792229 148.137299) (xy 175.875396 148.082894) (xy 175.928251 148.06781) (xy 176.000677 148.0625)
			)
		)
	)
	(zone
		(net 132)
		(net_name "Net-(D18-C_{R})")
		(layer "F.Cu")
		(name "$teardrop_padvia$")
		(hatch none 0.1)
		(priority 30025)
		(attr
			(teardrop
				(type padvia)
			)
		)
		(connect_pads yes
			(clearance 0)
		)
		(min_thickness 0.0254)
		(filled_areas_thickness no)
		(fill yes
			(thermal_gap 0.5)
			(thermal_bridge_width 0.5)
			(island_removal_mode 1)
			(island_area_min 10)
		)
		(polygon
			(pts
				(xy 101.729445 74.568942) (xy 101.757148 74.49691) (xy 101.8285 74.42331) (xy 101.948391 74.358232)
				(xy 102.024006 74.334517) (xy 102.106197 74.319665) (xy 102.185985 74.315) (xy 101.710707 73.564293)
				(xy 101.195637 74.315) (xy 101.333208 74.32015) (xy 101.452877 74.336198) (xy 101.529928 74.356934)
				(xy 101.589106 74.385322) (xy 101.619622 74.411527) (xy 101.637442 74.442338) (xy 101.641058 74.480555)
			)
		)
	)
	(zone
		(net 980)
		(net_name "Net-(D27-C)")
		(layer "F.Cu")
		(name "$teardrop_padvia$")
		(hatch none 0.1)
		(priority 30882)
		(attr
			(teardrop
				(type padvia)
			)
		)
		(connect_pads yes
			(clearance 0)
		)
		(min_thickness 0.0254)
		(filled_areas_thickness no)
		(fill yes
			(thermal_gap 0.5)
			(thermal_bridge_width 0.5)
			(island_removal_mode 1)
			(island_area_min 10)
		)
		(polygon
			(pts
				(xy 199.60861 76.259163) (xy 199.602838 76.2999) (xy 199.582434 76.341815) (xy 199.555259 76.370116)
				(xy 199.515713 76.393544) (xy 199.44311 76.412815) (xy 199.70861 76.673163) (xy 199.97411 76.412815)
				(xy 199.920968 76.400948) (xy 199.879929 76.382501) (xy 199.828228 76.331827) (xy 199.808892 76.268258)
				(xy 199.80861 76.259163)
			)
		)
	)
	(zone
		(net 1)
		(net_name "GND")
		(layer "F.Cu")
		(name "$teardrop_padvia$")
		(hatch none 0.1)
		(priority 31321)
		(attr
			(teardrop
				(type padvia)
			)
		)
		(connect_pads yes
			(clearance 0)
		)
		(min_thickness 0.0254)
		(filled_areas_thickness no)
		(fill yes
			(thermal_gap 0.5)
			(thermal_bridge_width 0.5)
			(island_removal_mode 1)
			(island_area_min 10)
		)
		(polygon
			(pts
				(xy 176.625 155.887793) (xy 176.629731 155.832196) (xy 176.64285 155.789645) (xy 176.688022 155.727772)
				(xy 176.711704 155.705388) (xy 176.780694 155.631389) (xy 176.6 155.499) (xy 176.383268 155.553421)
				(xy 176.38519 155.561215) (xy 176.416806 155.710064) (xy 176.425 155.887793)
			)
		)
	)
	(zone
		(net 312)
		(net_name "/2xUSB3.0+RJ45/USB_1.D-")
		(layer "F.Cu")
		(name "$teardrop_padvia$")
		(hatch none 0.1)
		(priority 31496)
		(attr
			(teardrop
				(type padvia)
			)
		)
		(connect_pads yes
			(clearance 0)
		)
		(min_thickness 0.0254)
		(filled_areas_thickness no)
		(fill yes
			(thermal_gap 0.5)
			(thermal_bridge_width 0.5)
			(island_removal_mode 1)
			(island_area_min 10)
		)
		(polygon
			(pts
				(xy 196.6775 167.359584) (xy 196.673316 167.195141) (xy 196.673177 167.012437) (xy 196.4525 166.999)
				(xy 196.293311 167.152895) (xy 196.360836 167.201773) (xy 196.387179 167.215148) (xy 196.427443 167.236523)
				(xy 196.461001 167.263232) (xy 196.483979 167.302007) (xy 196.4925 167.359584)
			)
		)
	)
	(zone
		(net 186)
		(net_name "/OCuLink/PCIe_{x4}.RX0+")
		(layer "F.Cu")
		(name "$teardrop_padvia$")
		(hatch none 0.1)
		(priority 32088)
		(attr
			(teardrop
				(type padvia)
			)
		)
		(connect_pads yes
			(clearance 0)
		)
		(min_thickness 0.0254)
		(filled_areas_thickness no)
		(fill yes
			(thermal_gap 0.5)
			(thermal_bridge_width 0.5)
			(island_removal_mode 1)
			(island_area_min 10)
		)
		(polygon
			(pts
				(xy 96.401 151.147) (xy 96.408198 151.167648) (xy 96.417792 151.199984) (xy 96.410965 151.214007)
				(xy 96.3895 151.223995) (xy 96.502 151.473) (xy 96.6145 151.223995) (xy 96.593324 151.214271) (xy 96.586269 151.200643)
				(xy 96.595802 151.167648) (xy 96.603 151.147)
			)
		)
	)
	(zone
		(net 581)
		(net_name "Net-(U19-FB)")
		(layer "F.Cu")
		(name "$teardrop_padvia$")
		(hatch none 0.1)
		(priority 32138)
		(attr
			(teardrop
				(type padvia)
			)
		)
		(connect_pads yes
			(clearance 0)
		)
		(min_thickness 0.0254)
		(filled_areas_thickness no)
		(fill yes
			(thermal_gap 0.5)
			(thermal_bridge_width 0.5)
			(island_removal_mode 1)
			(island_area_min 10)
		)
		(polygon
			(pts
				(xy 309.97692 105.264499) (xy 309.993646 105.263084) (xy 310.03397 105.263109) (xy 310.054265 105.272236)
				(xy 310.072521 105.292564) (xy 310.315999 105.203999) (xy 310.079358 105.112602) (xy 310.060468 105.131759)
				(xy 310.039973 105.140813) (xy 309.995139 105.14104) (xy 309.97692 105.139499)
			)
		)
	)
	(zone
		(net 2)
		(net_name "+3V3")
		(layer "F.Cu")
		(name "$teardrop_padvia$")
		(hatch none 0.1)
		(priority 30909)
		(attr
			(teardrop
				(type padvia)
			)
		)
		(connect_pads yes
			(clearance 0)
		)
		(min_thickness 0.0254)
		(filled_areas_thickness no)
		(fill yes
			(thermal_gap 0.5)
			(thermal_bridge_width 0.5)
			(island_removal_mode 1)
			(island_area_min 10)
		)
		(polygon
			(pts
				(xy 262.41 93.187) (xy 262.392933 93.188041) (xy 262.362146 93.189052) (xy 262.332008 93.18001)
				(xy 262.309099 93.150349) (xy 262.3 93.0895) (xy 261.999 93.337) (xy 262.3 93.5845) (xy 262.304623 93.538135)
				(xy 262.316987 93.508618) (xy 262.352025 93.48626) (xy 262.392933 93.485959) (xy 262.41 93.487)
			)
		)
	)
	(zone
		(net 1)
		(net_name "GND")
		(layer "F.Cu")
		(name "$teardrop_padvia$")
		(hatch none 0.1)
		(priority 30594)
		(attr
			(teardrop
				(type padvia)
			)
		)
		(connect_pads yes
			(clearance 0)
		)
		(min_thickness 0.0254)
		(filled_areas_thickness no)
		(fill yes
			(thermal_gap 0.5)
			(thermal_bridge_width 0.5)
			(island_removal_mode 1)
			(island_area_min 10)
		)
		(polygon
			(pts
				(xy 225.625 157.62) (xy 225.621667 157.605514) (xy 225.61881 157.57539) (xy 225.630964 157.564349)
				(xy 225.66 157.56) (xy 225.525 156.684) (xy 225.39 157.56) (xy 225.419334 157.564475) (xy 225.431358 157.575801)
				(xy 225.428333 157.605514) (xy 225.425 157.62)
			)
		)
	)
	(zone
		(net 635)
		(net_name "Net-(U41-SCL)")
		(layer "F.Cu")
		(name "$teardrop_padvia$")
		(hatch none 0.1)
		(priority 32023)
		(attr
			(teardrop
				(type padvia)
			)
		)
		(connect_pads yes
			(clearance 0)
		)
		(min_thickness 0.0254)
		(filled_areas_thickness no)
		(fill yes
			(thermal_gap 0.5)
			(thermal_bridge_width 0.5)
			(island_removal_mode 1)
			(island_area_min 10)
		)
		(polygon
			(pts
				(xy 131.836499 83.1595) (xy 131.836595 83.165822) (xy 131.83101 83.205325) (xy 131.816077 83.223548)
				(xy 131.786499 83.236496) (xy 131.899 83.623) (xy 132.011499 83.236494) (xy 131.984505 83.225378)
				(xy 131.969404 83.209851) (xy 131.961403 83.165822) (xy 131.961499 83.1595)
			)
		)
	)
	(zone
		(net 73)
		(net_name "+3V3_AON")
		(layer "F.Cu")
		(name "$teardrop_padvia$")
		(hatch none 0.1)
		(priority 30775)
		(attr
			(teardrop
				(type padvia)
			)
		)
		(connect_pads yes
			(clearance 0)
		)
		(min_thickness 0.0254)
		(filled_areas_thickness no)
		(fill yes
			(thermal_gap 0.5)
			(thermal_bridge_width 0.5)
			(island_removal_mode 1)
			(island_area_min 10)
		)
		(polygon
			(pts
				(xy 244.919387 126.887255) (xy 244.812869 126.770934) (xy 244.752759 126.670491) (xy 244.735257 126.628879)
				(xy 244.529293 126.709293) (xy 244.448879 126.915257) (xy 244.541105 126.958858) (xy 244.623905 127.020138)
				(xy 244.707255 127.099387)
			)
		)
	)
	(zone
		(net 684)
		(net_name "Net-(U45C-ST)")
		(layer "F.Cu")
		(name "$teardrop_padvia$")
		(hatch none 0.1)
		(priority 31470)
		(attr
			(teardrop
				(type padvia)
			)
		)
		(connect_pads yes
			(clearance 0)
		)
		(min_thickness 0.0254)
		(filled_areas_thickness no)
		(fill yes
			(thermal_gap 0.5)
			(thermal_bridge_width 0.5)
			(island_removal_mode 1)
			(island_area_min 10)
		)
		(polygon
			(pts
				(xy 126.931005 139.589393) (xy 126.977948 139.643133) (xy 127.006167 139.690646) (xy 127.028018 139.777796)
				(xy 127.031163 139.808454) (xy 127.044804 139.908773) (xy 127.290707 139.860707) (xy 127.338773 139.614804)
				(xy 127.238454 139.601163) (xy 127.132344 139.581075) (xy 127.079517 139.552515) (xy 127.019393 139.501005)
			)
		)
	)
	(zone
		(net 2)
		(net_name "+3V3")
		(layer "F.Cu")
		(name "$teardrop_padvia$")
		(hatch none 0.1)
		(priority 31042)
		(attr
			(teardrop
				(type padvia)
			)
		)
		(connect_pads yes
			(clearance 0)
		)
		(min_thickness 0.0254)
		(filled_areas_thickness no)
		(fill yes
			(thermal_gap 0.5)
			(thermal_bridge_width 0.5)
			(island_removal_mode 1)
			(island_area_min 10)
		)
		(polygon
			(pts
				(xy 308.866722 76.712304) (xy 308.863975 76.690426) (xy 308.878339 76.673176) (xy 308.95361 76.64879)
				(xy 309.006798 76.6388) (xy 308.754293 76.361295) (xy 308.515781 76.647205) (xy 308.593794 76.676405)
				(xy 308.660838 76.738647) (xy 308.715929 76.831823) (xy 308.725302 76.853724)
			)
		)
	)
	(zone
		(net 2)
		(net_name "+3V3")
		(layer "F.Cu")
		(name "$teardrop_padvia$")
		(hatch none 0.1)
		(priority 30942)
		(attr
			(teardrop
				(type padvia)
			)
		)
		(connect_pads yes
			(clearance 0)
		)
		(min_thickness 0.0254)
		(filled_areas_thickness no)
		(fill yes
			(thermal_gap 0.5)
			(thermal_bridge_width 0.5)
			(island_removal_mode 1)
			(island_area_min 10)
		)
		(polygon
			(pts
				(xy 220.1475 125.462) (xy 220.127531 125.524866) (xy 220.101079 125.556844) (xy 220.063668 125.585358)
				(xy 220.016473 125.607882) (xy 219.958833 125.623093) (xy 219.958202 125.623202) (xy 220.21 125.901)
				(xy 220.461798 125.623202) (xy 220.406365 125.608905) (xy 220.36048 125.587825) (xy 220.322799 125.56046)
				(xy 220.295566 125.529552) (xy 220.278528 125.496265) (xy 220.272511 125.463434) (xy 220.2725 125.462)
			)
		)
	)
	(zone
		(net 218)
		(net_name "/Com Express 7 Interfaces/PCIe_{B1x4}.RX1+")
		(layer "F.Cu")
		(name "$teardrop_padvia$")
		(hatch none 0.1)
		(priority 31552)
		(attr
			(teardrop
				(type padvia)
			)
		)
		(connect_pads yes
			(clearance 0)
		)
		(min_thickness 0.0254)
		(filled_areas_thickness no)
		(fill yes
			(thermal_gap 0.5)
			(thermal_bridge_width 0.5)
			(island_removal_mode 1)
			(island_area_min 10)
		)
		(polygon
			(pts
				(xy 207.651566 161.838768) (xy 207.685081 161.798525) (xy 207.704567 161.760225) (xy 207.712239 161.687898)
				(xy 207.694359 161.609672) (xy 207.675685 161.531677) (xy 207.677177 161.443895) (xy 207.457207 161.399293)
				(xy 207.331497 161.587081) (xy 207.39823 161.613397) (xy 207.436537 161.622567) (xy 207.514091 161.64737)
				(xy 207.526027 161.666984) (xy 207.508731 161.695933)
			)
		)
	)
	(zone
		(net 874)
		(net_name "/2xSFP+/SDA1")
		(layer "F.Cu")
		(name "$teardrop_padvia$")
		(hatch none 0.1)
		(priority 31852)
		(attr
			(teardrop
				(type padvia)
			)
		)
		(connect_pads yes
			(clearance 0)
		)
		(min_thickness 0.0254)
		(filled_areas_thickness no)
		(fill yes
			(thermal_gap 0.5)
			(thermal_bridge_width 0.5)
			(island_removal_mode 1)
			(island_area_min 10)
		)
		(polygon
			(pts
				(xy 177.039127 143.972485) (xy 176.986618 144.018181) (xy 176.940623 144.044768) (xy 176.854174 144.065152)
				(xy 176.838841 144.066988) (xy 176.756105 144.079323) (xy 176.799293 144.300707) (xy 177.020677 144.343895)
				(xy 177.033011 144.26116) (xy 177.053349 144.163881) (xy 177.080057 144.115841) (xy 177.127515 144.060873)
			)
		)
	)
	(zone
		(net 344)
		(net_name "/Com Express 7 MGMT/SER0.TX")
		(layer "F.Cu")
		(name "$teardrop_padvia$")
		(hatch none 0.1)
		(priority 30639)
		(attr
			(teardrop
				(type padvia)
			)
		)
		(connect_pads yes
			(clearance 0)
		)
		(min_thickness 0.0254)
		(filled_areas_thickness no)
		(fill yes
			(thermal_gap 0.5)
			(thermal_bridge_width 0.5)
			(island_removal_mode 1)
			(island_area_min 10)
		)
		(polygon
			(pts
				(xy 224.5875 169.62) (xy 224.598438 169.581177) (xy 224.620195 169.566067) (xy 224.66 169.56) (xy 224.525 168.684)
				(xy 224.39 169.56) (xy 224.425281 169.564517) (xy 224.446797 169.576138) (xy 224.461995 169.608961)
				(xy 224.4625 169.62)
			)
		)
	)
	(zone
		(net 484)
		(net_name "Net-(J12K-10G_PHY_CAP_01)")
		(layer "F.Cu")
		(name "$teardrop_padvia$")
		(hatch none 0.1)
		(priority 30690)
		(attr
			(teardrop
				(type padvia)
			)
		)
		(connect_pads yes
			(clearance 0)
		)
		(min_thickness 0.0254)
		(filled_areas_thickness no)
		(fill yes
			(thermal_gap 0.5)
			(thermal_bridge_width 0.5)
			(island_removal_mode 1)
			(island_area_min 10)
		)
		(polygon
			(pts
				(xy 192.9625 150.2) (xy 192.951563 150.238823) (xy 192.929805 150.253933) (xy 192.89 150.26) (xy 193.025 151.136)
				(xy 193.16 150.26) (xy 193.124719 150.255483) (xy 193.103203 150.243862) (xy 193.088005 150.211039)
				(xy 193.0875 150.2)
			)
		)
	)
	(zone
		(net 315)
		(net_name "Net-(J12H-VCC_RTC)")
		(layer "F.Cu")
		(name "$teardrop_padvia$")
		(hatch none 0.1)
		(priority 31784)
		(attr
			(teardrop
				(type padvia)
			)
		)
		(connect_pads yes
			(clearance 0)
		)
		(min_thickness 0.0254)
		(filled_areas_thickness no)
		(fill yes
			(thermal_gap 0.5)
			(thermal_bridge_width 0.5)
			(island_removal_mode 1)
			(island_area_min 10)
		)
		(polygon
			(pts
				(xy 167.9125 150.350677) (xy 167.917318 150.281236) (xy 167.93104 150.229912) (xy 167.977755 150.15437)
				(xy 167.987299 150.142229) (xy 168.037081 150.075003) (xy 167.85 149.949) (xy 167.662919 150.075003)
				(xy 167.712701 150.142231) (xy 167.767106 150.225397) (xy 167.78219 150.278251) (xy 167.7875 150.350677)
			)
		)
	)
	(zone
		(net 231)
		(net_name "/M.2 key M #1/PCIE_{REF}.CK+")
		(layer "F.Cu")
		(name "$teardrop_padvia$")
		(hatch none 0.1)
		(priority 30435)
		(attr
			(teardrop
				(type padvia)
			)
		)
		(connect_pads yes
			(clearance 0)
		)
		(min_thickness 0.0254)
		(filled_areas_thickness no)
		(fill yes
			(thermal_gap 0.5)
			(thermal_bridge_width 0.5)
			(island_removal_mode 1)
			(island_area_min 10)
		)
		(polygon
			(pts
				(xy 208.534479 128.2265) (xy 208.612726 128.184542) (xy 208.711279 128.14853) (xy 208.788154 128.133171)
				(xy 208.868421 128.130558) (xy 208.931754 128.14) (xy 208.901 127.82) (xy 208.605 127.721085) (xy 208.607815 127.845467)
				(xy 208.595293 127.936353) (xy 208.578304 127.978387) (xy 208.553452 128.010034) (xy 208.534479 128.0245)
			)
		)
	)
	(zone
		(net 78)
		(net_name "+1V8")
		(layer "F.Cu")
		(name "$teardrop_padvia$")
		(hatch none 0.1)
		(priority 30350)
		(attr
			(teardrop
				(type padvia)
			)
		)
		(connect_pads yes
			(clearance 0)
		)
		(min_thickness 0.0254)
		(filled_areas_thickness no)
		(fill yes
			(thermal_gap 0.5)
			(thermal_bridge_width 0.5)
			(island_removal_mode 1)
			(island_area_min 10)
		)
		(polygon
			(pts
				(xy 142.4765 150.594) (xy 142.470719 150.627863) (xy 142.450254 150.662486) (xy 142.423188 150.684307)
				(xy 142.383849 150.7) (xy 142.368289 150.703289) (xy 142.539 151.41) (xy 142.709711 150.703289)
				(xy 142.66949 150.6917) (xy 142.640017 150.674116) (xy 142.606827 150.626533) (xy 142.6015 150.594)
			)
		)
	)
	(zone
		(net 338)
		(net_name "/Com Express 7 MGMT/SPI.MISO")
		(layer "F.Cu")
		(name "$teardrop_padvia$")
		(hatch none 0.1)
		(priority 31605)
		(attr
			(teardrop
				(type padvia)
			)
		)
		(connect_pads yes
			(clearance 0)
		)
		(min_thickness 0.0254)
		(filled_areas_thickness no)
		(fill yes
			(thermal_gap 0.5)
			(thermal_bridge_width 0.5)
			(island_removal_mode 1)
			(island_area_min 10)
		)
		(polygon
			(pts
				(xy 221.5875 167.700677) (xy 221.592169 167.630798) (xy 221.604856 167.57742) (xy 221.649334 167.490418)
				(xy 221.707644 167.375358) (xy 221.5 167.299) (xy 221.312919 167.425003) (xy 221.38137 167.507658)
				(xy 221.439245 167.582143) (xy 221.456315 167.632044) (xy 221.4625 167.700677)
			)
		)
	)
	(zone
		(net 2)
		(net_name "+3V3")
		(layer "F.Cu")
		(name "$teardrop_padvia$")
		(hatch none 0.1)
		(priority 31529)
		(attr
			(teardrop
				(type padvia)
			)
		)
		(connect_pads yes
			(clearance 0)
		)
		(min_thickness 0.0254)
		(filled_areas_thickness no)
		(fill yes
			(thermal_gap 0.5)
			(thermal_bridge_width 0.5)
			(island_removal_mode 1)
			(island_area_min 10)
		)
		(polygon
			(pts
				(xy 143.930457 135.85207) (xy 143.861459 135.822426) (xy 143.823354 135.789638) (xy 143.789594 135.746681)
				(xy 143.764415 135.697622) (xy 143.748554 135.641435) (xy 143.746156 135.624691) (xy 143.479293 135.879293)
				(xy 143.763772 136.108946) (xy 143.772652 136.029493) (xy 143.790224 135.974232) (xy 143.808147 135.950277)
				(xy 143.830391 135.94024) (xy 143.84207 135.940457)
			)
		)
	)
	(zone
		(net 329)
		(net_name "/Com Express 7 Interfaces/PCIe_{B2Ax4}.TX2-")
		(layer "F.Cu")
		(name "$teardrop_padvia$")
		(hatch none 0.1)
		(priority 31593)
		(attr
			(teardrop
				(type padvia)
			)
		)
		(connect_pads yes
			(clearance 0)
		)
		(min_thickness 0.0254)
		(filled_areas_thickness no)
		(fill yes
			(thermal_gap 0.5)
			(thermal_bridge_width 0.5)
			(island_removal_mode 1)
			(island_area_min 10)
		)
		(polygon
			(pts
				(xy 214.576624 167.281288) (xy 214.562862 167.260855) (xy 214.565998 167.245581) (xy 214.601515 167.226675)
				(xy 214.636458 167.216935) (xy 214.718503 167.187081) (xy 214.592793 166.999293) (xy 214.373004 167.044333)
				(xy 214.377097 167.143408) (xy 214.370227 167.195029) (xy 214.363202 167.251042) (xy 214.365556 167.306168)
				(xy 214.386136 167.362997) (xy 214.433789 167.424123)
			)
		)
	)
	(zone
		(net 341)
		(net_name "/Com Express 7 MGMT/SPI.MOSI")
		(layer "F.Cu")
		(name "$teardrop_padvia$")
		(hatch none 0.1)
		(priority 31604)
		(attr
			(teardrop
				(type padvia)
			)
		)
		(connect_pads yes
			(clearance 0)
		)
		(min_thickness 0.0254)
		(filled_areas_thickness no)
		(fill yes
			(thermal_gap 0.5)
			(thermal_bridge_width 0.5)
			(island_removal_mode 1)
			(island_area_min 10)
		)
		(polygon
			(pts
				(xy 223.0875 167.300677) (xy 223.092169 167.230798) (xy 223.104856 167.17742) (xy 223.149334 167.090418)
				(xy 223.207644 166.975358) (xy 223 166.899) (xy 222.812919 167.025003) (xy 222.88137 167.107658)
				(xy 222.939245 167.182143) (xy 222.956315 167.232044) (xy 222.9625 167.300677)
			)
		)
	)
	(zone
		(net 375)
		(net_name "/2xUSB3.0+RJ45/USB_2.D+")
		(layer "F.Cu")
		(name "$teardrop_padvia$")
		(hatch none 0.1)
		(priority 30490)
		(attr
			(teardrop
				(type padvia)
			)
		)
		(connect_pads yes
			(clearance 0)
		)
		(min_thickness 0.0254)
		(filled_areas_thickness no)
		(fill yes
			(thermal_gap 0.5)
			(thermal_bridge_width 0.5)
			(island_removal_mode 1)
			(island_area_min 10)
		)
		(polygon
			(pts
				(xy 130.923657 116.1975) (xy 130.864038 116.232089) (xy 130.789647 116.262566) (xy 130.712526 116.282491)
				(xy 130.629874 116.290953) (xy 130.525508 116.28) (xy 130.559 116.6) (xy 130.855 116.696839) (xy 130.851947 116.567478)
				(xy 130.865113 116.471437) (xy 130.882533 116.42811) (xy 130.908085 116.395054) (xy 130.923657 116.3825)
			)
		)
	)
	(zone
		(net 73)
		(net_name "+3V3_AON")
		(layer "F.Cu")
		(name "$teardrop_padvia$")
		(hatch none 0.1)
		(priority 30165)
		(attr
			(teardrop
				(type padvia)
			)
		)
		(connect_pads yes
			(clearance 0)
		)
		(min_thickness 0.0254)
		(filled_areas_thickness no)
		(fill yes
			(thermal_gap 0.5)
			(thermal_bridge_width 0.5)
			(island_removal_mode 1)
			(island_area_min 10)
		)
		(polygon
			(pts
				(xy 222.239423 81.171629) (xy 222.249678 81.134118) (xy 222.255659 81.102196) (xy 222.267446 81.079089)
				(xy 222.290263 81.077467) (xy 222.329338 81.11) (xy 222.448207 80.609293) (xy 222.1475 80.528162)
				(xy 222.142755 80.577425) (xy 222.129536 80.619298) (xy 222.08058 80.687864) (xy 221.997781 80.747047)
				(xy 221.968222 80.763646) (xy 221.885871 80.818077)
			)
		)
	)
	(zone
		(net 728)
		(net_name "Net-(U43C-AMUXA)")
		(layer "F.Cu")
		(name "$teardrop_padvia$")
		(hatch none 0.1)
		(priority 30117)
		(attr
			(teardrop
				(type padvia)
			)
		)
		(connect_pads yes
			(clearance 0)
		)
		(min_thickness 0.0254)
		(filled_areas_thickness no)
		(fill yes
			(thermal_gap 0.5)
			(thermal_bridge_width 0.5)
			(island_removal_mode 1)
			(island_area_min 10)
		)
		(polygon
			(pts
				(xy 147.9625 129.377794) (xy 147.967315 129.295733) (xy 147.981019 129.230388) (xy 148.027576 129.13712)
				(xy 148.095787 129.058657) (xy 148.151942 128.997158) (xy 148.211801 128.918339) (xy 147.9 128.709)
				(xy 147.588199 128.918339) (xy 147.685219 129.038517) (xy 147.704214 129.058658) (xy 147.757366 129.117541)
				(xy 147.799591 129.181624) (xy 147.827449 129.264008) (xy 147.8375 129.377794)
			)
		)
	)
	(zone
		(net 81)
		(net_name "/Misc/FAN_12V")
		(layer "F.Cu")
		(hatch edge 0.5)
		(priority 1)
		(connect_pads yes
			(clearance 0.15)
		)
		(min_thickness 0.25)
		(filled_areas_thickness no)
		(fill yes
			(thermal_gap 0.2)
			(thermal_bridge_width 0.5)
			(smoothing fillet)
			(radius 0.2)
		)
		(polygon
			(pts
				(xy 298.1 144.21) (xy 298.1 140.36) (xy 296.375 140.36) (xy 296.375 144.21)
			)
		)
	)
	(zone
		(net 985)
		(net_name "Net-(D33-C)")
		(layer "F.Cu")
		(name "$teardrop_padvia$")
		(hatch none 0.1)
		(priority 30887)
		(attr
			(teardrop
				(type padvia)
			)
		)
		(connect_pads yes
			(clearance 0)
		)
		(min_thickness 0.0254)
		(filled_areas_thickness no)
		(fill yes
			(thermal_gap 0.5)
			(thermal_bridge_width 0.5)
			(island_removal_mode 1)
			(island_area_min 10)
		)
		(polygon
			(pts
				(xy 188.60861 76.259163) (xy 188.602838 76.2999) (xy 188.582434 76.341815) (xy 188.555259 76.370116)
				(xy 188.515713 76.393544) (xy 188.44311 76.412815) (xy 188.70861 76.673163) (xy 188.97411 76.412815)
				(xy 188.920968 76.400948) (xy 188.879929 76.382501) (xy 188.828228 76.331827) (xy 188.808892 76.268258)
				(xy 188.80861 76.259163)
			)
		)
	)
	(zone
		(net 204)
		(net_name "/Backplane/USB.D-")
		(layer "F.Cu")
		(name "$teardrop_padvia$")
		(hatch none 0.1)
		(priority 31533)
		(attr
			(teardrop
				(type padvia)
			)
		)
		(connect_pads yes
			(clearance 0)
		)
		(min_thickness 0.0254)
		(filled_areas_thickness no)
		(fill yes
			(thermal_gap 0.5)
			(thermal_bridge_width 0.5)
			(island_removal_mode 1)
			(island_area_min 10)
		)
		(polygon
			(pts
				(xy 212.4675 148.744916) (xy 212.462743 148.787708) (xy 212.449445 148.819045) (xy 212.404537 148.858413)
				(xy 212.36578 148.877253) (xy 212.297997 148.912919) (xy 212.423 149.101) (xy 212.643677 149.091365)
				(xy 212.646644 148.920056) (xy 212.6525 148.744916)
			)
		)
	)
	(zone
		(net 574)
		(net_name "Net-(U19-EN)")
		(layer "F.Cu")
		(name "$teardrop_padvia$")
		(hatch none 0.1)
		(priority 31820)
		(attr
			(teardrop
				(type padvia)
			)
		)
		(connect_pads yes
			(clearance 0)
		)
		(min_thickness 0.0254)
		(filled_areas_thickness no)
		(fill yes
			(thermal_gap 0.5)
			(thermal_bridge_width 0.5)
			(island_removal_mode 1)
			(island_area_min 10)
		)
		(polygon
			(pts
				(xy 310.225676 104.236499) (xy 310.156235 104.231681) (xy 310.104912 104.217959) (xy 310.02937 104.171245)
				(xy 310.01723 104.1617) (xy 309.950002 104.111918) (xy 309.823999 104.298999) (xy 309.950002 104.48608)
				(xy 310.017228 104.436298) (xy 310.100395 104.381893) (xy 310.15325 104.366809) (xy 310.225676 104.361499)
			)
		)
	)
	(zone
		(net 2)
		(net_name "+3V3")
		(layer "F.Cu")
		(name "$teardrop_padvia$")
		(hatch none 0.1)
		(priority 31510)
		(attr
			(teardrop
				(type padvia)
			)
		)
		(connect_pads yes
			(clearance 0)
		)
		(min_thickness 0.0254)
		(filled_areas_thickness no)
		(fill yes
			(thermal_gap 0.5)
			(thermal_bridge_width 0.5)
			(island_removal_mode 1)
			(island_area_min 10)
		)
		(polygon
			(pts
				(xy 212.946591 129.223) (xy 212.910253 129.218249) (xy 212.885214 129.204995) (xy 212.859893 129.161659)
				(xy 212.850176 129.108185) (xy 212.84075 129.053682) (xy 212.819835 129.001646) (xy 212.629 129.12)
				(xy 212.598249 129.340677) (xy 212.714918 129.372057) (xy 212.736457 129.380584) (xy 212.822626 129.409868)
				(xy 212.946591 129.423)
			)
		)
	)
	(zone
		(net 80)
		(net_name "Net-(Q6-D)")
		(layer "F.Cu")
		(name "$teardrop_padvia$")
		(hatch none 0.1)
		(priority 30523)
		(attr
			(teardrop
				(type padvia)
			)
		)
		(connect_pads yes
			(clearance 0)
		)
		(min_thickness 0.0254)
		(filled_areas_thickness no)
		(fill yes
			(thermal_gap 0.5)
			(thermal_bridge_width 0.5)
			(island_removal_mode 1)
			(island_area_min 10)
		)
		(polygon
			(pts
				(xy 260.624 87.489999) (xy 260.601961 87.496839) (xy 260.560854 87.504994) (xy 260.545884 87.48996)
				(xy 260.54 87.450999) (xy 259.979 87.64) (xy 260.54 87.828999) (xy 260.544553 87.793473) (xy 260.556426 87.77701)
				(xy 260.585712 87.776914) (xy 260.601961 87.783159) (xy 260.624 87.789999)
			)
		)
	)
	(zone
		(net 145)
		(net_name "Net-(D24-C)")
		(layer "F.Cu")
		(name "$teardrop_padvia$")
		(hatch none 0.1)
		(priority 30727)
		(attr
			(teardrop
				(type padvia)
			)
		)
		(connect_pads yes
			(clearance 0)
		)
		(min_thickness 0.0254)
		(filled_areas_thickness no)
		(fill yes
			(thermal_gap 0.5)
			(thermal_bridge_width 0.5)
			(island_removal_mode 1)
			(island_area_min 10)
		)
		(polygon
			(pts
				(xy 306.4125 147.17) (xy 306.407179 147.201735) (xy 306.389931 147.234435) (xy 306.363462 147.260626)
				(xy 306.325036 147.281555) (xy 306.28295 147.29295) (xy 306.475 147.811) (xy 306.66705 147.29295)
				(xy 306.622526 147.280591) (xy 306.5884 147.261992) (xy 306.546464 147.211197) (xy 306.5375 147.17)
			)
		)
	)
	(zone
		(net 587)
		(net_name "/M.2 key E/SUSCLK")
		(layer "F.Cu")
		(name "$teardrop_padvia$")
		(hatch none 0.1)
		(priority 31816)
		(attr
			(teardrop
				(type padvia)
			)
		)
		(connect_pads yes
			(clearance 0)
		)
		(min_thickness 0.0254)
		(filled_areas_thickness no)
		(fill yes
			(thermal_gap 0.5)
			(thermal_bridge_width 0.5)
			(island_removal_mode 1)
			(island_area_min 10)
		)
		(polygon
			(pts
				(xy 303.350677 84.4275) (xy 303.281236 84.422682) (xy 303.229913 84.40896) (xy 303.154371 84.362246)
				(xy 303.142231 84.352701) (xy 303.075003 84.302919) (xy 302.949 84.49) (xy 303.075003 84.677081)
				(xy 303.142229 84.627299) (xy 303.225396 84.572894) (xy 303.278251 84.55781) (xy 303.350677 84.5525)
			)
		)
	)
	(zone
		(net 389)
		(net_name "Net-(J12D-~{BIOS_DIS1})")
		(layer "F.Cu")
		(name "$teardrop_padvia$")
		(hatch none 0.1)
		(priority 30709)
		(attr
			(teardrop
				(type padvia)
			)
		)
		(connect_pads yes
			(clearance 0)
		)
		(min_thickness 0.0254)
		(filled_areas_thickness no)
		(fill yes
			(thermal_gap 0.5)
			(thermal_bridge_width 0.5)
			(island_removal_mode 1)
			(island_area_min 10)
		)
		(polygon
			(pts
				(xy 219.6 164.07) (xy 219.596865 164.055714) (xy 219.594488 164.025461) (xy 219.607042 164.014369)
				(xy 219.636651 164.01) (xy 219.525 163.134) (xy 219.375 164.01) (xy 219.40119 164.01447) (xy 219.410657 164.025762)
				(xy 219.40468 164.054279) (xy 219.4 164.07)
			)
		)
	)
	(zone
		(net 52)
		(net_name "+5V")
		(layer "F.Cu")
		(name "$teardrop_padvia$")
		(hatch none 0.1)
		(priority 30461)
		(attr
			(teardrop
				(type padvia)
			)
		)
		(connect_pads yes
			(clearance 0)
		)
		(min_thickness 0.0254)
		(filled_areas_thickness no)
		(fill yes
			(thermal_gap 0.5)
			(thermal_bridge_width 0.5)
			(island_removal_mode 1)
			(island_area_min 10)
		)
		(polygon
			(pts
				(xy 249.325708 76.198) (xy 249.32537 76.18113) (xy 249.325949 76.136174) (xy 249.337767 76.088831)
				(xy 249.372346 76.046427) (xy 249.441208 76.016291) (xy 249.175708 75.759) (xy 248.910208 76.016291)
				(xy 248.954977 76.031848) (xy 248.986593 76.052565) (xy 249.019327 76.103701) (xy 249.026046 76.18113)
				(xy 249.025708 76.198)
			)
		)
	)
	(zone
		(net 1)
		(net_name "GND")
		(layer "F.Cu")
		(name "$teardrop_padvia$")
		(hatch none 0.1)
		(priority 30587)
		(attr
			(teardrop
				(type padvia)
			)
		)
		(connect_pads yes
			(clearance 0)
		)
		(min_thickness 0.0254)
		(filled_areas_thickness no)
		(fill yes
			(thermal_gap 0.5)
			(thermal_bridge_width 0.5)
			(island_removal_mode 1)
			(island_area_min 10)
		)
		(polygon
			(pts
				(xy 191.125 157.62) (xy 191.121667 157.605514) (xy 191.11881 157.57539) (xy 191.130964 157.564349)
				(xy 191.16 157.56) (xy 191.025 156.684) (xy 190.89 157.56) (xy 190.919334 157.564475) (xy 190.931358 157.575801)
				(xy 190.928333 157.605514) (xy 190.925 157.62)
			)
		)
	)
	(zone
		(net 595)
		(net_name "/Misc/PWM_{SRCSEL}")
		(layer "F.Cu")
		(name "$teardrop_padvia$")
		(hatch none 0.1)
		(priority 30487)
		(attr
			(teardrop
				(type padvia)
			)
		)
		(connect_pads yes
			(clearance 0)
		)
		(min_thickness 0.0254)
		(filled_areas_thickness no)
		(fill yes
			(thermal_gap 0.5)
			(thermal_bridge_width 0.5)
			(island_removal_mode 1)
			(island_area_min 10)
		)
		(polygon
			(pts
				(xy 252.469054 85.037557) (xy 252.384357 85.093857) (xy 252.323751 85.115598) (xy 252.254439 85.12941)
				(xy 252.117567 85.129999) (xy 252.189295 85.450706) (xy 252.485002 85.51632) (xy 252.475604 85.425204)
				(xy 252.476675 85.341544) (xy 252.487223 85.268644) (xy 252.506601 85.205632) (xy 252.557442 85.125945)
			)
		)
	)
	(zone
		(net 151)
		(net_name "/2xUSB3.0+RJ45/DB-")
		(layer "F.Cu")
		(name "$teardrop_padvia$")
		(hatch none 0.1)
		(priority 30013)
		(attr
			(teardrop
				(type padvia)
			)
		)
		(connect_pads yes
			(clearance 0)
		)
		(min_thickness 0.0254)
		(filled_areas_thickness no)
		(fill yes
			(thermal_gap 0.5)
			(thermal_bridge_width 0.5)
			(island_removal_mode 1)
			(island_area_min 10)
		)
		(polygon
			(pts
				(xy 114.370177 103.476242) (xy 114.481587 103.580933) (xy 114.579799 103.660395) (xy 114.752941 103.768022)
				(xy 114.879486 103.828149) (xy 115.039437 103.90484) (xy 115.23499 104.021242) (xy 115.610707 103.460707)
				(xy 115.23499 102.898758) (xy 115.118389 102.997575) (xy 114.991595 103.149188) (xy 114.94613 103.210587)
				(xy 114.839204 103.348639) (xy 114.786376 103.402736) (xy 114.732228 103.441755) (xy 114.675449 103.461852)
				(xy 114.614731 103.459184) (xy 114.548765 103.429907) (xy 114.476242 103.370177)
			)
		)
	)
	(zone
		(net 1)
		(net_name "GND")
		(layer "F.Cu")
		(name "$teardrop_padvia$")
		(hatch none 0.1)
		(priority 30867)
		(attr
			(teardrop
				(type padvia)
			)
		)
		(connect_pads yes
			(clearance 0)
		)
		(min_thickness 0.0254)
		(filled_areas_thickness no)
		(fill yes
			(thermal_gap 0.5)
			(thermal_bridge_width 0.5)
			(island_removal_mode 1)
			(island_area_min 10)
		)
		(polygon
			(pts
				(xy 236.8 155.353) (xy 236.805772 155.312263) (xy 236.826176 155.270348) (xy 236.853351 155.242047)
				(xy 236.892897 155.218618) (xy 236.9655 155.199347) (xy 236.7 154.939) (xy 236.4345 155.199347)
				(xy 236.487642 155.211214) (xy 236.528681 155.229662) (xy 236.580382 155.280336) (xy 236.599718 155.343905)
				(xy 236.6 155.353)
			)
		)
	)
	(zone
		(net 51)
		(net_name "Net-(C13-Pad1)")
		(layer "F.Cu")
		(name "$teardrop_padvia$")
		(hatch none 0.1)
		(priority 30476)
		(attr
			(teardrop
				(type padvia)
			)
		)
		(connect_pads yes
			(clearance 0)
		)
		(min_thickness 0.0254)
		(filled_areas_thickness no)
		(fill yes
			(thermal_gap 0.5)
			(thermal_bridge_width 0.5)
			(island_removal_mode 1)
			(island_area_min 10)
		)
		(polygon
			(pts
				(xy 129.938 106.67) (xy 129.92113 106.670338) (xy 129.876174 106.669759) (xy 129.828831 106.657941)
				(xy 129.786427 106.623362) (xy 129.756292 106.5545) (xy 129.499 106.82) (xy 129.756292 107.0855)
				(xy 129.771849 107.040731) (xy 129.792565 107.009115) (xy 129.843701 106.976381) (xy 129.92113 106.969662)
				(xy 129.938 106.97)
			)
		)
	)
	(zone
		(net 142)
		(net_name "/2xSFP+/PHY0_{RESET}")
		(layer "F.Cu")
		(name "$teardrop_padvia$")
		(hatch none 0.1)
		(priority 30676)
		(attr
			(teardrop
				(type padvia)
			)
		)
		(connect_pads yes
			(clearance 0)
		)
		(min_thickness 0.0254)
		(filled_areas_thickness no)
		(fill yes
			(thermal_gap 0.5)
			(thermal_bridge_width 0.5)
			(island_removal_mode 1)
			(island_area_min 10)
		)
		(polygon
			(pts
				(xy 192.9625 155.75) (xy 192.951563 155.788823) (xy 192.929805 155.803933) (xy 192.89 155.81) (xy 193.025 156.686)
				(xy 193.16 155.81) (xy 193.124719 155.805483) (xy 193.103203 155.793862) (xy 193.088005 155.761039)
				(xy 193.0875 155.75)
			)
		)
	)
	(zone
		(net 123)
		(net_name "/2xUSB3.0+RJ45/P1_D-")
		(layer "F.Cu")
		(name "$teardrop_padvia$")
		(hatch none 0.1)
		(priority 31498)
		(attr
			(teardrop
				(type padvia)
			)
		)
		(connect_pads yes
			(clearance 0)
		)
		(min_thickness 0.0254)
		(filled_areas_thickness no)
		(fill yes
			(thermal_gap 0.5)
			(thermal_bridge_width 0.5)
			(island_removal_mode 1)
			(island_area_min 10)
		)
		(polygon
			(pts
				(xy 104.128157 105.2675) (xy 104.292598 105.263316) (xy 104.475303 105.263177) (xy 104.488741 105.0425)
				(xy 104.334845 104.883311) (xy 104.285966 104.950836) (xy 104.272592 104.97718) (xy 104.251217 105.017443)
				(xy 104.224508 105.051002) (xy 104.185733 105.073979) (xy 104.128157 105.0825)
			)
		)
	)
	(zone
		(net 592)
		(net_name "Net-(U24-+5V_{IN})")
		(layer "F.Cu")
		(name "$teardrop_padvia$")
		(hatch none 0.1)
		(priority 30745)
		(attr
			(teardrop
				(type padvia)
			)
		)
		(connect_pads yes
			(clearance 0)
		)
		(min_thickness 0.0254)
		(filled_areas_thickness no)
		(fill yes
			(thermal_gap 0.5)
			(thermal_bridge_width 0.5)
			(island_removal_mode 1)
			(island_area_min 10)
		)
		(polygon
			(pts
				(xy 253.987926 87.064345) (xy 254.047693 87.076179) (xy 254.109638 87.11108) (xy 254.129766 87.13813)
				(xy 254.139567 87.173463) (xy 254.14 87.183543) (xy 254.700707 87.000707) (xy 254.14 86.805519)
				(xy 254.144194 86.88412) (xy 254.144946 86.915946) (xy 254.129346 86.922925)
			)
		)
	)
	(zone
		(net 380)
		(net_name "Net-(J12G-USB0_HOST_PRSNT)")
		(layer "F.Cu")
		(name "$teardrop_padvia$")
		(hatch none 0.1)
		(priority 31884)
		(attr
			(teardrop
				(type padvia)
			)
		)
		(connect_pads yes
			(clearance 0)
		)
		(min_thickness 0.0254)
		(filled_areas_thickness no)
		(fill yes
			(thermal_gap 0.5)
			(thermal_bridge_width 0.5)
			(island_removal_mode 1)
			(island_area_min 10)
		)
		(polygon
			(pts
				(xy 196.502515 160.039127) (xy 196.456819 159.986618) (xy 196.430231 159.940623) (xy 196.409847 159.854175)
				(xy 196.408011 159.83884) (xy 196.395677 159.756105) (xy 196.174293 159.799293) (xy 196.131105 160.020677)
				(xy 196.21384 160.033011) (xy 196.311119 160.053349) (xy 196.359159 160.080057) (xy 196.414127 160.127515)
			)
		)
	)
	(zone
		(net 597)
		(net_name "/Misc/PWM1")
		(layer "F.Cu")
		(name "$teardrop_padvia$")
		(hatch none 0.1)
		(priority 30817)
		(attr
			(teardrop
				(type padvia)
			)
		)
		(connect_pads yes
			(clearance 0)
		)
		(min_thickness 0.0254)
		(filled_areas_thickness no)
		(fill yes
			(thermal_gap 0.5)
			(thermal_bridge_width 0.5)
			(island_removal_mode 1)
			(island_area_min 10)
		)
		(polygon
			(pts
				(xy 255.344 89.4775) (xy 255.317391 89.472137) (xy 255.292117 89.4546) (xy 255.274478 89.428306)
				(xy 255.26305 89.39016) (xy 255.26 89.351) (xy 254.699 89.54) (xy 255.26 89.729) (xy 255.264627 89.681637)
				(xy 255.277018 89.646589) (xy 255.294877 89.622651) (xy 255.316015 89.608454) (xy 255.344 89.6025)
			)
		)
	)
	(zone
		(net 530)
		(net_name "/M.2 key M #2/~{CLKREQ}")
		(layer "F.Cu")
		(name "$teardrop_padvia$")
		(hatch none 0.1)
		(priority 30852)
		(attr
			(teardrop
				(type padvia)
			)
		)
		(connect_pads yes
			(clearance 0)
		)
		(min_thickness 0.0254)
		(filled_areas_thickness no)
		(fill yes
			(thermal_gap 0.5)
			(thermal_bridge_width 0.5)
			(island_removal_mode 1)
			(island_area_min 10)
		)
		(polygon
			(pts
				(xy 299.0115 82.418) (xy 299.022438 82.379177) (xy 299.044195 82.364067) (xy 299.084 82.358) (xy 298.949 81.582)
				(xy 298.814 82.358) (xy 298.849281 82.362517) (xy 298.870797 82.374138) (xy 298.885995 82.406961)
				(xy 298.8865 82.418)
			)
		)
	)
	(zone
		(net 734)
		(net_name "Net-(U43A-LOSA)")
		(layer "F.Cu")
		(name "$teardrop_padvia$")
		(hatch none 0.1)
		(priority 31720)
		(attr
			(teardrop
				(type padvia)
			)
		)
		(connect_pads yes
			(clearance 0)
		)
		(min_thickness 0.0254)
		(filled_areas_thickness no)
		(fill yes
			(thermal_gap 0.5)
			(thermal_bridge_width 0.5)
			(island_removal_mode 1)
			(island_area_min 10)
		)
		(polygon
			(pts
				(xy 149.7875 130.109323) (xy 149.782682 130.178763) (xy 149.76896 130.230087) (xy 149.722245 130.305628)
				(xy 149.712702 130.317768) (xy 149.662919 130.384997) (xy 149.85 130.511) (xy 150.037081 130.384997)
				(xy 149.987299 130.317769) (xy 149.932894 130.234603) (xy 149.91781 130.181748) (xy 149.9125 130.109323)
			)
		)
	)
	(zone
		(net 1)
		(net_name "GND")
		(layer "F.Cu")
		(name "$teardrop_padvia$")
		(hatch none 0.1)
		(priority 30591)
		(attr
			(teardrop
				(type padvia)
			)
		)
		(connect_pads yes
			(clearance 0)
		)
		(min_thickness 0.0254)
		(filled_areas_thickness no)
		(fill yes
			(thermal_gap 0.5)
			(thermal_bridge_width 0.5)
			(island_removal_mode 1)
			(island_area_min 10)
		)
		(polygon
			(pts
				(xy 176.425 155.75) (xy 176.428333 155.764486) (xy 176.43119 155.79461) (xy 176.419036 155.805651)
				(xy 176.39 155.81) (xy 176.525 156.686) (xy 176.66 155.81) (xy 176.630666 155.805525) (xy 176.618642 155.794199)
				(xy 176.621667 155.764486) (xy 176.625 155.75)
			)
		)
	)
	(zone
		(net 57)
		(net_name "/USB-C console/FTDI_VCCIO")
		(layer "F.Cu")
		(name "$teardrop_padvia$")
		(hatch none 0.1)
		(priority 31111)
		(attr
			(teardrop
				(type padvia)
			)
		)
		(connect_pads yes
			(clearance 0)
		)
		(min_thickness 0.0254)
		(filled_areas_thickness no)
		(fill yes
			(thermal_gap 0.5)
			(thermal_bridge_width 0.5)
			(island_removal_mode 1)
			(island_area_min 10)
		)
		(polygon
			(pts
				(xy 112.807 78.772501) (xy 112.866412 78.792274) (xy 112.922497 78.855548) (xy 112.944199 78.904172)
				(xy 112.958873 78.963532) (xy 112.960653 78.9755) (xy 113.221 78.71) (xy 112.960652 78.4445) (xy 112.947803 78.504639)
				(xy 112.927869 78.554523) (xy 112.901944 78.594642) (xy 112.872125 78.623656) (xy 112.840706 78.641147)
				(xy 112.808895 78.64748) (xy 112.807 78.647501)
			)
		)
	)
	(zone
		(net 1)
		(net_name "GND")
		(layer "F.Cu")
		(name "$teardrop_padvia$")
		(hatch none 0.1)
		(priority 31214)
		(attr
			(teardrop
				(type padvia)
			)
		)
		(connect_pads yes
			(clearance 0)
		)
		(min_thickness 0.0254)
		(filled_areas_thickness no)
		(fill yes
			(thermal_gap 0.5)
			(thermal_bridge_width 0.5)
			(island_removal_mode 1)
			(island_area_min 10)
		)
		(polygon
			(pts
				(xy 179.425 157.499323) (xy 179.42028 157.568646) (xy 179.407244 157.621549) (xy 179.355344 157.714135)
				(xy 179.303541 157.797636) (xy 179.5 157.901) (xy 179.707644 157.824641) (xy 179.675418 157.744142)
				(xy 179.639035 157.642683) (xy 179.625 157.499323)
			)
		)
	)
	(zone
		(net 1)
		(net_name "GND")
		(layer "F.Cu")
		(name "$teardrop_padvia$")
		(hatch none 0.1)
		(priority 31224)
		(attr
			(teardrop
				(type padvia)
			)
		)
		(connect_pads yes
			(clearance 0)
		)
		(min_thickness 0.0254)
		(filled_areas_thickness no)
		(fill yes
			(thermal_gap 0.5)
			(thermal_bridge_width 0.5)
			(island_removal_mode 1)
			(island_area_min 10)
		)
		(polygon
			(pts
				(xy 213.625 167.900677) (xy 213.629737 167.809676) (xy 213.642896 167.742587) (xy 213.675418 167.655855)
				(xy 213.707644 167.575358) (xy 213.5 167.499) (xy 213.303541 167.602363) (xy 213.355343 167.685863)
				(xy 213.404833 167.771955) (xy 213.419614 167.82716) (xy 213.425 167.900677)
			)
		)
	)
	(zone
		(net 310)
		(net_name "/Com Express 7 MGMT/~{BIOS_DIS0}")
		(layer "F.Cu")
		(name "$teardrop_padvia$")
		(hatch none 0.1)
		(priority 31826)
		(attr
			(teardrop
				(type padvia)
			)
		)
		(connect_pads yes
			(clearance 0)
		)
		(min_thickness 0.0254)
		(filled_areas_thickness no)
		(fill yes
			(thermal_gap 0.5)
			(thermal_bridge_width 0.5)
			(island_removal_mode 1)
			(island_area_min 10)
		)
		(polygon
			(pts
				(xy 191.900677 166.9875) (xy 191.831236 166.982682) (xy 191.779913 166.96896) (xy 191.704371 166.922246)
				(xy 191.692231 166.912701) (xy 191.625003 166.862919) (xy 191.499 167.05) (xy 191.625003 167.237081)
				(xy 191.692229 167.187299) (xy 191.775396 167.132894) (xy 191.828251 167.11781) (xy 191.900677 167.1125)
			)
		)
	)
	(zone
		(net 280)
		(net_name "/Misc/PWM_{A5V}")
		(layer "F.Cu")
		(name "$teardrop_padvia$")
		(hatch none 0.1)
		(priority 30358)
		(attr
			(teardrop
				(type padvia)
			)
		)
		(connect_pads yes
			(clearance 0)
		)
		(min_thickness 0.0254)
		(filled_areas_thickness no)
		(fill yes
			(thermal_gap 0.5)
			(thermal_bridge_width 0.5)
			(island_removal_mode 1)
			(island_area_min 10)
		)
		(polygon
			(pts
				(xy 259.467708 77.1855) (xy 259.501571 77.191281) (xy 259.536192 77.211745) (xy 259.558014 77.23881)
				(xy 259.573708 77.27815) (xy 259.576997 77.293711) (xy 260.283708 77.123) (xy 259.576997 76.952289)
				(xy 259.565408 76.99251) (xy 259.547824 77.021984) (xy 259.500242 77.055173) (xy 259.467708 77.0605)
			)
		)
	)
	(zone
		(net 2)
		(net_name "+3V3")
		(layer "F.Cu")
		(name "$teardrop_padvia$")
		(hatch none 0.1)
		(priority 30038)
		(attr
			(teardrop
				(type padvia)
			)
		)
		(connect_pads yes
			(clearance 0)
		)
		(min_thickness 0.0254)
		(filled_areas_thickness no)
		(fill yes
			(thermal_gap 0.5)
			(thermal_bridge_width 0.5)
			(island_removal_mode 1)
			(island_area_min 10)
		)
		(polygon
			(pts
				(xy 125.575913 138.235699) (xy 125.478968 138.305468) (xy 125.329412 138.363498) (xy 125.12074 138.401415)
				(xy 124.94567 138.41) (xy 125.029293 138.935707) (xy 125.49 139.042844) (xy 125.495326 138.863025)
				(xy 125.512612 138.697809) (xy 125.535507 138.582447) (xy 125.567693 138.480482) (xy 125.601338 138.408852)
				(xy 125.642219 138.348488) (xy 125.664301 138.324087)
			)
		)
	)
	(zone
		(net 976)
		(net_name "/PCIe redriver/RX_EQ2")
		(layer "F.Cu")
		(name "$teardrop_padvia$")
		(hatch none 0.1)
		(priority 31024)
		(attr
			(teardrop
				(type padvia)
			)
		)
		(connect_pads yes
			(clearance 0)
		)
		(min_thickness 0.0254)
		(filled_areas_thickness no)
		(fill yes
			(thermal_gap 0.5)
			(thermal_bridge_width 0.5)
			(island_removal_mode 1)
			(island_area_min 10)
		)
		(polygon
			(pts
				(xy 193.064495 130.804929) (xy 193.034163 130.746356) (xy 193.030256 130.70504) (xy 193.036547 130.658424)
				(xy 193.053992 130.609125) (xy 193.083994 130.557612) (xy 193.084363 130.557089) (xy 192.709882 130.538704)
				(xy 192.728267 130.913185) (xy 192.777573 130.884097) (xy 192.824924 130.866558) (xy 192.870919 130.859263)
				(xy 192.912031 130.861862) (xy 192.947616 130.873351) (xy 192.975085 130.892311) (xy 192.976107 130.893317)
			)
		)
	)
	(zone
		(net 327)
		(net_name "/Com Express 7 Interfaces/PCIe_{B2Ax4}.TX1-")
		(layer "F.Cu")
		(name "$teardrop_padvia$")
		(hatch none 0.1)
		(priority 30515)
		(attr
			(teardrop
				(type padvia)
			)
		)
		(connect_pads yes
			(clearance 0)
		)
		(min_thickness 0.0254)
		(filled_areas_thickness no)
		(fill yes
			(thermal_gap 0.5)
			(thermal_bridge_width 0.5)
			(island_removal_mode 1)
			(island_area_min 10)
		)
		(polygon
			(pts
				(xy 212.924 167.75) (xy 212.927537 167.764678) (xy 212.930808 167.794685) (xy 212.918857 167.805673)
				(xy 212.89 167.81) (xy 213.025 168.686) (xy 213.16 167.81) (xy 213.130796 167.805525) (xy 213.119003 167.794203)
				(xy 213.122463 167.764678) (xy 213.126 167.75)
			)
		)
	)
	(zone
		(net 62)
		(net_name "+12V_AON")
		(layer "F.Cu")
		(hatch edge 0.5)
		(priority 1)
		(connect_pads yes
			(clearance 0.15)
		)
		(min_thickness 0.25)
		(filled_areas_thickness no)
		(fill yes
			(thermal_gap 0.2)
			(thermal_bridge_width 0.5)
			(smoothing fillet)
			(radius 0.2)
		)
		(polygon
			(pts
				(xy 313.05 144.21) (xy 306.925 144.21) (xy 306.925 141.735) (xy 307 141.66) (xy 308.1235 141.66)
				(xy 308.225 141.5585) (xy 308.225 139.21) (xy 309.025 138.41) (xy 313.05 138.41)
			)
		)
	)
	(zone
		(net 952)
		(net_name "/2xSFP+/KR to SFI #2/SFI_R.TX-")
		(layer "F.Cu")
		(name "$teardrop_padvia$")
		(hatch none 0.1)
		(priority 31178)
		(attr
			(teardrop
				(type padvia)
			)
		)
		(connect_pads yes
			(clearance 0)
		)
		(min_thickness 0.0254)
		(filled_areas_thickness no)
		(fill yes
			(thermal_gap 0.5)
			(thermal_bridge_width 0.5)
			(island_removal_mode 1)
			(island_area_min 10)
		)
		(polygon
			(pts
				(xy 128.68 143.17679) (xy 128.675347 143.112802) (xy 128.662777 143.062121) (xy 128.618645 142.980204)
				(xy 128.607609 142.964616) (xy 128.566024 142.899819) (xy 128.535196 142.811227) (xy 128.29 142.859)
				(xy 128.241227 143.105196) (xy 128.328185 143.107002) (xy 128.371073 143.101889) (xy 128.428443 143.095867)
				(xy 128.475848 143.099993) (xy 128.508097 143.123792) (xy 128.52 143.17679)
			)
		)
	)
	(zone
		(net 743)
		(net_name "/2xSFP+/KR to SFI #2/TDO")
		(layer "F.Cu")
		(name "$teardrop_padvia$")
		(hatch none 0.1)
		(priority 30132)
		(attr
			(teardrop
				(type padvia)
			)
		)
		(connect_pads yes
			(clearance 0)
		)
		(min_thickness 0.0254)
		(filled_areas_thickness no)
		(fill yes
			(thermal_gap 0.5)
			(thermal_bridge_width 0.5)
			(island_removal_mode 1)
			(island_area_min 10)
		)
		(polygon
			(pts
				(xy 133.7025 129.377794) (xy 133.707315 129.295733) (xy 133.721019 129.230388) (xy 133.767576 129.13712)
				(xy 133.835787 129.058657) (xy 133.891942 128.997158) (xy 133.951801 128.918339) (xy 133.64 128.709)
				(xy 133.328199 128.918339) (xy 133.425219 129.038517) (xy 133.444214 129.058658) (xy 133.497366 129.117541)
				(xy 133.539591 129.181624) (xy 133.567449 129.264008) (xy 133.5775 129.377794)
			)
		)
	)
	(zone
		(net 2)
		(net_name "+3V3")
		(layer "F.Cu")
		(name "$teardrop_padvia$")
		(hatch none 0.1)
		(priority 30228)
		(attr
			(teardrop
				(type padvia)
			)
		)
		(connect_pads yes
			(clearance 0)
		)
		(min_thickness 0.0254)
		(filled_areas_thickness no)
		(fill yes
			(thermal_gap 0.5)
			(thermal_bridge_width 0.5)
			(island_removal_mode 1)
			(island_area_min 10)
		)
		(polygon
			(pts
				(xy 245.737709 78.573) (xy 245.768317 78.56465) (xy 245.821302 78.554039) (xy 245.844434 78.567044)
				(xy 245.8609 78.603) (xy 246.553709 78.423) (xy 245.8609 78.243) (xy 245.848966 78.272959) (xy 245.832645 78.288272)
				(xy 245.794971 78.290108) (xy 245.768317 78.28135) (xy 245.737709 78.273)
			)
		)
	)
	(zone
		(net 219)
		(net_name "/Com Express 7 Interfaces/PCIe_{B1x4}.TX1-")
		(layer "F.Cu")
		(name "$teardrop_padvia$")
		(hatch none 0.1)
		(priority 30270)
		(attr
			(teardrop
				(type padvia)
			)
		)
		(connect_pads yes
			(clearance 0)
		)
		(min_thickness 0.0254)
		(filled_areas_thickness no)
		(fill yes
			(thermal_gap 0.5)
			(thermal_bridge_width 0.5)
			(island_removal_mode 1)
			(island_area_min 10)
		)
		(polygon
			(pts
				(xy 207.8685 167.75) (xy 207.879599 167.923112) (xy 207.894216 168.15051) (xy 207.891181 168.285138)
				(xy 207.875 168.437021) (xy 208.025 168.686) (xy 208.108295 167.81) (xy 208.077864 167.805523) (xy 208.065097 167.794185)
				(xy 208.06742 167.764227) (xy 208.0705 167.75)
			)
		)
	)
	(zone
		(net 948)
		(net_name "/2xSFP+/KR to SFI #1/BYP_TX-")
		(layer "F.Cu")
		(name "$teardrop_padvia$")
		(hatch none 0.1)
		(priority 31955)
		(attr
			(teardrop
				(type padvia)
			)
		)
		(connect_pads yes
			(clearance 0)
		)
		(min_thickness 0.0254)
		(filled_areas_thickness no)
		(fill yes
			(thermal_gap 0.5)
			(thermal_bridge_width 0.5)
			(island_removal_mode 1)
			(island_area_min 10)
		)
		(polygon
			(pts
				(xy 156.22 148.526893) (xy 156.232488 148.503919) (xy 156.255566 148.488424) (xy 156.33326 148.479871)
				(xy 156.389562 148.485) (xy 156.332 148.254) (xy 156.132 148.225449) (xy 156.127606 148.324729)
				(xy 156.083133 148.463503) (xy 156.06 148.526893)
			)
		)
	)
	(zone
		(net 254)
		(net_name "/Com Express 7 Interfaces/PCIe_{B2Bx4}.RX1+")
		(layer "F.Cu")
		(name "$teardrop_padvia$")
		(hatch none 0.1)
		(priority 31409)
		(attr
			(teardrop
				(type padvia)
			)
		)
		(connect_pads yes
			(clearance 0)
		)
		(min_thickness 0.0254)
		(filled_areas_thickness no)
		(fill yes
			(thermal_gap 0.5)
			(thermal_bridge_width 0.5)
			(island_removal_mode 1)
			(island_area_min 10)
		)
		(polygon
			(pts
				(xy 173.232504 100.0165) (xy 173.394035 100.011105) (xy 173.478445 100.007554) (xy 173.58014 100.012177)
				(xy 173.601 99.7915) (xy 173.451147 99.628268) (xy 173.397007 99.696935) (xy 173.387115 99.713393)
				(xy 173.362615 99.752065) (xy 173.333109 99.784279) (xy 173.291953 99.806327) (xy 173.232504 99.8145)
			)
		)
	)
	(zone
		(net 1)
		(net_name "GND")
		(layer "F.Cu")
		(name "$teardrop_padvia$")
		(hatch none 0.1)
		(priority 30833)
		(attr
			(teardrop
				(type padvia)
			)
		)
		(connect_pads yes
			(clearance 0)
		)
		(min_thickness 0.0254)
		(filled_areas_thickness no)
		(fill yes
			(thermal_gap 0.5)
			(thermal_bridge_width 0.5)
			(island_removal_mode 1)
			(island_area_min 10)
		)
		(polygon
			(pts
				(xy 245.371105 77.622) (xy 245.318841 77.6173) (xy 245.277709 77.604398) (xy 245.21481 77.55897)
				(xy 245.190161 77.532879) (xy 245.146828 77.489035) (xy 244.999709 77.655) (xy 245.026266 77.875677)
				(xy 245.12588 77.880649) (xy 245.177579 77.893475) (xy 245.260214 77.912745) (xy 245.371105 77.922)
			)
		)
	)
	(zone
		(net 205)
		(net_name "/Backplane/PCIe_{REF}.CK-")
		(layer "F.Cu")
		(name "$teardrop_padvia$")
		(hatch none 0.1)
		(priority 31449)
		(attr
			(teardrop
				(type padvia)
			)
		)
		(connect_pads yes
			(clearance 0)
		)
		(min_thickness 0.0254)
		(filled_areas_thickness no)
		(fill yes
			(thermal_gap 0.5)
			(thermal_bridge_width 0.5)
			(island_removal_mode 1)
			(island_area_min 10)
		)
		(polygon
			(pts
				(xy 258.8065 137.463584) (xy 258.799528 137.293351) (xy 258.797677 137.115931) (xy 258.577 137.099)
				(xy 258.415834 137.250918) (xy 258.484098 137.30277) (xy 258.502419 137.313184) (xy 258.541426 137.336544)
				(xy 258.573955 137.364991) (xy 258.596236 137.405135) (xy 258.6045 137.463584)
			)
		)
	)
	(zone
		(net 136)
		(net_name "/Com Express 7 MGMT/~{TYPE0}")
		(layer "F.Cu")
		(name "$teardrop_padvia$")
		(hatch none 0.1)
		(priority 31569)
		(attr
			(teardrop
				(type padvia)
			)
		)
		(connect_pads yes
			(clearance 0)
		)
		(min_thickness 0.0254)
		(filled_areas_thickness no)
		(fill yes
			(thermal_gap 0.5)
			(thermal_bridge_width 0.5)
			(island_removal_mode 1)
			(island_area_min 10)
		)
		(polygon
			(pts
				(xy 202.5875 155.773148) (xy 202.592238 155.717375) (xy 202.605402 155.674936) (xy 202.650325 155.614854)
				(xy 202.677418 155.590668) (xy 202.719634 155.551941) (xy 202.762081 155.500003) (xy 202.575 155.374)
				(xy 202.362745 155.439229) (xy 202.411026 155.556876) (xy 202.447294 155.644505) (xy 202.4625 155.773148)
			)
		)
	)
	(zone
		(net 600)
		(net_name "Net-(U36-~{HOLD}(D3))")
		(layer "F.Cu")
		(name "$teardrop_padvia$")
		(hatch none 0.1)
		(priority 31096)
		(attr
			(teardrop
				(type padvia)
			)
		)
		(connect_pads yes
			(clearance 0)
		)
		(min_thickness 0.0254)
		(filled_areas_thickness no)
		(fill yes
			(thermal_gap 0.5)
			(thermal_bridge_width 0.5)
			(island_removal_mode 1)
			(island_area_min 10)
		)
		(polygon
			(pts
				(xy 259.0575 160.187) (xy 259.037727 160.246412) (xy 258.974453 160.302496) (xy 258.925828 160.324198)
				(xy 258.866469 160.338872) (xy 258.8545 160.340652) (xy 259.12 160.601) (xy 259.3855 160.340652)
				(xy 259.325362 160.327803) (xy 259.275478 160.307869) (xy 259.235358 160.281944) (xy 259.206345 160.252124)
				(xy 259.188854 160.220706) (xy 259.182521 160.188895) (xy 259.1825 160.187)
			)
		)
	)
	(zone
		(net 635)
		(net_name "Net-(U41-SCL)")
		(layer "F.Cu")
		(name "$teardrop_padvia$")
		(hatch none 0.1)
		(priority 31526)
		(attr
			(teardrop
				(type padvia)
			)
		)
		(connect_pads yes
			(clearance 0)
		)
		(min_thickness 0.0254)
		(filled_areas_thickness no)
		(fill yes
			(thermal_gap 0.5)
			(thermal_bridge_width 0.5)
			(island_removal_mode 1)
			(island_area_min 10)
		)
		(polygon
			(pts
				(xy 132.931466 82.691923) (xy 132.958569 82.623714) (xy 132.98996 82.585538) (xy 133.031552 82.551373)
				(xy 133.079945 82.525176) (xy 133.135688 82.508067) (xy 133.157622 82.504611) (xy 132.900707 82.239294)
				(xy 132.671054 82.523773) (xy 132.750597 82.53267) (xy 132.806747 82.55037) (xy 132.831772 82.568602)
				(xy 132.842871 82.591316) (xy 132.843078 82.603535)
			)
		)
	)
	(zone
		(net 73)
		(net_name "+3V3_AON")
		(layer "F.Cu")
		(name "$teardrop_padvia$")
		(hatch none 0.1)
		(priority 31285)
		(attr
			(teardrop
				(type padvia)
			)
		)
		(connect_pads yes
			(clearance 0)
		)
		(min_thickness 0.0254)
		(filled_areas_thickness no)
		(fill yes
			(thermal_gap 0.5)
			(thermal_bridge_width 0.5)
			(island_removal_mode 1)
			(island_area_min 10)
		)
		(polygon
			(pts
				(xy 244.43 126.309323) (xy 244.425287 126.387234) (xy 244.4123 126.446018) (xy 244.370199 126.537048)
				(xy 244.3275 126.622221) (xy 244.53 126.711) (xy 244.7325 126.622221) (xy 244.689801 126.53705)
				(xy 244.647133 126.444217) (xy 244.634556 126.386078) (xy 244.63 126.309323)
			)
		)
	)
	(zone
		(net 969)
		(net_name "/M.2 key M #1/M2_3V3")
		(layer "F.Cu")
		(hatch edge 0.5)
		(priority 5)
		(connect_pads yes
			(clearance 0.15)
		)
		(min_thickness 0.25)
		(filled_areas_thickness no)
		(fill yes
			(thermal_gap 0.2)
			(thermal_bridge_width 0.5)
		)
		(polygon
			(pts
				(xy 180 88.21) (xy 177.6 88.21) (xy 177.6 93.86) (xy 178.65 93.86) (xy 180 92.51)
			)
		)
	)
	(zone
		(net 2)
		(net_name "+3V3")
		(layer "F.Cu")
		(name "$teardrop_padvia$")
		(hatch none 0.1)
		(priority 30407)
		(attr
			(teardrop
				(type padvia)
			)
		)
		(connect_pads yes
			(clearance 0)
		)
		(min_thickness 0.0254)
		(filled_areas_thickness no)
		(fill yes
			(thermal_gap 0.5)
			(thermal_bridge_width 0.5)
			(island_removal_mode 1)
			(island_area_min 10)
		)
		(polygon
			(pts
				(xy 114.15 145.408) (xy 114.170403 145.452645) (xy 114.189221 145.486192) (xy 114.197795 145.518655)
				(xy 114.183697 145.545365) (xy 114.1345 145.561652) (xy 114.4 145.822) (xy 114.6655 145.561652)
				(xy 114.627407 145.551832) (xy 114.607642 145.536425) (xy 114.604648 145.5021) (xy 114.629597 145.452645)
				(xy 114.65 145.408)
			)
		)
	)
	(zone
		(net 379)
		(net_name "Net-(J12D-~{ESPI_EN})")
		(layer "F.Cu")
		(name "$teardrop_padvia$")
		(hatch none 0.1)
		(priority 30689)
		(attr
			(teardrop
				(type padvia)
			)
		)
		(connect_pads yes
			(clearance 0)
		)
		(min_thickness 0.0254)
		(filled_areas_thickness no)
		(fill yes
			(thermal_gap 0.5)
			(thermal_bridge_width 0.5)
			(island_removal_mode 1)
			(island_area_min 10)
		)
		(polygon
			(pts
				(xy 198.9625 162.2) (xy 198.951563 162.238823) (xy 198.929805 162.253933) (xy 198.89 162.26) (xy 199.025 163.136)
				(xy 199.16 162.26) (xy 199.124719 162.255483) (xy 199.103203 162.243862) (xy 199.088005 162.211039)
				(xy 199.0875 162.2)
			)
		)
	)
	(zone
		(net 49)
		(net_name "/2xUSB3.0+RJ45/USBSS_2.TX-")
		(layer "F.Cu")
		(name "$teardrop_padvia$")
		(hatch none 0.1)
		(priority 30288)
		(attr
			(teardrop
				(type padvia)
			)
		)
		(connect_pads yes
			(clearance 0)
		)
		(min_thickness 0.0254)
		(filled_areas_thickness no)
		(fill yes
			(thermal_gap 0.5)
			(thermal_bridge_width 0.5)
			(island_removal_mode 1)
			(island_area_min 10)
		)
		(polygon
			(pts
				(xy 181.4925 150.2) (xy 181.494085 150.212189) (xy 181.492704 150.243738) (xy 181.477931 150.255396)
				(xy 181.445877 150.26) (xy 181.525 151.136) (xy 181.675 150.906314) (xy 181.655715 150.6469) (xy 181.668097 150.373917)
				(xy 181.6775 150.2)
			)
		)
	)
	(zone
		(net 195)
		(net_name "/OCuLink/PCIe_{x4}.RX2-")
		(layer "F.Cu")
		(name "$teardrop_padvia$")
		(hatch none 0.1)
		(priority 32073)
		(attr
			(teardrop
				(type padvia)
			)
		)
		(connect_pads yes
			(clearance 0)
		)
		(min_thickness 0.0254)
		(filled_areas_thickness no)
		(fill yes
			(thermal_gap 0.5)
			(thermal_bridge_width 0.5)
			(island_removal_mode 1)
			(island_area_min 10)
		)
		(polygon
			(pts
				(xy 107.999 151.488) (xy 108.006198 151.508648) (xy 108.015792 151.540984) (xy 108.008965 151.555007)
				(xy 107.9875 151.564995) (xy 108.1 151.814) (xy 108.2125 151.564995) (xy 108.191324 151.555271)
				(xy 108.184269 151.541643) (xy 108.193802 151.508648) (xy 108.201 151.488)
			)
		)
	)
	(zone
		(net 625)
		(net_name "/PCIe redriver/TX_EQ2")
		(layer "F.Cu")
		(name "$teardrop_padvia$")
		(hatch none 0.1)
		(priority 31831)
		(attr
			(teardrop
				(type padvia)
			)
		)
		(connect_pads yes
			(clearance 0)
		)
		(min_thickness 0.0254)
		(filled_areas_thickness no)
		(fill yes
			(thermal_gap 0.5)
			(thermal_bridge_width 0.5)
			(island_removal_mode 1)
			(island_area_min 10)
		)
		(polygon
			(pts
				(xy 113.300677 143.1575) (xy 113.231236 143.152682) (xy 113.179913 143.13896) (xy 113.104371 143.092246)
				(xy 113.092231 143.082701) (xy 113.025003 143.032919) (xy 112.899 143.22) (xy 113.025003 143.407081)
				(xy 113.092229 143.357299) (xy 113.175396 143.302894) (xy 113.228251 143.28781) (xy 113.300677 143.2825)
			)
		)
	)
	(zone
		(net 574)
		(net_name "Net-(U19-EN)")
		(layer "F.Cu")
		(name "$teardrop_padvia$")
		(hatch none 0.1)
		(priority 32129)
		(attr
			(teardrop
				(type padvia)
			)
		)
		(connect_pads yes
			(clearance 0)
		)
		(min_thickness 0.0254)
		(filled_areas_thickness no)
		(fill yes
			(thermal_gap 0.5)
			(thermal_bridge_width 0.5)
			(island_removal_mode 1)
			(island_area_min 10)
		)
		(polygon
			(pts
				(xy 309.97692 104.361499) (xy 309.994386 104.360024) (xy 310.035831 104.359895) (xy 310.056844 104.368882)
				(xy 310.075986 104.388999) (xy 310.315999 104.298999) (xy 310.075986 104.208999) (xy 310.057842 104.228417)
				(xy 310.037938 104.237605) (xy 309.994386 104.237974) (xy 309.97692 104.236499)
			)
		)
	)
	(zone
		(net 534)
		(net_name "Net-(Q1-D)")
		(layer "F.Cu")
		(name "$teardrop_padvia$")
		(hatch none 0.1)
		(priority 30185)
		(attr
			(teardrop
				(type padvia)
			)
		)
		(connect_pads yes
			(clearance 0)
		)
		(min_thickness 0.0254)
		(filled_areas_thickness no)
		(fill yes
			(thermal_gap 0.5)
			(thermal_bridge_width 0.5)
			(island_removal_mode 1)
			(island_area_min 10)
		)
		(polygon
			(pts
				(xy 306.695 138.6595) (xy 306.656486 138.653825) (xy 306.617381 138.634097) (xy 306.590531 138.607219)
				(xy 306.568718 138.568111) (xy 306.551072 138.4895) (xy 306.074 138.7595) (xy 306.551072 139.0295)
				(xy 306.560617 138.974894) (xy 306.577225 138.932658) (xy 306.624911 138.879693) (xy 306.685814 138.859816)
				(xy 306.695 138.8595)
			)
		)
	)
	(zone
		(net 571)
		(net_name "Net-(U7-A_{1})")
		(layer "F.Cu")
		(name "$teardrop_padvia$")
		(hatch none 0.1)
		(priority 30343)
		(attr
			(teardrop
				(type padvia)
			)
		)
		(connect_pads yes
			(clearance 0)
		)
		(min_thickness 0.0254)
		(filled_areas_thickness no)
		(fill yes
			(thermal_gap 0.5)
			(thermal_bridge_width 0.5)
			(island_removal_mode 1)
			(island_area_min 10)
		)
		(polygon
			(pts
				(xy 122.0495 72.274) (xy 122.055281 72.240137) (xy 122.075745 72.205516) (xy 122.102811 72.183694)
				(xy 122.14215 72.168) (xy 122.157711 72.164711) (xy 121.987 71.458) (xy 121.816289 72.164711) (xy 121.85651 72.1763)
				(xy 121.885984 72.193885) (xy 121.919173 72.241467) (xy 121.9245 72.274)
			)
		)
	)
	(zone
		(net 663)
		(net_name "Net-(U43C-ST)")
		(layer "F.Cu")
		(name "$teardrop_padvia$")
		(hatch none 0.1)
		(priority 30969)
		(attr
			(teardrop
				(type padvia)
			)
		)
		(connect_pads yes
			(clearance 0)
		)
		(min_thickness 0.0254)
		(filled_areas_thickness no)
		(fill yes
			(thermal_gap 0.5)
			(thermal_bridge_width 0.5)
			(island_removal_mode 1)
			(island_area_min 10)
		)
		(polygon
			(pts
				(xy 143.4175 134.442) (xy 143.397531 134.504866) (xy 143.371079 134.536844) (xy 143.333668 134.565358)
				(xy 143.286473 134.587882) (xy 143.228833 134.603093) (xy 143.228202 134.603202) (xy 143.48 134.881)
				(xy 143.731798 134.603202) (xy 143.676365 134.588905) (xy 143.63048 134.567825) (xy 143.592799 134.54046)
				(xy 143.565566 134.509552) (xy 143.548528 134.476265) (xy 143.542511 134.443434) (xy 143.5425 134.442)
			)
		)
	)
	(zone
		(net 365)
		(net_name "/Com Express 7 MGMT/PWR_OK")
		(layer "F.Cu")
		(name "$teardrop_padvia$")
		(hatch none 0.1)
		(priority 31586)
		(attr
			(teardrop
				(type padvia)
			)
		)
		(connect_pads yes
			(clearance 0)
		)
		(min_thickness 0.0254)
		(filled_areas_thickness no)
		(fill yes
			(thermal_gap 0.5)
			(thermal_bridge_width 0.5)
			(island_removal_mode 1)
			(island_area_min 10)
		)
		(polygon
			(pts
				(xy 277.100677 129.0765) (xy 277.042538 129.071758) (xy 276.998415 129.058563) (xy 276.935293 129.01354)
				(xy 276.912923 128.990517) (xy 276.825003 128.912919) (xy 276.699 129.1) (xy 276.769058 129.310254)
				(xy 276.885995 129.257585) (xy 276.972552 129.218102) (xy 277.027971 129.205973) (xy 277.100677 129.2015)
			)
		)
	)
	(zone
		(net 80)
		(net_name "Net-(Q6-D)")
		(layer "F.Cu")
		(name "$teardrop_padvia$")
		(hatch none 0.1)
		(priority 30910)
		(attr
			(teardrop
				(type padvia)
			)
		)
		(connect_pads yes
			(clearance 0)
		)
		(min_thickness 0.0254)
		(filled_areas_thickness no)
		(fill yes
			(thermal_gap 0.5)
			(thermal_bridge_width 0.5)
			(island_removal_mode 1)
			(island_area_min 10)
		)
		(polygon
			(pts
				(xy 261.76 91.335) (xy 261.742933 91.336041) (xy 261.712146 91.337052) (xy 261.682008 91.32801)
				(xy 261.659099 91.298349) (xy 261.65 91.2375) (xy 261.349 91.485) (xy 261.65 91.7325) (xy 261.654623 91.686135)
				(xy 261.666987 91.656618) (xy 261.702025 91.63426) (xy 261.742933 91.633959) (xy 261.76 91.635)
			)
		)
	)
	(zone
		(net 14)
		(net_name "/Com Express 7 Interfaces/PCIe_{B1x2}.RX0+")
		(layer "F.Cu")
		(name "$teardrop_padvia$")
		(hatch none 0.1)
		(priority 30263)
		(attr
			(teardrop
				(type padvia)
			)
		)
		(connect_pads yes
			(clearance 0)
		)
		(min_thickness 0.0254)
		(filled_areas_thickness no)
		(fill yes
			(thermal_gap 0.5)
			(thermal_bridge_width 0.5)
			(island_removal_mode 1)
			(island_area_min 10)
		)
		(polygon
			(pts
				(xy 203.1815 164.07) (xy 203.170401 163.896888) (xy 203.155784 163.66949) (xy 203.158819 163.534862)
				(xy 203.175 163.382978) (xy 203.025 163.134) (xy 202.941705 164.01) (xy 202.972136 164.014477) (xy 202.984903 164.025815)
				(xy 202.98258 164.055773) (xy 202.9795 164.07)
			)
		)
	)
	(zone
		(net 85)
		(net_name "/Com Express 7 MGMT/MAFS_POWER")
		(layer "F.Cu")
		(name "$teardrop_padvia$")
		(hatch none 0.1)
		(priority 30237)
		(attr
			(teardrop
				(type padvia)
			)
		)
		(connect_pads yes
			(clearance 0)
		)
		(min_thickness 0.0254)
		(filled_areas_thickness no)
		(fill yes
			(thermal_gap 0.5)
			(thermal_bridge_width 0.5)
			(island_removal_mode 1)
			(island_area_min 10)
		)
		(polygon
			(pts
				(xy 251.988685 165.290815) (xy 252.008503 165.310148) (xy 252.058745 165.361236) (xy 252.106193 165.425445)
				(xy 252.13892 165.507086) (xy 252.145 165.610473) (xy 252.440707 165.530707) (xy 252.495474 165.21)
				(xy 252.441747 165.21506) (xy 252.394293 165.210542) (xy 252.310798 165.177112) (xy 252.234031 165.11289)
				(xy 252.218343 165.096694) (xy 252.200816 165.078684)
			)
		)
	)
	(zone
		(net 208)
		(net_name "/Backplane/UART.RX")
		(layer "F.Cu")
		(name "$teardrop_padvia$")
		(hatch none 0.1)
		(priority 32123)
		(attr
			(teardrop
				(type padvia)
			)
		)
		(connect_pads yes
			(clearance 0)
		)
		(min_thickness 0.0254)
		(filled_areas_thickness no)
		(fill yes
			(thermal_gap 0.5)
			(thermal_bridge_width 0.5)
			(island_removal_mode 1)
			(island_area_min 10)
		)
		(polygon
			(pts
				(xy 314.688 167.4455) (xy 314.681678 167.445596) (xy 314.642175 167.440011) (xy 314.623953 167.425078)
				(xy 314.611005 167.3955) (xy 314.362 167.508) (xy 314.611005 167.6205) (xy 314.622121 167.593506)
				(xy 314.637648 167.578405) (xy 314.681678 167.570404) (xy 314.688 167.5705)
			)
		)
	)
	(zone
		(net 1)
		(net_name "GND")
		(layer "F.Cu")
		(name "$teardrop_padvia$")
		(hatch none 0.1)
		(priority 31228)
		(attr
			(teardrop
				(type padvia)
			)
		)
		(connect_pads yes
			(clearance 0)
		)
		(min_thickness 0.0254)
		(filled_areas_thickness no)
		(fill yes
			(thermal_gap 0.5)
			(thermal_bridge_width 0.5)
			(island_removal_mode 1)
			(island_area_min 10)
		)
		(polygon
			(pts
				(xy 186.125 162.100677) (xy 186.129737 162.009676) (xy 186.142896 161.942587) (xy 186.175418 161.855855)
				(xy 186.207644 161.775358) (xy 186 161.699) (xy 185.803541 161.802363) (xy 185.855343 161.885863)
				(xy 185.904833 161.971955) (xy 185.919614 162.02716) (xy 185.925 162.100677)
			)
		)
	)
	(zone
		(net 932)
		(net_name "Net-(D7-C)")
		(layer "F.Cu")
		(name "$teardrop_padvia$")
		(hatch none 0.1)
		(priority 30176)
		(attr
			(teardrop
				(type padvia)
			)
		)
		(connect_pads yes
			(clearance 0)
		)
		(min_thickness 0.0254)
		(filled_areas_thickness no)
		(fill yes
			(thermal_gap 0.5)
			(thermal_bridge_width 0.5)
			(island_removal_mode 1)
			(island_area_min 10)
		)
		(polygon
			(pts
				(xy 147.75 168.3775) (xy 147.69156 168.358243) (xy 147.637486 168.297235) (xy 147.597203 168.187634)
				(xy 147.586022 168.08) (xy 147.189 168.44) (xy 147.586022 168.8) (xy 147.591642 168.724212) (xy 147.605856 168.657749)
				(xy 147.627451 168.601481) (xy 147.655051 168.556792) (xy 147.685041 168.526501) (xy 147.718017 168.508124)
				(xy 147.75 168.5025)
			)
		)
	)
	(zone
		(net 330)
		(net_name "/Com Express 7 Interfaces/PCIe_{B2Ax4}.TX3+")
		(layer "F.Cu")
		(name "$teardrop_padvia$")
		(hatch none 0.1)
		(priority 31452)
		(attr
			(teardrop
				(type padvia)
			)
		)
		(connect_pads yes
			(clearance 0)
		)
		(min_thickness 0.0254)
		(filled_areas_thickness no)
		(fill yes
			(thermal_gap 0.5)
			(thermal_bridge_width 0.5)
			(island_removal_mode 1)
			(island_area_min 10)
		)
		(polygon
			(pts
				(xy 233.263584 148.8935) (xy 233.09335 148.900471) (xy 232.915931 148.902323) (xy 232.899 149.123)
				(xy 233.050918 149.284165) (xy 233.10277 149.2159) (xy 233.113183 149.197581) (xy 233.136543 149.158574)
				(xy 233.164991 149.126045) (xy 233.205135 149.103764) (xy 233.263584 149.0955)
			)
		)
	)
	(zone
		(net 1)
		(net_name "GND")
		(layer "F.Cu")
		(name "$teardrop_padvia$")
		(hatch none 0.1)
		(priority 31923)
		(attr
			(teardrop
				(type padvia)
			)
		)
		(connect_pads yes
			(clearance 0)
		)
		(min_thickness 0.0254)
		(filled_areas_thickness no)
		(fill yes
			(thermal_gap 0.5)
			(thermal_bridge_width 0.5)
			(island_removal_mode 1)
			(island_area_min 10)
		)
		(polygon
			(pts
				(xy 112.118 132.31) (xy 112.107885 132.310153) (xy 112.077169 132.30954) (xy 112.04468 132.301218)
				(xy 112.015526 132.277325) (xy 111.994809 132.23) (xy 111.762 132.41) (xy 111.994809 132.59) (xy 112.008168 132.554099)
				(xy 112.026399 132.530801) (xy 112.071725 132.511101) (xy 112.107885 132.509847) (xy 112.118 132.51)
			)
		)
	)
	(zone
		(net 1)
		(net_name "GND")
		(layer "F.Cu")
		(name "$teardrop_padvia$")
		(hatch none 0.1)
		(priority 30581)
		(attr
			(teardrop
				(type padvia)
			)
		)
		(connect_pads yes
			(clearance 0)
		)
		(min_thickness 0.0254)
		(filled_areas_thickness no)
		(fill yes
			(thermal_gap 0.5)
			(thermal_bridge_width 0.5)
			(island_removal_mode 1)
			(island_area_min 10)
		)
		(polygon
			(pts
				(xy 194.625 169.62) (xy 194.621667 169.605514) (xy 194.61881 169.57539) (xy 194.630964 169.564349)
				(xy 194.66 169.56) (xy 194.525 168.684) (xy 194.39 169.56) (xy 194.419334 169.564475) (xy 194.431358 169.575801)
				(xy 194.428333 169.605514) (xy 194.425 169.62)
			)
		)
	)
	(zone
		(net 188)
		(net_name "/OCuLink/PCIe_{x4}.RX1+")
		(layer "F.Cu")
		(name "$teardrop_padvia$")
		(hatch none 0.1)
		(priority 31373)
		(attr
			(teardrop
				(type padvia)
			)
		)
		(connect_pads yes
			(clearance 0)
		)
		(min_thickness 0.0254)
		(filled_areas_thickness no)
		(fill yes
			(thermal_gap 0.5)
			(thermal_bridge_width 0.5)
			(island_removal_mode 1)
			(island_area_min 10)
		)
		(polygon
			(pts
				(xy 98.662504 164.6505) (xy 98.70929 164.655235) (xy 98.744742 164.668379) (xy 98.792939 164.713387)
				(xy 98.817116 164.751608) (xy 98.844485 164.794773) (xy 98.881147 164.836731) (xy 99.031 164.6735)
				(xy 99.01014 164.452823) (xy 98.909466 164.457452) (xy 98.826096 164.454019) (xy 98.824035 164.453895)
				(xy 98.662504 164.4485)
			)
		)
	)
	(zone
		(net 697)
		(net_name "Net-(U5-IO0_6)")
		(layer "F.Cu")
		(name "$teardrop_padvia$")
		(hatch none 0.1)
		(priority 31663)
		(attr
			(teardrop
				(type padvia)
			)
		)
		(connect_pads yes
			(clearance 0)
		)
		(min_thickness 0.0254)
		(filled_areas_thickness no)
		(fill yes
			(thermal_gap 0.5)
			(thermal_bridge_width 0.5)
			(island_removal_mode 1)
			(island_area_min 10)
		)
		(polygon
			(pts
				(xy 157.9875 162.992166) (xy 157.982729 163.030255) (xy 157.969336 163.056183) (xy 157.926572 163.08065)
				(xy 157.86241 163.088648) (xy 157.795286 163.096193) (xy 157.73032 163.120713) (xy 157.85 163.311)
				(xy 158.070677 163.340279) (xy 158.090415 163.223865) (xy 158.10613 163.127805) (xy 158.1125 162.992166)
			)
		)
	)
	(zone
		(net 636)
		(net_name "Net-(U41-~{INT})")
		(layer "F.Cu")
		(name "$teardrop_padvia$")
		(hatch none 0.1)
		(priority 32007)
		(attr
			(teardrop
				(type padvia)
			)
		)
		(connect_pads yes
			(clearance 0)
		)
		(min_thickness 0.0254)
		(filled_areas_thickness no)
		(fill yes
			(thermal_gap 0.5)
			(thermal_bridge_width 0.5)
			(island_removal_mode 1)
			(island_area_min 10)
		)
		(polygon
			(pts
				(xy 130.3375 83.1595) (xy 130.337596 83.165822) (xy 130.332011 83.205325) (xy 130.317078 83.223547)
				(xy 130.2875 83.236495) (xy 130.4 83.623) (xy 130.5125 83.236495) (xy 130.485507 83.225379) (xy 130.470405 83.209852)
				(xy 130.462404 83.165822) (xy 130.4625 83.1595)
			)
		)
	)
	(zone
		(net 607)
		(net_name "Net-(U37-~{HIBW_BYPM_LOBW})")
		(layer "F.Cu")
		(name "$teardrop_padvia$")
		(hatch none 0.1)
		(priority 31113)
		(attr
			(teardrop
				(type padvia)
			)
		)
		(connect_pads yes
			(clearance 0)
		)
		(min_thickness 0.0254)
		(filled_areas_thickness no)
		(fill yes
			(thermal_gap 0.5)
			(thermal_bridge_width 0.5)
			(island_removal_mode 1)
			(island_area_min 10)
		)
		(polygon
			(pts
				(xy 218.837 123.9625) (xy 218.896412 123.982273) (xy 218.952497 124.045547) (xy 218.974199 124.094172)
				(xy 218.988873 124.153531) (xy 218.990653 124.1655) (xy 219.251 123.9) (xy 218.990653 123.6345)
				(xy 218.977804 123.694638) (xy 218.95787 123.744522) (xy 218.931945 123.784641) (xy 218.902125 123.813654)
				(xy 218.870707 123.831146) (xy 218.838896 123.837479) (xy 218.837 123.8375)
			)
		)
	)
	(zone
		(net 598)
		(net_name "Net-(U31-~{WC})")
		(layer "F.Cu")
		(name "$teardrop_padvia$")
		(hatch none 0.1)
		(priority 31005)
		(attr
			(teardrop
				(type padvia)
			)
		)
		(connect_pads yes
			(clearance 0)
		)
		(min_thickness 0.0254)
		(filled_areas_thickness no)
		(fill yes
			(thermal_gap 0.5)
			(thermal_bridge_width 0.5)
			(island_removal_mode 1)
			(island_area_min 10)
		)
		(polygon
			(pts
				(xy 238.3125 153.368999) (xy 238.332469 153.306133) (xy 238.358921 153.274155) (xy 238.396332 153.245641)
				(xy 238.443527 153.223117) (xy 238.501167 153.207906) (xy 238.501798 153.207797) (xy 238.25 152.929999)
				(xy 237.998202 153.207797) (xy 238.053635 153.222094) (xy 238.09952 153.243174) (xy 238.137201 153.270539)
				(xy 238.164434 153.301447) (xy 238.181472 153.334734) (xy 238.187489 153.367565) (xy 238.1875 153.368999)
			)
		)
	)
	(zone
		(net 353)
		(net_name "Net-(J12D-~{LPC_DRQ0}{slash}~{ESPI_ALERT0})")
		(layer "F.Cu")
		(name "$teardrop_padvia$")
		(hatch none 0.1)
		(priority 31857)
		(attr
			(teardrop
				(type padvia)
			)
		)
		(connect_pads yes
			(clearance 0)
		)
		(min_thickness 0.0254)
		(filled_areas_thickness no)
		(fill yes
			(thermal_gap 0.5)
			(thermal_bridge_width 0.5)
			(island_removal_mode 1)
			(island_area_min 10)
		)
		(polygon
			(pts
				(xy 179.139127 165.372485) (xy 179.086618 165.418181) (xy 179.040623 165.444768) (xy 178.954174 165.465152)
				(xy 178.938841 165.466988) (xy 178.856105 165.479323) (xy 178.899293 165.700707) (xy 179.120677 165.743895)
				(xy 179.133011 165.66116) (xy 179.153349 165.563881) (xy 179.180057 165.515841) (xy 179.227515 165.460873)
			)
		)
	)
	(zone
		(net 428)
		(net_name "/2xSFP+/10GKR_SFP1.RX-")
		(layer "F.Cu")
		(name "$teardrop_padvia$")
		(hatch none 0.1)
		(priority 30901)
		(attr
			(teardrop
				(type padvia)
			)
		)
		(connect_pads yes
			(clearance 0)
		)
		(min_thickness 0.0254)
		(filled_areas_thickness no)
		(fill yes
			(thermal_gap 0.5)
			(thermal_bridge_width 0.5)
			(island_removal_mode 1)
			(island_area_min 10)
		)
		(polygon
			(pts
				(xy 196.885 155.75) (xy 196.890417 155.767388) (xy 196.897891 155.795743) (xy 196.892331 155.805985)
				(xy 196.875 155.81) (xy 197.025 156.686) (xy 197.104123 155.81) (xy 197.070422 155.805503) (xy 197.052459 155.794025)
				(xy 197.044745 155.757452) (xy 197.045 155.75)
			)
		)
	)
	(zone
		(net 2)
		(net_name "+3V3")
		(layer "F.Cu")
		(name "$teardrop_padvia$")
		(hatch none 0.1)
		(priority 31685)
		(attr
			(teardrop
				(type padvia)
			)
		)
		(connect_pads yes
			(clearance 0)
		)
		(min_thickness 0.0254)
		(filled_areas_thickness no)
		(fill yes
			(thermal_gap 0.5)
			(thermal_bridge_width 0.5)
			(island_removal_mode 1)
			(island_area_min 10)
		)
		(polygon
			(pts
				(xy 145.7275 169.347019) (xy 145.732097 169.416918) (xy 145.744279 169.470464) (xy 145.778095 169.546726)
				(xy 145.806158 169.605617) (xy 145.829323 169.683895) (xy 146.05 169.641) (xy 146.093895 169.419323)
				(xy 146.008441 169.417026) (xy 145.984603 169.419108) (xy 145.933674 169.422475) (xy 145.891629 169.417127)
				(xy 145.863045 169.394748) (xy 145.8525 169.347019)
			)
		)
	)
	(zone
		(net 945)
		(net_name "/GPIO expander/GPIOEX5")
		(layer "F.Cu")
		(name "$teardrop_padvia$")
		(hatch none 0.1)
		(priority 31123)
		(attr
			(teardrop
				(type padvia)
			)
		)
		(connect_pads yes
			(clearance 0)
		)
		(min_thickness 0.0254)
		(filled_areas_thickness no)
		(fill yes
			(thermal_gap 0.5)
			(thermal_bridge_width 0.5)
			(island_removal_mode 1)
			(island_area_min 10)
		)
		(polygon
			(pts
				(xy 211.697 132.3225) (xy 211.756412 132.342273) (xy 211.812497 132.405547) (xy 211.834199 132.454172)
				(xy 211.848873 132.513531) (xy 211.850653 132.5255) (xy 212.111 132.26) (xy 211.850653 131.9945)
				(xy 211.837804 132.054638) (xy 211.81787 132.104522) (xy 211.791945 132.144641) (xy 211.762125 132.173654)
				(xy 211.730707 132.191146) (xy 211.698896 132.197479) (xy 211.697 132.1975)
			)
		)
	)
	(zone
		(net 1)
		(net_name "GND")
		(layer "F.Cu")
		(name "$teardrop_padvia$")
		(hatch none 0.1)
		(priority 31184)
		(attr
			(teardrop
				(type padvia)
			)
		)
		(connect_pads yes
			(clearance 0)
		)
		(min_thickness 0.0254)
		(filled_areas_thickness no)
		(fill yes
			(thermal_gap 0.5)
			(thermal_bridge_width 0.5)
			(island_removal_mode 1)
			(island_area_min 10)
		)
		(polygon
			(pts
				(xy 212.125 150.321677) (xy 212.12972 150.252353) (xy 212.142756 150.199449) (xy 212.194658 150.10686)
				(xy 212.246458 150.023363) (xy 212.05 149.92) (xy 211.842355 149.996358) (xy 211.874583 150.076861)
				(xy 211.910965 150.178318) (xy 211.925 150.321677)
			)
		)
	)
	(zone
		(net 329)
		(net_name "/Com Express 7 Interfaces/PCIe_{B2Ax4}.TX2-")
		(layer "F.Cu")
		(name "$teardrop_padvia$")
		(hatch none 0.1)
		(priority 31443)
		(attr
			(teardrop
				(type padvia)
			)
		)
		(connect_pads yes
			(clearance 0)
		)
		(min_thickness 0.0254)
		(filled_areas_thickness no)
		(fill yes
			(thermal_gap 0.5)
			(thermal_bridge_width 0.5)
			(island_removal_mode 1)
			(island_area_min 10)
		)
		(polygon
			(pts
				(xy 231.2455 147.163584) (xy 231.250235 147.117781) (xy 231.263381 147.0832) (xy 231.308329 147.03671)
				(xy 231.347581 147.013183) (xy 231.391576 146.986771) (xy 231.434165 146.950918) (xy 231.273 146.799)
				(xy 231.052323 146.815931) (xy 231.050471 146.99335) (xy 231.0435 147.163584)
			)
		)
	)
	(zone
		(net 372)
		(net_name "/Com Express 7 MGMT/I2C.SDA")
		(layer "F.Cu")
		(name "$teardrop_padvia$")
		(hatch none 0.1)
		(priority 30724)
		(attr
			(teardrop
				(type padvia)
			)
		)
		(connect_pads yes
			(clearance 0)
		)
		(min_thickness 0.0254)
		(filled_areas_thickness no)
		(fill yes
			(thermal_gap 0.5)
			(thermal_bridge_width 0.5)
			(island_removal_mode 1)
			(island_area_min 10)
		)
		(polygon
			(pts
				(xy 302.7625 93.22) (xy 302.757179 93.251735) (xy 302.739931 93.284435) (xy 302.713462 93.310626)
				(xy 302.675036 93.331555) (xy 302.63295 93.34295) (xy 302.825 93.861) (xy 303.01705 93.34295) (xy 302.972526 93.330591)
				(xy 302.9384 93.311992) (xy 302.896464 93.261197) (xy 302.8875 93.22)
			)
		)
	)
	(zone
		(net 492)
		(net_name "/2xSFP+/MOD1_ABS")
		(layer "F.Cu")
		(name "$teardrop_padvia$")
		(hatch none 0.1)
		(priority 30680)
		(attr
			(teardrop
				(type padvia)
			)
		)
		(connect_pads yes
			(clearance 0)
		)
		(min_thickness 0.0254)
		(filled_areas_thickness no)
		(fill yes
			(thermal_gap 0.5)
			(thermal_bridge_width 0.5)
			(island_removal_mode 1)
			(island_area_min 10)
		)
		(polygon
			(pts
				(xy 198.9625 150.2) (xy 198.951563 150.238823) (xy 198.929805 150.253933) (xy 198.89 150.26) (xy 199.025 151.136)
				(xy 199.16 150.26) (xy 199.124719 150.255483) (xy 199.103203 150.243862) (xy 199.088005 150.211039)
				(xy 199.0875 150.2)
			)
		)
	)
	(zone
		(net 745)
		(net_name "/2xSFP+/KR to SFI #2/TCK")
		(layer "F.Cu")
		(name "$teardrop_padvia$")
		(hatch none 0.1)
		(priority 30134)
		(attr
			(teardrop
				(type padvia)
			)
		)
		(connect_pads yes
			(clearance 0)
		)
		(min_thickness 0.0254)
		(filled_areas_thickness no)
		(fill yes
			(thermal_gap 0.5)
			(thermal_bridge_width 0.5)
			(island_removal_mode 1)
			(island_area_min 10)
		)
		(polygon
			(pts
				(xy 134.3525 130.227794) (xy 134.357315 130.145733) (xy 134.371019 130.080388) (xy 134.417576 129.98712)
				(xy 134.485787 129.908657) (xy 134.541942 129.847158) (xy 134.601801 129.768339) (xy 134.29 129.559)
				(xy 133.978199 129.768339) (xy 134.075219 129.888517) (xy 134.094214 129.908658) (xy 134.147366 129.967541)
				(xy 134.189591 130.031624) (xy 134.217449 130.114008) (xy 134.2275 130.227794)
			)
		)
	)
	(zone
		(net 194)
		(net_name "/OCuLink/PCIe_{x4}.RX2+")
		(layer "F.Cu")
		(name "$teardrop_padvia$")
		(hatch none 0.1)
		(priority 32062)
		(attr
			(teardrop
				(type padvia)
			)
		)
		(connect_pads yes
			(clearance 0)
		)
		(min_thickness 0.0254)
		(filled_areas_thickness no)
		(fill yes
			(thermal_gap 0.5)
			(thermal_bridge_width 0.5)
			(island_removal_mode 1)
			(island_area_min 10)
		)
		(polygon
			(pts
				(xy 108.701 152.138) (xy 108.693802 152.117352) (xy 108.684208 152.085016) (xy 108.691035 152.070993)
				(xy 108.7125 152.061004) (xy 108.6 151.812) (xy 108.4875 152.061004) (xy 108.508676 152.070729)
				(xy 108.515731 152.084357) (xy 108.506198 152.117352) (xy 108.499 152.138)
			)
		)
	)
	(zone
		(net 723)
		(net_name "/2xSFP+/KR to SFI #1/TDO")
		(layer "F.Cu")
		(name "$teardrop_padvia$")
		(hatch none 0.1)
		(priority 30108)
		(attr
			(teardrop
				(type padvia)
			)
		)
		(connect_pads yes
			(clearance 0)
		)
		(min_thickness 0.0254)
		(filled_areas_thickness no)
		(fill yes
			(thermal_gap 0.5)
			(thermal_bridge_width 0.5)
			(island_removal_mode 1)
			(island_area_min 10)
		)
		(polygon
			(pts
				(xy 151.8625 129.377794) (xy 151.867315 129.295733) (xy 151.881019 129.230388) (xy 151.927576 129.13712)
				(xy 151.995787 129.058657) (xy 152.051942 128.997158) (xy 152.111801 128.918339) (xy 151.8 128.709)
				(xy 151.488199 128.918339) (xy 151.585219 129.038517) (xy 151.604214 129.058658) (xy 151.657366 129.117541)
				(xy 151.699591 129.181624) (xy 151.727449 129.264008) (xy 151.7375 129.377794)
			)
		)
	)
	(zone
		(net 323)
		(net_name "/Com Express 7 Interfaces/SDIO.DAT2")
		(layer "F.Cu")
		(name "$teardrop_padvia$")
		(hatch none 0.1)
		(priority 30628)
		(attr
			(teardrop
				(type padvia)
			)
		)
		(connect_pads yes
			(clearance 0)
		)
		(min_thickness 0.0254)
		(filled_areas_thickness no)
		(fill yes
			(thermal_gap 0.5)
			(thermal_bridge_width 0.5)
			(island_removal_mode 1)
			(island_area_min 10)
		)
		(polygon
			(pts
				(xy 209.116 169.62) (xy 209.114282 169.607584) (xy 209.115106 169.576206) (xy 209.129162 169.56459)
				(xy 209.16 169.56) (xy 209.025 168.684) (xy 208.89 169.56) (xy 208.920565 169.564481) (xy 208.934698 169.575851)
				(xy 208.935718 169.607584) (xy 208.934 169.62)
			)
		)
	)
	(zone
		(net 401)
		(net_name "/Com Express 7 MGMT/FAM_TACH")
		(layer "F.Cu")
		(name "$teardrop_padvia$")
		(hatch none 0.1)
		(priority 30340)
		(attr
			(teardrop
				(type padvia)
			)
		)
		(connect_pads yes
			(clearance 0)
		)
		(min_thickness 0.0254)
		(filled_areas_thickness no)
		(fill yes
			(thermal_gap 0.5)
			(thermal_bridge_width 0.5)
			(island_removal_mode 1)
			(island_area_min 10)
		)
		(polygon
			(pts
				(xy 237.936707 79.0095) (xy 237.902844 79.003719) (xy 237.868222 78.983254) (xy 237.8464 78.956188)
				(xy 237.830707 78.916848) (xy 237.827418 78.901289) (xy 237.120707 79.072) (xy 237.827418 79.242711)
				(xy 237.839008 79.20249) (xy 237.856592 79.173016) (xy 237.904175 79.139827) (xy 237.936707 79.1345)
			)
		)
	)
	(zone
		(net 2)
		(net_name "+3V3")
		(layer "F.Cu")
		(name "$teardrop_padvia$")
		(hatch none 0.1)
		(priority 30928)
		(attr
			(teardrop
				(type padvia)
			)
		)
		(connect_pads yes
			(clearance 0)
		)
		(min_thickness 0.0254)
		(filled_areas_thickness no)
		(fill yes
			(thermal_gap 0.5)
			(thermal_bridge_width 0.5)
			(island_removal_mode 1)
			(island_area_min 10)
		)
		(polygon
			(pts
				(xy 298.638 84.4275) (xy 298.575134 84.407531) (xy 298.543156 84.381079) (xy 298.514642 84.343668)
				(xy 298.492118 84.296473) (xy 298.476907 84.238833) (xy 298.476798 84.238202) (xy 298.199 84.49)
				(xy 298.476798 84.741798) (xy 298.491095 84.686365) (xy 298.512175 84.64048) (xy 298.53954 84.602799)
				(xy 298.570448 84.575566) (xy 298.603735 84.558528) (xy 298.636566 84.552511) (xy 298.638 84.5525)
			)
		)
	)
	(zone
		(net 939)
		(net_name "/2xSFP+/SFP0_LEDY")
		(layer "F.Cu")
		(name "$teardrop_padvia$")
		(hatch none 0.1)
		(priority 31219)
		(attr
			(teardrop
				(type padvia)
			)
		)
		(connect_pads yes
			(clearance 0)
		)
		(min_thickness 0.0254)
		(filled_areas_thickness no)
		(fill yes
			(thermal_gap 0.5)
			(thermal_bridge_width 0.5)
			(island_removal_mode 1)
			(island_area_min 10)
		)
		(polygon
			(pts
				(xy 155.722786 164.971173) (xy 155.720307 164.994266) (xy 155.708058 165.014779) (xy 155.650664 165.051182)
				(xy 155.527202 165.083202) (xy 155.779707 165.360707) (xy 156.030798 165.083202) (xy 155.93714 165.049055)
				(xy 155.859171 164.9834) (xy 155.831013 164.942082) (xy 155.814571 164.90119) (xy 155.811173 164.882786)
			)
		)
	)
	(zone
		(net 365)
		(net_name "/Com Express 7 MGMT/PWR_OK")
		(layer "F.Cu")
		(name "$teardrop_padvia$")
		(hatch none 0.1)
		(priority 31531)
		(attr
			(teardrop
				(type padvia)
			)
		)
		(connect_pads yes
			(clearance 0)
		)
		(min_thickness 0.0254)
		(filled_areas_thickness no)
		(fill yes
			(thermal_gap 0.5)
			(thermal_bridge_width 0.5)
			(island_removal_mode 1)
			(island_area_min 10)
		)
		(polygon
			(pts
				(xy 301.6975 128.754) (xy 301.692444 128.781311) (xy 301.677051 128.80812) (xy 301.651166 128.83194)
				(xy 301.614401 128.850612) (xy 301.529883 128.864) (xy 301.839 129.14) (xy 302.035143 128.864) (xy 301.966211 128.859245)
				(xy 301.910199 128.84596) (xy 301.869307 128.826738) (xy 301.840927 128.802388) (xy 301.8225 128.754)
			)
		)
	)
	(zone
		(net 400)
		(net_name "/Com Express 7 MGMT/FAN_PWM")
		(layer "F.Cu")
		(name "$teardrop_padvia$")
		(hatch none 0.1)
		(priority 30692)
		(attr
			(teardrop
				(type padvia)
			)
		)
		(connect_pads yes
			(clearance 0)
		)
		(min_thickness 0.0254)
		(filled_areas_thickness no)
		(fill yes
			(thermal_gap 0.5)
			(thermal_bridge_width 0.5)
			(island_removal_mode 1)
			(island_area_min 10)
		)
		(polygon
			(pts
				(xy 225.9625 162.2) (xy 225.951563 162.238823) (xy 225.929805 162.253933) (xy 225.89 162.26) (xy 226.025 163.136)
				(xy 226.16 162.26) (xy 226.124719 162.255483) (xy 226.103203 162.243862) (xy 226.088005 162.211039)
				(xy 226.0875 162.2)
			)
		)
	)
	(zone
		(net 2)
		(net_name "+3V3")
		(layer "F.Cu")
		(name "$teardrop_padvia$")
		(hatch none 0.1)
		(priority 30756)
		(attr
			(teardrop
				(type padvia)
			)
		)
		(connect_pads yes
			(clearance 0)
		)
		(min_thickness 0.0254)
		(filled_areas_thickness no)
		(fill yes
			(thermal_gap 0.5)
			(thermal_bridge_width 0.5)
			(island_removal_mode 1)
			(island_area_min 10)
		)
		(polygon
			(pts
				(xy 146.679823 89.4585) (xy 146.8374 89.465432) (xy 146.950934 89.493956) (xy 146.992722 89.511)
				(xy 147.0815 89.3085) (xy 146.992722 89.106) (xy 146.896677 89.140383) (xy 146.794796 89.155601)
				(xy 146.679823 89.1585)
			)
		)
	)
	(zone
		(net 2)
		(net_name "+3V3")
		(layer "F.Cu")
		(name "$teardrop_padvia$")
		(hatch none 0.1)
		(priority 30404)
		(attr
			(teardrop
				(type padvia)
			)
		)
		(connect_pads yes
			(clearance 0)
		)
		(min_thickness 0.0254)
		(filled_areas_thickness no)
		(fill yes
			(thermal_gap 0.5)
			(thermal_bridge_width 0.5)
			(island_removal_mode 1)
			(island_area_min 10)
		)
		(polygon
			(pts
				(xy 189.912073 136.86151) (xy 189.958069 136.878652) (xy 189.995097 136.889067) (xy 190.024114 136.905959)
				(xy 190.033032 136.934815) (xy 190.009761 136.981119) (xy 190.381592 136.977476) (xy 190.385235 136.605645)
				(xy 190.351356 136.625637) (xy 190.326485 136.628719) (xy 190.300096 136.606564) (xy 190.282768 136.553953)
				(xy 190.265626 136.507957)
			)
		)
	)
	(zone
		(net 270)
		(net_name "/M.2 key M #2/~{PERST_D}")
		(layer "F.Cu")
		(name "$teardrop_padvia$")
		(hatch none 0.1)
		(priority 30953)
		(attr
			(teardrop
				(type padvia)
			)
		)
		(connect_pads yes
			(clearance 0)
		)
		(min_thickness 0.0254)
		(filled_areas_thickness no)
		(fill yes
			(thermal_gap 0.5)
			(thermal_bridge_width 0.5)
			(island_removal_mode 1)
			(island_area_min 10)
		)
		(polygon
			(pts
				(xy 297.762 83.5925) (xy 297.824866 83.612469) (xy 297.856844 83.638921) (xy 297.885358 83.676332)
				(xy 297.907882 83.723527) (xy 297.923093 83.781167) (xy 297.923202 83.781798) (xy 298.201 83.53)
				(xy 297.923202 83.278202) (xy 297.908905 83.333635) (xy 297.887825 83.37952) (xy 297.86046 83.417201)
				(xy 297.829552 83.444434) (xy 297.796265 83.461472) (xy 297.763434 83.467489) (xy 297.762 83.4675)
			)
		)
	)
	(zone
		(net 195)
		(net_name "/OCuLink/PCIe_{x4}.RX2-")
		(layer "F.Cu")
		(name "$teardrop_padvia$")
		(hatch none 0.1)
		(priority 32059)
		(attr
			(teardrop
				(type padvia)
			)
		)
		(connect_pads yes
			(clearance 0)
		)
		(min_thickness 0.0254)
		(filled_areas_thickness no)
		(fill yes
			(thermal_gap 0.5)
			(thermal_bridge_width 0.5)
			(island_removal_mode 1)
			(island_area_min 10)
		)
		(polygon
			(pts
				(xy 108.201 152.91) (xy 108.193802 152.889352) (xy 108.184208 152.857016) (xy 108.191035 152.842993)
				(xy 108.2125 152.833004) (xy 108.1 152.584) (xy 107.9875 152.833004) (xy 108.008676 152.842729)
				(xy 108.015731 152.856357) (xy 108.006198 152.889352) (xy 107.999 152.91)
			)
		)
	)
	(zone
		(net 1)
		(net_name "GND")
		(layer "F.Cu")
		(name "$teardrop_padvia$")
		(hatch none 0.1)
		(priority 30807)
		(attr
			(teardrop
				(type padvia)
			)
		)
		(connect_pads yes
			(clearance 0)
		)
		(min_thickness 0.0254)
		(filled_areas_thickness no)
		(fill yes
			(thermal_gap 0.5)
			(thermal_bridge_width 0.5)
			(island_removal_mode 1)
			(island_area_min 10)
		)
		(polygon
			(pts
				(xy 121.302745 73.499387) (xy 121.378165 73.431067) (xy 121.442029 73.388621) (xy 121.564395 73.342185)
				(xy 121.500707 73.129293) (xy 121.300513 73.034946) (xy 121.263156 73.101625) (xy 121.219874 73.156904)
				(xy 121.140645 73.237744) (xy 121.090613 73.287255)
			)
		)
	)
	(zone
		(net 1)
		(net_name "GND")
		(layer "F.Cu")
		(name "$teardrop_padvia$")
		(hatch none 0.1)
		(priority 31799)
		(attr
			(teardrop
				(type padvia)
			)
		)
		(connect_pads yes
			(clearance 0)
		)
		(min_thickness 0.0254)
		(filled_areas_thickness no)
		(fill yes
			(thermal_gap 0.5)
			(thermal_bridge_width 0.5)
			(island_removal_mode 1)
			(island_area_min 10)
		)
		(polygon
			(pts
				(xy 120.800677 147.2985) (xy 120.731236 147.293682) (xy 120.679913 147.27996) (xy 120.604371 147.233246)
				(xy 120.592231 147.223701) (xy 120.525003 147.173919) (xy 120.399 147.361) (xy 120.525003 147.548081)
				(xy 120.592229 147.498299) (xy 120.675396 147.443894) (xy 120.728251 147.42881) (xy 120.800677 147.4235)
			)
		)
	)
	(zone
		(net 723)
		(net_name "/2xSFP+/KR to SFI #1/TDO")
		(layer "F.Cu")
		(name "$teardrop_padvia$")
		(hatch none 0.1)
		(priority 31706)
		(attr
			(teardrop
				(type padvia)
			)
		)
		(connect_pads yes
			(clearance 0)
		)
		(min_thickness 0.0254)
		(filled_areas_thickness no)
		(fill yes
			(thermal_gap 0.5)
			(thermal_bridge_width 0.5)
			(island_removal_mode 1)
			(island_area_min 10)
		)
		(polygon
			(pts
				(xy 151.7375 129.739323) (xy 151.732682 129.808763) (xy 151.71896 129.860087) (xy 151.672245 129.935628)
				(xy 151.662702 129.947768) (xy 151.612919 130.014997) (xy 151.8 130.141) (xy 151.987081 130.014997)
				(xy 151.937299 129.947769) (xy 151.882894 129.864603) (xy 151.86781 129.811748) (xy 151.8625 129.739323)
			)
		)
	)
	(zone
		(net 50)
		(net_name "Net-(C12-Pad2)")
		(layer "F.Cu")
		(name "$teardrop_padvia$")
		(hatch none 0.1)
		(priority 30878)
		(attr
			(teardrop
				(type padvia)
			)
		)
		(connect_pads yes
			(clearance 0)
		)
		(min_thickness 0.0254)
		(filled_areas_thickness no)
		(fill yes
			(thermal_gap 0.5)
			(thermal_bridge_width 0.5)
			(island_removal_mode 1)
			(island_area_min 10)
		)
		(polygon
			(pts
				(xy 137.493 109.12) (xy 137.452263 109.114228) (xy 137.410348 109.093824) (xy 137.382047 109.066649)
				(xy 137.358618 109.027103) (xy 137.339347 108.9545) (xy 137.079 109.22) (xy 137.339347 109.4855)
				(xy 137.351214 109.432358) (xy 137.369662 109.391319) (xy 137.420336 109.339618) (xy 137.483905 109.320282)
				(xy 137.493 109.32)
			)
		)
	)
	(zone
		(net 537)
		(net_name "/Backplane/PCIe_{x2}.RX0-")
		(layer "F.Cu")
		(name "$teardrop_padvia$")
		(hatch none 0.1)
		(priority 32092)
		(attr
			(teardrop
				(type padvia)
			)
		)
		(connect_pads yes
			(clearance 0)
		)
		(min_thickness 0.0254)
		(filled_areas_thickness no)
		(fill yes
			(thermal_gap 0.5)
			(thermal_bridge_width 0.5)
			(island_removal_mode 1)
			(island_area_min 10)
		)
		(polygon
			(pts
				(xy 314.688 160.309) (xy 314.667352 160.316199) (xy 314.635017 160.325792) (xy 314.620994 160.318965)
				(xy 314.611005 160.2975) (xy 314.362 160.41) (xy 314.611005 160.5225) (xy 314.62073 160.501324)
				(xy 314.634358 160.494269) (xy 314.667352 160.503801) (xy 314.688 160.511)
			)
		)
	)
	(zone
		(net 548)
		(net_name "/2xUSB3.0+RJ45/P2_ISET")
		(layer "F.Cu")
		(name "$teardrop_padvia$")
		(hatch none 0.1)
		(priority 31038)
		(attr
			(teardrop
				(type padvia)
			)
		)
		(connect_pads yes
			(clearance 0)
		)
		(min_thickness 0.0254)
		(filled_areas_thickness no)
		(fill yes
			(thermal_gap 0.5)
			(thermal_bridge_width 0.5)
			(island_removal_mode 1)
			(island_area_min 10)
		)
		(polygon
			(pts
				(xy 119.762 91.8265) (xy 119.82982 91.847019) (xy 119.863595 91.873459) (xy 119.893121 91.911216)
				(xy 119.923202 91.991798) (xy 120.201 91.74) (xy 119.922446 91.489332) (xy 119.907877 91.552522)
				(xy 119.886374 91.605032) (xy 119.859265 91.646839) (xy 119.828341 91.677085) (xy 119.796538 91.694934)
				(xy 119.764161 91.701474) (xy 119.762 91.7015)
			)
		)
	)
	(zone
		(net 295)
		(net_name "/2xUSB3.0+RJ45/GbE.MDI0+")
		(layer "F.Cu")
		(name "$teardrop_padvia$")
		(hatch none 0.1)
		(priority 30312)
		(attr
			(teardrop
				(type padvia)
			)
		)
		(connect_pads yes
			(clearance 0)
		)
		(min_thickness 0.0254)
		(filled_areas_thickness no)
		(fill yes
			(thermal_gap 0.5)
			(thermal_bridge_width 0.5)
			(island_removal_mode 1)
			(island_area_min 10)
		)
		(polygon
			(pts
				(xy 181.875 167.75) (xy 181.882191 167.932252) (xy 181.891641 168.183885) (xy 181.888369 168.333893)
				(xy 181.875 168.504204) (xy 182.025 168.686) (xy 182.090241 167.81) (xy 182.055265 167.805495) (xy 182.035678 167.793958)
				(xy 182.024981 167.762811) (xy 182.024965 167.754084) (xy 182.025 167.75)
			)
		)
	)
	(zone
		(net 737)
		(net_name "Net-(U43B-LOSB)")
		(layer "F.Cu")
		(name "$teardrop_padvia$")
		(hatch none 0.1)
		(priority 31689)
		(attr
			(teardrop
				(type padvia)
			)
		)
		(connect_pads yes
			(clearance 0)
		)
		(min_thickness 0.0254)
		(filled_areas_thickness no)
		(fill yes
			(thermal_gap 0.5)
			(thermal_bridge_width 0.5)
			(island_removal_mode 1)
			(island_area_min 10)
		)
		(polygon
			(pts
				(xy 146.5375 129.739323) (xy 146.532682 129.808763) (xy 146.51896 129.860087) (xy 146.472245 129.935628)
				(xy 146.462702 129.947768) (xy 146.412919 130.014997) (xy 146.6 130.141) (xy 146.787081 130.014997)
				(xy 146.737299 129.947769) (xy 146.682894 129.864603) (xy 146.66781 129.811748) (xy 146.6625 129.739323)
			)
		)
	)
	(zone
		(net 1)
		(net_name "GND")
		(layer "F.Cu")
		(name "$teardrop_padvia$")
		(hatch none 0.1)
		(priority 32151)
		(attr
			(teardrop
				(type padvia)
			)
		)
		(connect_pads yes
			(clearance 0)
		)
		(min_thickness 0.0254)
		(filled_areas_thickness no)
		(fill yes
			(thermal_gap 0.5)
			(thermal_bridge_width 0.5)
			(island_removal_mode 1)
			(island_area_min 10)
		)
		(polygon
			(pts
				(xy 124.4225 133.339323) (xy 124.417764 133.311184) (xy 124.404615 133.290239) (xy 124.358158 133.267664)
				(xy 124.281044 133.272043) (xy 124.234681 133.288623) (xy 124.194927 133.313459) (xy 124.169691 133.340944)
				(xy 124.157903 133.372268) (xy 124.1575 133.379) (xy 124.36 133.379) (xy 124.1575 133.379) (xy 124.162082 133.390036)
				(xy 124.174541 133.388577) (xy 124.220632 133.358082) (xy 124.272991 133.323768) (xy 124.290711 133.322013)
				(xy 124.2975 133.339323)
			)
		)
	)
	(zone
		(net 62)
		(net_name "+12V_AON")
		(layer "F.Cu")
		(hatch edge 0.5)
		(priority 18)
		(connect_pads yes
			(clearance 0.15)
		)
		(min_thickness 0.25)
		(filled_areas_thickness no)
		(fill yes
			(thermal_gap 0.2)
			(thermal_bridge_width 0.5)
			(smoothing fillet)
			(radius 0.2)
		)
		(polygon
			(pts
				(xy 312.7005 94.6865) (xy 313.4505 94.6865) (xy 313.7505 94.9865) (xy 318.75 94.9865) (xy 318.75 92.8365)
				(xy 314.0005 92.8365) (xy 312.7005 94.1365)
			)
		)
	)
	(zone
		(net 526)
		(net_name "/Backplane/~{PRSNT}")
		(layer "F.Cu")
		(name "$teardrop_padvia$")
		(hatch none 0.1)
		(priority 32109)
		(attr
			(teardrop
				(type padvia)
			)
		)
		(connect_pads yes
			(clearance 0)
		)
		(min_thickness 0.0254)
		(filled_areas_thickness no)
		(fill yes
			(thermal_gap 0.5)
			(thermal_bridge_width 0.5)
			(island_removal_mode 1)
			(island_area_min 10)
		)
		(polygon
			(pts
				(xy 314.038 164.5205) (xy 314.044322 164.520404) (xy 314.083825 164.525989) (xy 314.102047 164.540922)
				(xy 314.114995 164.5705) (xy 314.364 164.458) (xy 314.114995 164.3455) (xy 314.103879 164.372493)
				(xy 314.088352 164.387595) (xy 314.044322 164.395596) (xy 314.038 164.3955)
			)
		)
	)
	(zone
		(net 397)
		(net_name "/Com Express 7 MGMT/SPI.~{CS}")
		(layer "F.Cu")
		(name "$teardrop_padvia$")
		(hatch none 0.1)
		(priority 30667)
		(attr
			(teardrop
				(type padvia)
			)
		)
		(connect_pads yes
			(clearance 0)
		)
		(min_thickness 0.0254)
		(filled_areas_thickness no)
		(fill yes
			(thermal_gap 0.5)
			(thermal_bridge_width 0.5)
			(island_removal_mode 1)
			(island_area_min 10)
		)
		(polygon
			(pts
				(xy 224.0875 164.07) (xy 224.098438 164.031177) (xy 224.120195 164.016067) (xy 224.16 164.01) (xy 224.025 163.134)
				(xy 223.89 164.01) (xy 223.925281 164.014517) (xy 223.946797 164.026138) (xy 223.961995 164.058961)
				(xy 223.9625 164.07)
			)
		)
	)
	(zone
		(net 2)
		(net_name "+3V3")
		(layer "F.Cu")
		(name "$teardrop_padvia$")
		(hatch none 0.1)
		(priority 30344)
		(attr
			(teardrop
				(type padvia)
			)
		)
		(connect_pads yes
			(clearance 0)
		)
		(min_thickness 0.0254)
		(filled_areas_thickness no)
		(fill yes
			(thermal_gap 0.5)
			(thermal_bridge_width 0.5)
			(island_removal_mode 1)
			(island_area_min 10)
		)
		(polygon
			(pts
				(xy 121.4005 72.274) (xy 121.406281 72.240137) (xy 121.426745 72.205516) (xy 121.453811 72.183694)
				(xy 121.49315 72.168) (xy 121.508711 72.164711) (xy 121.338 71.458) (xy 121.167289 72.164711) (xy 121.20751 72.1763)
				(xy 121.236984 72.193885) (xy 121.270173 72.241467) (xy 121.2755 72.274)
			)
		)
	)
	(zone
		(net 188)
		(net_name "/OCuLink/PCIe_{x4}.RX1+")
		(layer "F.Cu")
		(name "$teardrop_padvia$")
		(hatch none 0.1)
		(priority 32051)
		(attr
			(teardrop
				(type padvia)
			)
		)
		(connect_pads yes
			(clearance 0)
		)
		(min_thickness 0.0254)
		(filled_areas_thickness no)
		(fill yes
			(thermal_gap 0.5)
			(thermal_bridge_width 0.5)
			(island_removal_mode 1)
			(island_area_min 10)
		)
		(polygon
			(pts
				(xy 98.101 151.025) (xy 98.093802 151.004352) (xy 98.084208 150.972016) (xy 98.091035 150.957993)
				(xy 98.1125 150.948004) (xy 98 150.699) (xy 97.8875 150.948004) (xy 97.908676 150.957729) (xy 97.915731 150.971357)
				(xy 97.906198 151.004352) (xy 97.899 151.025)
			)
		)
	)
	(zone
		(net 401)
		(net_name "/Com Express 7 MGMT/FAM_TACH")
		(layer "F.Cu")
		(name "$teardrop_padvia$")
		(hatch none 0.1)
		(priority 30691)
		(attr
			(teardrop
				(type padvia)
			)
		)
		(connect_pads yes
			(clearance 0)
		)
		(min_thickness 0.0254)
		(filled_areas_thickness no)
		(fill yes
			(thermal_gap 0.5)
			(thermal_bridge_width 0.5)
			(island_removal_mode 1)
			(island_area_min 10)
		)
		(polygon
			(pts
				(xy 226.4625 162.2) (xy 226.451563 162.238823) (xy 226.429805 162.253933) (xy 226.39 162.26) (xy 226.525 163.136)
				(xy 226.66 162.26) (xy 226.624719 162.255483) (xy 226.603203 162.243862) (xy 226.588005 162.211039)
				(xy 226.5875 162.2)
			)
		)
	)
	(zone
		(net 1)
		(net_name "GND")
		(layer "F.Cu")
		(name "$teardrop_padvia$")
		(hatch none 0.1)
		(priority 30559)
		(attr
			(teardrop
				(type padvia)
			)
		)
		(connect_pads yes
			(clearance 0)
		)
		(min_thickness 0.0254)
		(filled_areas_thickness no)
		(fill yes
			(thermal_gap 0.5)
			(thermal_bridge_width 0.5)
			(island_removal_mode 1)
			(island_area_min 10)
		)
		(polygon
			(pts
				(xy 189.625 157.62) (xy 189.621667 157.605514) (xy 189.61881 157.57539) (xy 189.630964 157.564349)
				(xy 189.66 157.56) (xy 189.525 156.684) (xy 189.39 157.56) (xy 189.419334 157.564475) (xy 189.431358 157.575801)
				(xy 189.428333 157.605514) (xy 189.425 157.62)
			)
		)
	)
	(zone
		(net 1)
		(net_name "GND")
		(layer "F.Cu")
		(name "$teardrop_padvia$")
		(hatch none 0.1)
		(priority 30708)
		(attr
			(teardrop
				(type padvia)
			)
		)
		(connect_pads yes
			(clearance 0)
		)
		(min_thickness 0.0254)
		(filled_areas_thickness no)
		(fill yes
			(thermal_gap 0.5)
			(thermal_bridge_width 0.5)
			(island_removal_mode 1)
			(island_area_min 10)
		)
		(polygon
			(pts
				(xy 213.65 152.07) (xy 213.64532 152.054279) (xy 213.639557 152.024928) (xy 213.649336 152.014214)
				(xy 213.675 152.01) (xy 213.525 151.134) (xy 213.413349 152.01) (xy 213.443217 152.014476) (xy 213.455664 152.025809)
				(xy 213.453135 152.055714) (xy 213.45 152.07)
			)
		)
	)
	(zone
		(net 560)
		(net_name "Net-(U5-~{RESET})")
		(layer "F.Cu")
		(name "$teardrop_padvia$")
		(hatch none 0.1)
		(priority 32015)
		(attr
			(teardrop
				(type padvia)
			)
		)
		(connect_pads yes
			(clearance 0)
		)
		(min_thickness 0.0254)
		(filled_areas_thickness no)
		(fill yes
			(thermal_gap 0.5)
			(thermal_bridge_width 0.5)
			(island_removal_mode 1)
			(island_area_min 10)
		)
		(polygon
			(pts
				(xy 157.9875 158.2095) (xy 157.987596 158.215822) (xy 157.982011 158.255325) (xy 157.967078 158.273547)
				(xy 157.9375 158.286495) (xy 158.05 158.673) (xy 158.1625 158.286495) (xy 158.135507 158.275379)
				(xy 158.120405 158.259852) (xy 158.112404 158.215822) (xy 158.1125 158.2095)
			)
		)
	)
	(zone
		(net 1)
		(net_name "GND")
		(layer "F.Cu")
		(name "$teardrop_padvia$")
		(hatch none 0.1)
		(priority 30545)
		(attr
			(teardrop
				(type padvia)
			)
		)
		(connect_pads yes
			(clearance 0)
		)
		(min_thickness 0.0254)
		(filled_areas_thickness no)
		(fill yes
			(thermal_gap 0.5)
			(thermal_bridge_width 0.5)
			(island_removal_mode 1)
			(island_area_min 10)
		)
		(polygon
			(pts
				(xy 185.925 167.75) (xy 185.928333 167.764486) (xy 185.93119 167.79461) (xy 185.919036 167.805651)
				(xy 185.89 167.81) (xy 186.025 168.686) (xy 186.16 167.81) (xy 186.130666 167.805525) (xy 186.118642 167.794199)
				(xy 186.121667 167.764486) (xy 186.125 167.75)
			)
		)
	)
	(zone
		(net 526)
		(net_name "/Backplane/~{PRSNT}")
		(layer "F.Cu")
		(name "$teardrop_padvia$")
		(hatch none 0.1)
		(priority 31791)
		(attr
			(teardrop
				(type padvia)
			)
		)
		(connect_pads yes
			(clearance 0)
		)
		(min_thickness 0.0254)
		(filled_areas_thickness no)
		(fill yes
			(thermal_gap 0.5)
			(thermal_bridge_width 0.5)
			(island_removal_mode 1)
			(island_area_min 10)
		)
		(polygon
			(pts
				(xy 200.3625 122.150677) (xy 200.367318 122.081236) (xy 200.38104 122.029912) (xy 200.427755 121.95437)
				(xy 200.437299 121.942229) (xy 200.487081 121.875003) (xy 200.3 121.749) (xy 200.112919 121.875003)
				(xy 200.162701 121.942231) (xy 200.217106 122.025397) (xy 200.23219 122.078251) (xy 200.2375 122.150677)
			)
		)
	)
	(zone
		(net 78)
		(net_name "+1V8")
		(layer "F.Cu")
		(name "$teardrop_padvia$")
		(hatch none 0.1)
		(priority 31872)
		(attr
			(teardrop
				(type padvia)
			)
		)
		(connect_pads yes
			(clearance 0)
		)
		(min_thickness 0.0254)
		(filled_areas_thickness no)
		(fill yes
			(thermal_gap 0.5)
			(thermal_bridge_width 0.5)
			(island_removal_mode 1)
			(island_area_min 10)
		)
		(polygon
			(pts
				(xy 142.137873 149.105515) (xy 142.190382 149.059819) (xy 142.236376 149.033231) (xy 142.322824 149.012847)
				(xy 142.33816 149.011011) (xy 142.420895 148.998677) (xy 142.377707 148.777293) (xy 142.156323 148.734105)
				(xy 142.143988 148.816841) (xy 142.123651 148.914119) (xy 142.096943 148.962159) (xy 142.049485 149.017127)
			)
		)
	)
	(zone
		(net 285)
		(net_name "/2xUSB3.0+RJ45/GbE.MDI3-")
		(layer "F.Cu")
		(name "$teardrop_padvia$")
		(hatch none 0.1)
		(priority 30303)
		(attr
			(teardrop
				(type padvia)
			)
		)
		(connect_pads yes
			(clearance 0)
		)
		(min_thickness 0.0254)
		(filled_areas_thickness no)
		(fill yes
			(thermal_gap 0.5)
			(thermal_bridge_width 0.5)
			(island_removal_mode 1)
			(island_area_min 10)
		)
		(polygon
			(pts
				(xy 176.525 167.75) (xy 176.525035 167.754084) (xy 176.517242 167.790449) (xy 176.497831 167.804416)
				(xy 176.459759 167.81) (xy 176.525 168.686) (xy 176.675 168.504204) (xy 176.658334 168.198008) (xy 176.667809 167.932252)
				(xy 176.675 167.75)
			)
		)
	)
	(zone
		(net 580)
		(net_name "Net-(U18-FB)")
		(layer "F.Cu")
		(name "$teardrop_padvia$")
		(hatch none 0.1)
		(priority 30986)
		(attr
			(teardrop
				(type padvia)
			)
		)
		(connect_pads yes
			(clearance 0)
		)
		(min_thickness 0.0254)
		(filled_areas_thickness no)
		(fill yes
			(thermal_gap 0.5)
			(thermal_bridge_width 0.5)
			(island_removal_mode 1)
			(island_area_min 10)
		)
		(polygon
			(pts
				(xy 309.112499 121.172) (xy 309.09253 121.234866) (xy 309.066078 121.266844) (xy 309.028667 121.295358)
				(xy 308.981472 121.317882) (xy 308.923832 121.333093) (xy 308.923201 121.333202) (xy 309.174999 121.611)
				(xy 309.426797 121.333202) (xy 309.371364 121.318905) (xy 309.325479 121.297825) (xy 309.287798 121.27046)
				(xy 309.260565 121.239552) (xy 309.243527 121.206265) (xy 309.23751 121.173434) (xy 309.237499 121.172)
			)
		)
	)
	(zone
		(net 1)
		(net_name "GND")
		(layer "F.Cu")
		(name "$teardrop_padvia$")
		(hatch none 0.1)
		(priority 30769)
		(attr
			(teardrop
				(type padvia)
			)
		)
		(connect_pads yes
			(clearance 0)
		)
		(min_thickness 0.0254)
		(filled_areas_thickness no)
		(fill yes
			(thermal_gap 0.5)
			(thermal_bridge_width 0.5)
			(island_removal_mode 1)
			(island_area_min 10)
		)
		(polygon
			(pts
				(xy 262.100708 76.160677) (xy 262.10764 76.0031) (xy 262.136164 75.889565) (xy 262.153208 75.847778)
				(xy 261.950708 75.759) (xy 261.748208 75.847778) (xy 261.782591 75.943822) (xy 261.797809 76.045702)
				(xy 261.800708 76.160677)
			)
		)
	)
	(zone
		(net 529)
		(net_name "/M.2 key M #1/~{CLKREQ}")
		(layer "F.Cu")
		(name "$teardrop_padvia$")
		(hatch none 0.1)
		(priority 31086)
		(attr
			(teardrop
				(type padvia)
			)
		)
		(connect_pads yes
			(clearance 0)
		)
		(min_thickness 0.0254)
		(filled_areas_thickness no)
		(fill yes
			(thermal_gap 0.5)
			(thermal_bridge_width 0.5)
			(island_removal_mode 1)
			(island_area_min 10)
		)
		(polygon
			(pts
				(xy 179.4125 104.763) (xy 179.432273 104.703588) (xy 179.495547 104.647503) (xy 179.544172 104.625801)
				(xy 179.603532 104.611127) (xy 179.6155 104.609347) (xy 179.35 104.349) (xy 179.0845 104.609347)
				(xy 179.144639 104.622197) (xy 179.194523 104.642131) (xy 179.234642 104.668056) (xy 179.263655 104.697876)
				(xy 179.281146 104.729294) (xy 179.287479 104.761105) (xy 179.2875 104.763)
			)
		)
	)
	(zone
		(net 89)
		(net_name "/Com Express 7 Interfaces/PCIe_{B2Ax4}.RX3-")
		(layer "F.Cu")
		(name "$teardrop_padvia$")
		(hatch none 0.1)
		(priority 30361)
		(attr
			(teardrop
				(type padvia)
			)
		)
		(connect_pads yes
			(clearance 0)
		)
		(min_thickness 0.0254)
		(filled_areas_thickness no)
		(fill yes
			(thermal_gap 0.5)
			(thermal_bridge_width 0.5)
			(island_removal_mode 1)
			(island_area_min 10)
		)
		(polygon
			(pts
				(xy 287.743 74.87) (xy 287.73998 74.855836) (xy 287.737965 74.825494) (xy 287.750965 74.814378)
				(xy 287.781322 74.81) (xy 287.698 74.034) (xy 287.548 74.253414) (xy 287.567141 74.467736) (xy 287.552216 74.713526)
				(xy 287.541 74.87)
			)
		)
	)
	(zone
		(net 621)
		(net_name "/PCIe misc/DIF5+")
		(layer "F.Cu")
		(name "$teardrop_padvia$")
		(hatch none 0.1)
		(priority 31511)
		(attr
			(teardrop
				(type padvia)
			)
		)
		(connect_pads yes
			(clearance 0)
		)
		(min_thickness 0.0254)
		(filled_areas_thickness no)
		(fill yes
			(thermal_gap 0.5)
			(thermal_bridge_width 0.5)
			(island_removal_mode 1)
			(island_area_min 10)
		)
		(polygon
			(pts
				(xy 220.030272 127.99632) (xy 220.068187 127.991074) (xy 220.097644 127.996871) (xy 220.137931 128.031505)
				(xy 220.164592 128.077275) (xy 220.191573 128.124335) (xy 220.228521 128.166039) (xy 220.369031 127.993242)
				(xy 220.324171 127.772823) (xy 220.201554 127.782279) (xy 220.177186 127.78125) (xy 220.092609 127.780968)
				(xy 219.977989 127.801205)
			)
		)
	)
	(zone
		(net 314)
		(net_name "/2xUSB3.0+RJ45/FLG_1")
		(layer "F.Cu")
		(name "$teardrop_padvia$")
		(hatch none 0.1)
		(priority 31322)
		(attr
			(teardrop
				(type padvia)
			)
		)
		(connect_pads yes
			(clearance 0)
		)
		(min_thickness 0.0254)
		(filled_areas_thickness no)
		(fill yes
			(thermal_gap 0.5)
			(thermal_bridge_width 0.5)
			(island_removal_mode 1)
			(island_area_min 10)
		)
		(polygon
			(pts
				(xy 197.625 167.787793) (xy 197.629731 167.732196) (xy 197.64285 167.689645) (xy 197.688022 167.627772)
				(xy 197.711704 167.605388) (xy 197.780694 167.531389) (xy 197.6 167.399) (xy 197.383268 167.453421)
				(xy 197.38519 167.461215) (xy 197.416806 167.610064) (xy 197.425 167.787793)
			)
		)
	)
	(zone
		(net 2)
		(net_name "+3V3")
		(layer "F.Cu")
		(name "$teardrop_padvia$")
		(hatch none 0.1)
		(priority 30933)
		(attr
			(teardrop
				(type padvia)
			)
		)
		(connect_pads yes
			(clearance 0)
		)
		(min_thickness 0.0254)
		(filled_areas_thickness no)
		(fill yes
			(thermal_gap 0.5)
			(thermal_bridge_width 0.5)
			(island_removal_mode 1)
			(island_area_min 10)
		)
		(polygon
			(pts
				(xy 220.2725 124.338) (xy 220.292469 124.275134) (xy 220.318921 124.243156) (xy 220.356332 124.214642)
				(xy 220.403527 124.192118) (xy 220.461167 124.176907) (xy 220.461798 124.176798) (xy 220.21 123.899)
				(xy 219.958202 124.176798) (xy 220.013635 124.191095) (xy 220.05952 124.212175) (xy 220.097201 124.23954)
				(xy 220.124434 124.270448) (xy 220.141472 124.303735) (xy 220.147489 124.336566) (xy 220.1475 124.338)
			)
		)
	)
	(zone
		(net 2)
		(net_name "+3V3")
		(layer "F.Cu")
		(name "$teardrop_padvia$")
		(hatch none 0.1)
		(priority 30360)
		(attr
			(teardrop
				(type padvia)
			)
		)
		(connect_pads yes
			(clearance 0)
		)
		(min_thickness 0.0254)
		(filled_areas_thickness no)
		(fill yes
			(thermal_gap 0.5)
			(thermal_bridge_width 0.5)
			(island_removal_mode 1)
			(island_area_min 10)
		)
		(polygon
			(pts
				(xy 250.036709 78.4855) (xy 250.070572 78.491281) (xy 250.105193 78.511745) (xy 250.127015 78.53881)
				(xy 250.142709 78.57815) (xy 250.145998 78.593711) (xy 250.852709 78.423) (xy 250.145998 78.252289)
				(xy 250.134409 78.29251) (xy 250.116825 78.321984) (xy 250.069243 78.355173) (xy 250.036709 78.3605)
			)
		)
	)
	(zone
		(net 2)
		(net_name "+3V3")
		(layer "F.Cu")
		(name "$teardrop_padvia$")
		(hatch none 0.1)
		(priority 31551)
		(attr
			(teardrop
				(type padvia)
			)
		)
		(connect_pads yes
			(clearance 0)
		)
		(min_thickness 0.0254)
		(filled_areas_thickness no)
		(fill yes
			(thermal_gap 0.5)
			(thermal_bridge_width 0.5)
			(island_removal_mode 1)
			(island_area_min 10)
		)
		(polygon
			(pts
				(xy 111.349 135.31) (xy 111.346301 135.347413) (xy 111.332408 135.387924) (xy 111.298627 135.423597)
				(xy 111.236265 135.446499) (xy 111.235612 135.446612) (xy 111.449 135.711) (xy 111.662388 135.446612)
				(xy 111.620236 135.434665) (xy 111.590044 135.416774) (xy 111.557156 135.369119) (xy 111.549 135.31)
			)
		)
	)
	(zone
		(net 868)
		(net_name "/Backplane/PCIe_{x2}.TX1+")
		(layer "F.Cu")
		(name "$teardrop_padvia$")
		(hatch none 0.1)
		(priority 31401)
		(attr
			(teardrop
				(type padvia)
			)
		)
		(connect_pads yes
			(clearance 0)
		)
		(min_thickness 0.0254)
		(filled_areas_thickness no)
		(fill yes
			(thermal_gap 0.5)
			(thermal_bridge_width 0.5)
			(island_removal_mode 1)
			(island_area_min 10)
		)
		(polygon
			(pts
				(xy 268.632504 140.6065) (xy 268.794035 140.601105) (xy 268.878445 140.597554) (xy 268.98014 140.602177)
				(xy 269.001 140.3815) (xy 268.851147 140.218268) (xy 268.797007 140.286935) (xy 268.787115 140.303393)
				(xy 268.762615 140.342065) (xy 268.733109 140.374279) (xy 268.691953 140.396327) (xy 268.632504 140.4045)
			)
		)
	)
	(zone
		(net 2)
		(net_name "+3V3")
		(layer "F.Cu")
		(name "$teardrop_padvia$")
		(hatch none 0.1)
		(priority 31515)
		(attr
			(teardrop
				(type padvia)
			)
		)
		(connect_pads yes
			(clearance 0)
		)
		(min_thickness 0.0254)
		(filled_areas_thickness no)
		(fill yes
			(thermal_gap 0.5)
			(thermal_bridge_width 0.5)
			(island_removal_mode 1)
			(island_area_min 10)
		)
		(polygon
			(pts
				(xy 215.382001 131.453095) (xy 215.386519 131.532808) (xy 215.398146 131.593891) (xy 215.420375 131.662275)
				(xy 215.440789 131.723595) (xy 215.456323 131.800787) (xy 215.677 131.773999) (xy 215.798881 131.584625)
				(xy 215.730614 131.558637) (xy 215.694766 131.552148) (xy 215.651635 131.543793) (xy 215.615706 131.529077)
				(xy 215.591116 131.501133) (xy 215.582 131.453096)
			)
		)
	)
	(zone
		(net 228)
		(net_name "/M.2 key M #1/~{PERST_D}")
		(layer "F.Cu")
		(name "$teardrop_padvia$")
		(hatch none 0.1)
		(priority 31516)
		(attr
			(teardrop
				(type padvia)
			)
		)
		(connect_pads yes
			(clearance 0)
		)
		(min_thickness 0.0254)
		(filled_areas_thickness no)
		(fill yes
			(thermal_gap 0.5)
			(thermal_bridge_width 0.5)
			(island_removal_mode 1)
			(island_area_min 10)
		)
		(polygon
			(pts
				(xy 178.392072 104.806315) (xy 178.412382 104.74019) (xy 178.439903 104.701871) (xy 178.47769 104.666666)
				(xy 178.523928 104.637756) (xy 178.578107 104.617263) (xy 178.614427 104.610064) (xy 178.350707 104.349293)
				(xy 178.121054 104.633772) (xy 178.200414 104.642679) (xy 178.258951 104.660632) (xy 178.287431 104.679772)
				(xy 178.301972 104.703831) (xy 178.303685 104.717928)
			)
		)
	)
	(zone
		(net 536)
		(net_name "Net-(Q3-D)")
		(layer "F.Cu")
		(name "$teardrop_padvia$")
		(hatch none 0.1)
		(priority 30195)
		(attr
			(teardrop
				(type padvia)
			)
		)
		(connect_pads yes
			(clearance 0)
		)
		(min_thickness 0.0254)
		(filled_areas_thickness no)
		(fill yes
			(thermal_gap 0.5)
			(thermal_bridge_width 0.5)
			(island_removal_mode 1)
			(island_area_min 10)
		)
		(polygon
			(pts
				(xy 289.2995 97.69) (xy 289.293825 97.728514) (xy 289.274097 97.767619) (xy 289.247219 97.794469)
				(xy 289.208111 97.816281) (xy 289.1295 97.833927) (xy 289.3995 98.311) (xy 289.6695 97.833927) (xy 289.614894 97.824382)
				(xy 289.572658 97.807775) (xy 289.519693 97.760089) (xy 289.499816 97.699186) (xy 289.4995 97.69)
			)
		)
	)
	(zone
		(net 724)
		(net_name "/2xSFP+/KR to SFI #1/TMS")
		(layer "F.Cu")
		(name "$teardrop_padvia$")
		(hatch none 0.1)
		(priority 31708)
		(attr
			(teardrop
				(type padvia)
			)
		)
		(connect_pads yes
			(clearance 0)
		)
		(min_thickness 0.0254)
		(filled_areas_thickness no)
		(fill yes
			(thermal_gap 0.5)
			(thermal_bridge_width 0.5)
			(island_removal_mode 1)
			(island_area_min 10)
		)
		(polygon
			(pts
				(xy 153.6875 130.109323) (xy 153.682682 130.178763) (xy 153.66896 130.230087) (xy 153.622245 130.305628)
				(xy 153.612702 130.317768) (xy 153.562919 130.384997) (xy 153.75 130.511) (xy 153.937081 130.384997)
				(xy 153.887299 130.317769) (xy 153.832894 130.234603) (xy 153.81781 130.181748) (xy 153.8125 130.109323)
			)
		)
	)
	(zone
		(net 82)
		(net_name "Net-(U32-CT)")
		(layer "F.Cu")
		(name "$teardrop_padvia$")
		(hatch none 0.1)
		(priority 30947)
		(attr
			(teardrop
				(type padvia)
			)
		)
		(connect_pads yes
			(clearance 0)
		)
		(min_thickness 0.0254)
		(filled_areas_thickness no)
		(fill yes
			(thermal_gap 0.5)
			(thermal_bridge_width 0.5)
			(island_removal_mode 1)
			(island_area_min 10)
		)
		(polygon
			(pts
				(xy 257.887 126.284248) (xy 257.949866 126.304217) (xy 257.981844 126.330669) (xy 258.010358 126.36808)
				(xy 258.032882 126.415275) (xy 258.048093 126.472915) (xy 258.048202 126.473546) (xy 258.326 126.221748)
				(xy 258.048202 125.96995) (xy 258.033905 126.025383) (xy 258.012825 126.071268) (xy 257.98546 126.108949)
				(xy 257.954552 126.136182) (xy 257.921265 126.15322) (xy 257.888434 126.159237) (xy 257.887 126.159248)
			)
		)
	)
	(zone
		(net 359)
		(net_name "/Com Express 7 MGMT/SMBus.~{INT}")
		(layer "F.Cu")
		(name "$teardrop_padvia$")
		(hatch none 0.1)
		(priority 30703)
		(attr
			(teardrop
				(type padvia)
			)
		)
		(connect_pads yes
			(clearance 0)
		)
		(min_thickness 0.0254)
		(filled_areas_thickness no)
		(fill yes
			(thermal_gap 0.5)
			(thermal_bridge_width 0.5)
			(island_removal_mode 1)
			(island_area_min 10)
		)
		(polygon
			(pts
				(xy 182.9625 162.2) (xy 182.951563 162.238823) (xy 182.929805 162.253933) (xy 182.89 162.26) (xy 183.025 163.136)
				(xy 183.16 162.26) (xy 183.124719 162.255483) (xy 183.103203 162.243862) (xy 183.088005 162.211039)
				(xy 183.0875 162.2)
			)
		)
	)
	(zone
		(net 2)
		(net_name "+3V3")
		(layer "F.Cu")
		(name "$teardrop_padvia$")
		(hatch none 0.1)
		(priority 30306)
		(attr
			(teardrop
				(type padvia)
			)
		)
		(connect_pads yes
			(clearance 0)
		)
		(min_thickness 0.0254)
		(filled_areas_thickness no)
		(fill yes
			(thermal_gap 0.5)
			(thermal_bridge_width 0.5)
			(island_removal_mode 1)
			(island_area_min 10)
		)
		(polygon
			(pts
				(xy 231.703834 78.273) (xy 231.582895 78.293993) (xy 231.441249 78.320393) (xy 231.367123 78.319308)
				(xy 231.293485 78.3) (xy 231.269707 78.595) (xy 231.588353 78.754332) (xy 231.592514 78.684874)
				(xy 231.604964 78.635725) (xy 231.621828 78.605823) (xy 231.642537 78.587191) (xy 231.693454 78.573226)
				(xy 231.703834 78.573)
			)
		)
	)
	(zone
		(net 1)
		(net_name "GND")
		(layer "F.Cu")
		(name "$teardrop_padvia$")
		(hatch none 0.1)
		(priority 31938)
		(attr
			(teardrop
				(type padvia)
			)
		)
		(connect_pads yes
			(clearance 0)
		)
		(min_thickness 0.0254)
		(filled_areas_thickness no)
		(fill yes
			(thermal_gap 0.5)
			(thermal_bridge_width 0.5)
			(island_removal_mode 1)
			(island_area_min 10)
		)
		(polygon
			(pts
				(xy 314.78 167.11) (xy 314.790115 167.109847) (xy 314.820832 167.11046) (xy 314.85332 167.118782)
				(xy 314.882475 167.142675) (xy 314.903191 167.19) (xy 315.136 167.01) (xy 314.903191 166.83) (xy 314.889833 166.865901)
				(xy 314.871601 166.889199) (xy 314.826276 166.908899) (xy 314.790115 166.910153) (xy 314.78 166.91)
			)
		)
	)
	(zone
		(net 196)
		(net_name "/OCuLink/PCIe_{x4}.RX3+")
		(layer "F.Cu")
		(name "$teardrop_padvia$")
		(hatch none 0.1)
		(priority 32061)
		(attr
			(teardrop
				(type padvia)
			)
		)
		(connect_pads yes
			(clearance 0)
		)
		(min_thickness 0.0254)
		(filled_areas_thickness no)
		(fill yes
			(thermal_gap 0.5)
			(thermal_bridge_width 0.5)
			(island_removal_mode 1)
			(island_area_min 10)
		)
		(polygon
			(pts
				(xy 107.203 152.91) (xy 107.195802 152.889352) (xy 107.186208 152.857016) (xy 107.193035 152.842993)
				(xy 107.2145 152.833004) (xy 107.102 152.584) (xy 106.9895 152.833004) (xy 107.010676 152.842729)
				(xy 107.017731 152.856357) (xy 107.008198 152.889352) (xy 107.001 152.91)
			)
		)
	)
	(zone
		(net 281)
		(net_name "/Misc/TACH_{B5V}")
		(layer "F.Cu")
		(name "$teardrop_padvia$")
		(hatch none 0.1)
		(priority 30009)
		(attr
			(teardrop
				(type padvia)
			)
		)
		(connect_pads yes
			(clearance 0)
		)
		(min_thickness 0.0254)
		(filled_areas_thickness no)
		(fill yes
			(thermal_gap 0.5)
			(thermal_bridge_width 0.5)
			(island_removal_mode 1)
			(island_area_min 10)
		)
		(polygon
			(pts
				(xy 248.394457 72.735359) (xy 248.323806 72.637539) (xy 248.270681 72.495936) (xy 248.240679 72.30263)
				(xy 248.242337 72.05536) (xy 248.283613 71.765372) (xy 248.295709 71.71) (xy 247.430002 71.859293)
				(xy 247.599462 72.858379) (xy 247.752569 72.782683) (xy 247.922637 72.740142) (xy 248.008588 72.733309)
				(xy 248.089803 72.736611) (xy 248.162476 72.749312) (xy 248.226588 72.771083) (xy 248.306068 72.823748)
			)
		)
	)
	(zone
		(net 1)
		(net_name "GND")
		(layer "F.Cu")
		(name "$teardrop_padvia$")
		(hatch none 0.1)
		(priority 31286)
		(attr
			(teardrop
				(type padvia)
			)
		)
		(connect_pads yes
			(clearance 0)
		)
		(min_thickness 0.0254)
		(filled_areas_thickness no)
		(fill yes
			(thermal_gap 0.5)
			(thermal_bridge_width 0.5)
			(island_removal_mode 1)
			(island_area_min 10)
		)
		(polygon
			(pts
				(xy 195.85 151.849323) (xy 195.845287 151.927234) (xy 195.8323 151.986018) (xy 195.790199 152.077048)
				(xy 195.7475 152.162221) (xy 195.95 152.251) (xy 196.1525 152.162221) (xy 196.109801 152.07705)
				(xy 196.067133 151.984217) (xy 196.054556 151.926078) (xy 196.05 151.849323)
			)
		)
	)
	(zone
		(net 1)
		(net_name "GND")
		(layer "F.Cu")
		(name "$teardrop_padvia$")
		(hatch none 0.1)
		(priority 30785)
		(attr
			(teardrop
				(type padvia)
			)
		)
		(connect_pads yes
			(clearance 0)
		)
		(min_thickness 0.0254)
		(filled_areas_thickness no)
		(fill yes
			(thermal_gap 0.5)
			(thermal_bridge_width 0.5)
			(island_removal_mode 1)
			(island_area_min 10)
		)
		(polygon
			(pts
				(xy 286.600677 74.81) (xy 286.443106 74.803069) (xy 286.329578 74.774549) (xy 286.287778 74.7575)
				(xy 286.199 74.96) (xy 286.287778 75.1625) (xy 286.383817 75.128118) (xy 286.485689 75.1129) (xy 286.600677 75.11)
			)
		)
	)
	(zone
		(net 51)
		(net_name "Net-(C13-Pad1)")
		(layer "F.Cu")
		(name "$teardrop_padvia$")
		(hatch none 0.1)
		(priority 30471)
		(attr
			(teardrop
				(type padvia)
			)
		)
		(connect_pads yes
			(clearance 0)
		)
		(min_thickness 0.0254)
		(filled_areas_thickness no)
		(fill yes
			(thermal_gap 0.5)
			(thermal_bridge_width 0.5)
			(island_removal_mode 1)
			(island_area_min 10)
		)
		(polygon
			(pts
				(xy 129.938 110.56) (xy 129.92113 110.560338) (xy 129.876174 110.559759) (xy 129.828831 110.547941)
				(xy 129.786427 110.513362) (xy 129.756292 110.4445) (xy 129.499 110.71) (xy 129.756292 110.9755)
				(xy 129.771849 110.930731) (xy 129.792565 110.899115) (xy 129.843701 110.866381) (xy 129.92113 110.859662)
				(xy 129.938 110.86)
			)
		)
	)
	(zone
		(net 271)
		(net_name "/M.2 key M #2/PCIE_{REF}.CK-")
		(layer "F.Cu")
		(name "$teardrop_padvia$")
		(hatch none 0.1)
		(priority 30419)
		(attr
			(teardrop
				(type padvia)
			)
		)
		(connect_pads yes
			(clearance 0)
		)
		(min_thickness 0.0254)
		(filled_areas_thickness no)
		(fill yes
			(thermal_gap 0.5)
			(thermal_bridge_width 0.5)
			(island_removal_mode 1)
			(island_area_min 10)
		)
		(polygon
			(pts
				(xy 222.005521 129.8545) (xy 221.977939 129.831242) (xy 221.957276 129.800004) (xy 221.934401 129.708085)
				(xy 221.935 129.551085) (xy 221.639 129.65) (xy 221.608246 129.97) (xy 221.723378 129.960561) (xy 221.851718 129.985334)
				(xy 221.983283 130.043209) (xy 222.005521 130.0565)
			)
		)
	)
	(zone
		(net 2)
		(net_name "+3V3")
		(layer "F.Cu")
		(name "$teardrop_padvia$")
		(hatch none 0.1)
		(priority 30913)
		(attr
			(teardrop
				(type padvia)
			)
		)
		(connect_pads yes
			(clearance 0)
		)
		(min_thickness 0.0254)
		(filled_areas_thickness no)
		(fill yes
			(thermal_gap 0.5)
			(thermal_bridge_width 0.5)
			(island_removal_mode 1)
			(island_area_min 10)
		)
		(polygon
			(pts
				(xy 111.735053 135.066367) (xy 111.760894 134.970386) (xy 111.789737 134.921799) (xy 111.829896 134.879202)
				(xy 111.869442 134.853667) (xy 111.916415 134.837798) (xy 111.921798 134.836798) (xy 111.670707 134.559293)
				(xy 111.418202 134.836798) (xy 111.543693 134.866203) (xy 111.57697 134.884907) (xy 111.59231 134.909373)
				(xy 111.593633 134.924947)
			)
		)
	)
	(zone
		(net 1)
		(net_name "GND")
		(layer "F.Cu")
		(name "$teardrop_padvia$")
		(hatch none 0.1)
		(priority 30799)
		(attr
			(teardrop
				(type padvia)
			)
		)
		(connect_pads yes
			(clearance 0)
		)
		(min_thickness 0.0254)
		(filled_areas_thickness no)
		(fill yes
			(thermal_gap 0.5)
			(thermal_bridge_width 0.5)
			(island_removal_mode 1)
			(island_area_min 10)
		)
		(polygon
			(pts
				(xy 304.547 74.639323) (xy 304.540069 74.796893) (xy 304.511549 74.910421) (xy 304.4945 74.952221)
				(xy 304.697 75.041) (xy 304.8995 74.952221) (xy 304.865117 74.856179) (xy 304.8499 74.754304) (xy 304.847 74.639323)
			)
		)
	)
	(zone
		(net 599)
		(net_name "Net-(U34-~{INT})")
		(layer "F.Cu")
		(name "$teardrop_padvia$")
		(hatch none 0.1)
		(priority 31106)
		(attr
			(teardrop
				(type padvia)
			)
		)
		(connect_pads yes
			(clearance 0)
		)
		(min_thickness 0.0254)
		(filled_areas_thickness no)
		(fill yes
			(thermal_gap 0.5)
			(thermal_bridge_width 0.5)
			(island_removal_mode 1)
			(island_area_min 10)
		)
		(polygon
			(pts
				(xy 241.7375 131.467) (xy 241.717727 131.526412) (xy 241.654453 131.582496) (xy 241.605828 131.604198)
				(xy 241.546469 131.618872) (xy 241.5345 131.620652) (xy 241.8 131.881) (xy 242.0655 131.620652)
				(xy 242.005362 131.607803) (xy 241.955478 131.587869) (xy 241.915358 131.561944) (xy 241.886345 131.532124)
				(xy 241.868854 131.500706) (xy 241.862521 131.468895) (xy 241.8625 131.467)
			)
		)
	)
	(zone
		(net 570)
		(net_name "Net-(U6-~{RESET})")
		(layer "F.Cu")
		(name "$teardrop_padvia$")
		(hatch none 0.1)
		(priority 31034)
		(attr
			(teardrop
				(type padvia)
			)
		)
		(connect_pads yes
			(clearance 0)
		)
		(min_thickness 0.0254)
		(filled_areas_thickness no)
		(fill yes
			(thermal_gap 0.5)
			(thermal_bridge_width 0.5)
			(island_removal_mode 1)
			(island_area_min 10)
		)
		(polygon
			(pts
				(xy 114.117499 78.272) (xy 114.09753 78.334865) (xy 114.071078 78.366844) (xy 114.033667 78.395359)
				(xy 113.986472 78.417883) (xy 113.928832 78.433093) (xy 113.928202 78.433202) (xy 114.18 78.710999)
				(xy 114.431798 78.433202) (xy 114.376364 78.418905) (xy 114.330479 78.397825) (xy 114.292797 78.37046)
				(xy 114.265564 78.339552) (xy 114.248526 78.306265) (xy 114.242509 78.273435) (xy 114.242498 78.272001)
			)
		)
	)
	(zone
		(net 50)
		(net_name "Net-(C12-Pad2)")
		(layer "F.Cu")
		(name "$teardrop_padvia$")
		(hatch none 0.1)
		(priority 30872)
		(attr
			(teardrop
				(type padvia)
			)
		)
		(connect_pads yes
			(clearance 0)
		)
		(min_thickness 0.0254)
		(filled_areas_thickness no)
		(fill yes
			(thermal_gap 0.5)
			(thermal_bridge_width 0.5)
			(island_removal_mode 1)
			(island_area_min 10)
		)
		(polygon
			(pts
				(xy 137.493 113.01) (xy 137.452263 113.004228) (xy 137.410348 112.983824) (xy 137.382047 112.956649)
				(xy 137.358618 112.917103) (xy 137.339347 112.8445) (xy 137.079 113.11) (xy 137.339347 113.3755)
				(xy 137.351214 113.322358) (xy 137.369662 113.281319) (xy 137.420336 113.229618) (xy 137.483905 113.210282)
				(xy 137.493 113.21)
			)
		)
	)
	(zone
		(net 328)
		(net_name "/Com Express 7 Interfaces/PCIe_{B2Ax4}.TX2+")
		(layer "F.Cu")
		(name "$teardrop_padvia$")
		(hatch none 0.1)
		(priority 30367)
		(attr
			(teardrop
				(type padvia)
			)
		)
		(connect_pads yes
			(clearance 0)
		)
		(min_thickness 0.0254)
		(filled_areas_thickness no)
		(fill yes
			(thermal_gap 0.5)
			(thermal_bridge_width 0.5)
			(island_removal_mode 1)
			(island_area_min 10)
		)
		(polygon
			(pts
				(xy 291.6535 73.2) (xy 291.656524 73.214169) (xy 291.658552 73.244507) (xy 291.645562 73.255622)
				(xy 291.61522 73.26) (xy 291.699 74.036) (xy 291.849 73.814533) (xy 291.829652 73.60088) (xy 291.844397 73.355527)
				(xy 291.8555 73.2)
			)
		)
	)
	(zone
		(net 2)
		(net_name "+3V3")
		(layer "F.Cu")
		(name "$teardrop_padvia$")
		(hatch none 0.1)
		(priority 30399)
		(attr
			(teardrop
				(type padvia)
			)
		)
		(connect_pads yes
			(clearance 0)
		)
		(min_thickness 0.0254)
		(filled_areas_thickness no)
		(fill yes
			(thermal_gap 0.5)
			(thermal_bridge_width 0.5)
			(island_removal_mode 1)
			(island_area_min 10)
		)
		(polygon
			(pts
				(xy 114.65 149.314) (xy 114.629597 149.269355) (xy 114.610779 149.235808) (xy 114.602205 149.203345)
				(xy 114.616303 149.176635) (xy 114.6655 149.160347) (xy 114.4 148.9) (xy 114.1345 149.160347) (xy 114.172593 149.170167)
				(xy 114.192358 149.185574) (xy 114.195352 149.2199) (xy 114.170403 149.269355) (xy 114.15 149.314)
			)
		)
	)
	(zone
		(net 337)
		(net_name "/Com Express 7 Interfaces/PCIE_{REF}.CK-")
		(layer "F.Cu")
		(name "$teardrop_padvia$")
		(hatch none 0.1)
		(priority 31422)
		(attr
			(teardrop
				(type padvia)
			)
		)
		(connect_pads yes
			(clearance 0)
		)
		(min_thickness 0.0254)
		(filled_areas_thickness no)
		(fill yes
			(thermal_gap 0.5)
			(thermal_bridge_width 0.5)
			(island_removal_mode 1)
			(island_area_min 10)
		)
		(polygon
			(pts
				(xy 219.8685 169.632504) (xy 219.873895 169.794035) (xy 219.877445 169.878446) (xy 219.872823 169.98014)
				(xy 220.0935 170.001) (xy 220.256731 169.851147) (xy 220.188062 169.797007) (xy 220.171608 169.787116)
				(xy 220.132935 169.762616) (xy 220.100721 169.733109) (xy 220.078673 169.691953) (xy 220.0705 169.632504)
			)
		)
	)
	(zone
		(net 63)
		(net_name "Net-(U18-V_{CC})")
		(layer "F.Cu")
		(name "$teardrop_padvia$")
		(hatch none 0.1)
		(priority 31698)
		(attr
			(teardrop
				(type padvia)
			)
		)
		(connect_pads yes
			(clearance 0)
		)
		(min_thickness 0.0254)
		(filled_areas_thickness no)
		(fill yes
			(thermal_gap 0.5)
			(thermal_bridge_width 0.5)
			(island_removal_mode 1)
			(island_area_min 10)
		)
		(polygon
			(pts
				(xy 311.202499 122.059323) (xy 311.197681 122.128763) (xy 311.183959 122.180087) (xy 311.137244 122.255628)
				(xy 311.127701 122.267768) (xy 311.077918 122.334997) (xy 311.264999 122.461) (xy 311.45208 122.334997)
				(xy 311.402298 122.267769) (xy 311.347893 122.184603) (xy 311.332809 122.131748) (xy 311.327499 122.059323)
			)
		)
	)
	(zone
		(net 605)
		(net_name "Net-(U37-~{OE3})")
		(layer "F.Cu")
		(name "$teardrop_padvia$")
		(hatch none 0.1)
		(priority 31308)
		(attr
			(teardrop
				(type padvia)
			)
		)
		(connect_pads yes
			(clearance 0)
		)
		(min_thickness 0.0254)
		(filled_areas_thickness no)
		(fill yes
			(thermal_gap 0.5)
			(thermal_bridge_width 0.5)
			(island_removal_mode 1)
			(island_area_min 10)
		)
		(polygon
			(pts
				(xy 217.950149 132.658537) (xy 218.020256 132.681193) (xy 218.061118 132.710182) (xy 218.098536 132.749541)
				(xy 218.127896 132.79562) (xy 218.148311 132.84923) (xy 218.153202 132.871798) (xy 218.430707 132.620707)
				(xy 218.153202 132.368202) (xy 218.131665 132.462189) (xy 218.102535 132.529453) (xy 218.079256 132.556423)
				(xy 218.052005 132.569281) (xy 218.038537 132.570149)
			)
		)
	)
	(zone
		(net 89)
		(net_name "/Com Express 7 Interfaces/PCIe_{B2Ax4}.RX3-")
		(layer "F.Cu")
		(name "$teardrop_padvia$")
		(hatch none 0.1)
		(priority 30240)
		(attr
			(teardrop
				(type padvia)
			)
		)
		(connect_pads yes
			(clearance 0)
		)
		(min_thickness 0.0254)
		(filled_areas_thickness no)
		(fill yes
			(thermal_gap 0.5)
			(thermal_bridge_width 0.5)
			(island_removal_mode 1)
			(island_area_min 10)
		)
		(polygon
			(pts
				(xy 216.5705 164.07) (xy 216.56742 164.055773) (xy 216.565252 164.025473) (xy 216.578123 164.014372)
				(xy 216.608295 164.01) (xy 216.525 163.134) (xy 216.375 163.382978) (xy 216.394356 163.624182) (xy 216.379599 163.896888)
				(xy 216.3685 164.07)
			)
		)
	)
	(zone
		(net 1)
		(net_name "GND")
		(layer "F.Cu")
		(name "$teardrop_padvia$")
		(hatch none 0.1)
		(priority 31260)
		(attr
			(teardrop
				(type padvia)
			)
		)
		(connect_pads yes
			(clearance 0)
		)
		(min_thickness 0.0254)
		(filled_areas_thickness no)
		(fill yes
			(thermal_gap 0.5)
			(thermal_bridge_width 0.5)
			(island_removal_mode 1)
			(island_area_min 10)
		)
		(polygon
			(pts
				(xy 194.625 167.850677) (xy 194.629713 167.772764) (xy 194.6427 167.71398) (xy 194.684802 167.622947)
				(xy 194.7275 167.537778) (xy 194.525 167.449) (xy 194.3225 167.537778) (xy 194.365198 167.622949)
				(xy 194.407867 167.715783) (xy 194.420444 167.773922) (xy 194.425 167.850677)
			)
		)
	)
	(zone
		(net 55)
		(net_name "/USB-C console/USB_D+")
		(layer "F.Cu")
		(name "$teardrop_padvia$")
		(hatch none 0.1)
		(priority 30212)
		(attr
			(teardrop
				(type padvia)
			)
		)
		(connect_pads yes
			(clearance 0)
		)
		(min_thickness 0.0254)
		(filled_areas_thickness no)
		(fill yes
			(thermal_gap 0.5)
			(thermal_bridge_width 0.5)
			(island_removal_mode 1)
			(island_area_min 10)
		)
		(polygon
			(pts
				(xy 107.72926 78.669445) (xy 107.684974 78.617539) (xy 107.644392 78.5519) (xy 107.614118 78.481919)
				(xy 107.591918 78.401209) (xy 107.579 78.268162) (xy 107.278293 78.349293) (xy 107.197162 78.65)
				(xy 107.353302 78.668039) (xy 107.486908 78.718558) (xy 107.592748 78.794673) (xy 107.598445 78.80026)
			)
		)
	)
	(zone
		(net 978)
		(net_name "/PCIe redriver/RX_EQ0")
		(layer "F.Cu")
		(name "$teardrop_padvia$")
		(hatch none 0.1)
		(priority 31743)
		(attr
			(teardrop
				(type padvia)
			)
		)
		(connect_pads yes
			(clearance 0)
		)
		(min_thickness 0.0254)
		(filled_areas_thickness no)
		(fill yes
			(thermal_gap 0.5)
			(thermal_bridge_width 0.5)
			(island_removal_mode 1)
			(island_area_min 10)
		)
		(polygon
			(pts
				(xy 190.007785 140.67309) (xy 190.077226 140.677908) (xy 190.12855 140.69163) (xy 190.204091 140.738345)
				(xy 190.216231 140.747889) (xy 190.283459 140.797671) (xy 190.409462 140.61059) (xy 190.283459 140.423509)
				(xy 190.21623 140.473292) (xy 190.133064 140.527696) (xy 190.08021 140.54278) (xy 190.007785 140.54809)
			)
		)
	)
	(zone
		(net 85)
		(net_name "/Com Express 7 MGMT/MAFS_POWER")
		(layer "F.Cu")
		(name "$teardrop_padvia$")
		(hatch none 0.1)
		(priority 30055)
		(attr
			(teardrop
				(type padvia)
			)
		)
		(connect_pads yes
			(clearance 0)
		)
		(min_thickness 0.0254)
		(filled_areas_thickness no)
		(fill yes
			(thermal_gap 0.5)
			(thermal_bridge_width 0.5)
			(island_removal_mode 1)
			(island_area_min 10)
		)
		(polygon
			(pts
				(xy 250.277145 163.684999) (xy 250.265586 163.685103) (xy 250.219121 163.683687) (xy 250.169877 163.67015)
				(xy 250.126978 163.632212) (xy 250.09955 163.557595) (xy 249.321145 163.835) (xy 250.09955 164.112405)
				(xy 250.112306 164.065766) (xy 250.131069 164.032088) (xy 250.180056 163.99537) (xy 250.246142 163.98481)
				(xy 250.265587 163.984895) (xy 250.277145 163.984999)
			)
		)
	)
	(zone
		(net 356)
		(net_name "/Com Express 7 MGMT/~{CW_PWRBTN}")
		(layer "F.Cu")
		(name "$teardrop_padvia$")
		(hatch none 0.1)
		(priority 31722)
		(attr
			(teardrop
				(type padvia)
			)
		)
		(connect_pads yes
			(clearance 0)
		)
		(min_thickness 0.0254)
		(filled_areas_thickness no)
		(fill yes
			(thermal_gap 0.5)
			(thermal_bridge_width 0.5)
			(island_removal_mode 1)
			(island_area_min 10)
		)
		(polygon
			(pts
				(xy 223.3375 145.499323) (xy 223.332682 145.568763) (xy 223.31896 145.620087) (xy 223.272245 145.695628)
				(xy 223.262702 145.707768) (xy 223.212919 145.774997) (xy 223.4 145.901) (xy 223.587081 145.774997)
				(xy 223.537299 145.707769) (xy 223.482894 145.624603) (xy 223.46781 145.571748) (xy 223.4625 145.499323)
			)
		)
	)
	(zone
		(net 73)
		(net_name "+3V3_AON")
		(layer "F.Cu")
		(name "$teardrop_padvia$")
		(hatch none 0.1)
		(priority 30474)
		(attr
			(teardrop
				(type padvia)
			)
		)
		(connect_pads yes
			(clearance 0)
		)
		(min_thickness 0.0254)
		(filled_areas_thickness no)
		(fill yes
			(thermal_gap 0.5)
			(thermal_bridge_width 0.5)
			(island_removal_mode 1)
			(island_area_min 10)
		)
		(polygon
			(pts
				(xy 307.088 153.2) (xy 307.07113 153.200338) (xy 307.026174 153.199759) (xy 306.978831 153.187941)
				(xy 306.936427 153.153362) (xy 306.906292 153.0845) (xy 306.649 153.35) (xy 306.906292 153.6155)
				(xy 306.921849 153.570731) (xy 306.942565 153.539115) (xy 306.993701 153.506381) (xy 307.07113 153.499662)
				(xy 307.088 153.5)
			)
		)
	)
	(zone
		(net 704)
		(net_name "Net-(U24-GPIO2)")
		(layer "F.Cu")
		(name "$teardrop_padvia$")
		(hatch none 0.1)
		(priority 30813)
		(attr
			(teardrop
				(type padvia)
			)
		)
		(connect_pads yes
			(clearance 0)
		)
		(min_thickness 0.0254)
		(filled_areas_thickness no)
		(fill yes
			(thermal_gap 0.5)
			(thermal_bridge_width 0.5)
			(island_removal_mode 1)
			(island_area_min 10)
		)
		(polygon
			(pts
				(xy 260.624 85.667499) (xy 260.597391 85.662136) (xy 260.572117 85.644599) (xy 260.554478 85.618305)
				(xy 260.54305 85.580159) (xy 260.54 85.540999) (xy 259.979 85.73) (xy 260.54 85.918999) (xy 260.544627 85.871636)
				(xy 260.557018 85.836588) (xy 260.574877 85.81265) (xy 260.596015 85.798453) (xy 260.624 85.792499)
			)
		)
	)
	(zone
		(net 194)
		(net_name "/OCuLink/PCIe_{x4}.RX2+")
		(layer "F.Cu")
		(name "$teardrop_padvia$")
		(hatch none 0.1)
		(priority 32072)
		(attr
			(teardrop
				(type padvia)
			)
		)
		(connect_pads yes
			(clearance 0)
		)
		(min_thickness 0.0254)
		(filled_areas_thickness no)
		(fill yes
			(thermal_gap 0.5)
			(thermal_bridge_width 0.5)
			(island_removal_mode 1)
			(island_area_min 10)
		)
		(polygon
			(pts
				(xy 108.499 152.26) (xy 108.506198 152.280648) (xy 108.515792 152.312984) (xy 108.508965 152.327007)
				(xy 108.4875 152.336995) (xy 108.6 152.586) (xy 108.7125 152.336995) (xy 108.691324 152.327271)
				(xy 108.684269 152.313643) (xy 108.693802 152.280648) (xy 108.701 152.26)
			)
		)
	)
	(zone
		(net 955)
		(net_name "/2xSFP+/KR to SFI #2/BYP_TX+")
		(layer "F.Cu")
		(name "$teardrop_padvia$")
		(hatch none 0.1)
		(priority 31956)
		(attr
			(teardrop
				(type padvia)
			)
		)
		(connect_pads yes
			(clearance 0)
		)
		(min_thickness 0.0254)
		(filled_areas_thickness no)
		(fill yes
			(thermal_gap 0.5)
			(thermal_bridge_width 0.5)
			(island_removal_mode 1)
			(island_area_min 10)
		)
		(polygon
			(pts
				(xy 137.68 148.52855) (xy 137.655301 148.453648) (xy 137.620633 148.345962) (xy 137.610977 148.287503)
				(xy 137.612 148.227485) (xy 137.412 148.254) (xy 137.352023 148.485) (xy 137.432739 148.479808)
				(xy 137.484487 148.488465) (xy 137.506066 148.502201) (xy 137.518125 148.522056) (xy 137.52 148.52855)
			)
		)
	)
	(zone
		(net 153)
		(net_name "/2xUSB3.0+RJ45/DD-")
		(layer "F.Cu")
		(name "$teardrop_padvia$")
		(hatch none 0.1)
		(priority 30018)
		(attr
			(teardrop
				(type padvia)
			)
		)
		(connect_pads yes
			(clearance 0)
		)
		(min_thickness 0.0254)
		(filled_areas_thickness no)
		(fill yes
			(thermal_gap 0.5)
			(thermal_bridge_width 0.5)
			(island_removal_mode 1)
			(island_area_min 10)
		)
		(polygon
			(pts
				(xy 116.806515 100.7) (xy 116.665683 100.695039) (xy 116.550869 100.680314) (xy 116.466384 100.659521)
				(xy 116.392573 100.631541) (xy 116.252169 100.549668) (xy 116.159684 100.482811) (xy 115.98501 100.358758)
				(xy 115.609 100.92) (xy 115.98501 101.481242) (xy 116.118711 101.370931) (xy 116.230923 101.235351)
				(xy 116.284423 101.157213) (xy 116.368812 101.038676) (xy 116.415492 100.986536) (xy 116.468923 100.940909)
				(xy 116.531921 100.90312) (xy 116.607306 100.874491) (xy 116.697898 100.856343) (xy 116.806515 100.85)
			)
		)
	)
	(zone
		(net 262)
		(net_name "/Com Express 7 Interfaces/PCIe_{B2Bx4}.RX0-")
		(layer "F.Cu")
		(name "$teardrop_padvia$")
		(hatch none 0.1)
		(priority 31446)
		(attr
			(teardrop
				(type padvia)
			)
		)
		(connect_pads yes
			(clearance 0)
		)
		(min_thickness 0.0254)
		(filled_areas_thickness no)
		(fill yes
			(thermal_gap 0.5)
			(thermal_bridge_width 0.5)
			(island_removal_mode 1)
			(island_area_min 10)
		)
		(polygon
			(pts
				(xy 186.436416 122.7065) (xy 186.606647 122.699528) (xy 186.784069 122.697677) (xy 186.801 122.477)
				(xy 186.649081 122.315834) (xy 186.597229 122.384098) (xy 186.586815 122.402419) (xy 186.563455 122.441426)
				(xy 186.535008 122.473955) (xy 186.494865 122.496236) (xy 186.436416 122.5045)
			)
		)
	)
	(zone
		(net 348)
		(net_name "Net-(J12D-~{LPC_FRAME}{slash}~{ESPI_CS0})")
		(layer "F.Cu")
		(name "$teardrop_padvia$")
		(hatch none 0.1)
		(priority 30660)
		(attr
			(teardrop
				(type padvia)
			)
		)
		(connect_pads yes
			(clearance 0)
		)
		(min_thickness 0.0254)
		(filled_areas_thickness no)
		(fill yes
			(thermal_gap 0.5)
			(thermal_bridge_width 0.5)
			(island_removal_mode 1)
			(island_area_min 10)
		)
		(polygon
			(pts
				(xy 177.0875 164.07) (xy 177.098438 164.031177) (xy 177.120195 164.016067) (xy 177.16 164.01) (xy 177.025 163.134)
				(xy 176.89 164.01) (xy 176.925281 164.014517) (xy 176.946797 164.026138) (xy 176.961995 164.058961)
				(xy 176.9625 164.07)
			)
		)
	)
	(zone
		(net 139)
		(net_name "/Com Express 7 MGMT/SPI_POWER")
		(layer "F.Cu")
		(name "$teardrop_padvia$")
		(hatch none 0.1)
		(priority 30553)
		(attr
			(teardrop
				(type padvia)
			)
		)
		(connect_pads yes
			(clearance 0)
		)
		(min_thickness 0.0254)
		(filled_areas_thickness no)
		(fill yes
			(thermal_gap 0.5)
			(thermal_bridge_width 0.5)
			(island_removal_mode 1)
			(island_area_min 10)
		)
		(polygon
			(pts
				(xy 220.925 167.75) (xy 220.928333 167.764486) (xy 220.93119 167.79461) (xy 220.919036 167.805651)
				(xy 220.89 167.81) (xy 221.025 168.686) (xy 221.16 167.81) (xy 221.130666 167.805525) (xy 221.118642 167.794199)
				(xy 221.121667 167.764486) (xy 221.125 167.75)
			)
		)
	)
	(zone
		(net 893)
		(net_name "Net-(J2B-TX_{DISABLE})")
		(layer "F.Cu")
		(name "$teardrop_padvia$")
		(hatch none 0.1)
		(priority 31794)
		(attr
			(teardrop
				(type padvia)
			)
		)
		(connect_pads yes
			(clearance 0)
		)
		(min_thickness 0.0254)
		(filled_areas_thickness no)
		(fill yes
			(thermal_gap 0.5)
			(thermal_bridge_width 0.5)
			(island_removal_mode 1)
			(island_area_min 10)
		)
		(polygon
			(pts
				(xy 138.450677 167.5025) (xy 138.381236 167.497682) (xy 138.329913 167.48396) (xy 138.254371 167.437246)
				(xy 138.242231 167.427701) (xy 138.175003 167.377919) (xy 138.049 167.565) (xy 138.175003 167.752081)
				(xy 138.242229 167.702299) (xy 138.325396 167.647894) (xy 138.378251 167.63281) (xy 138.450677 167.6275)
			)
		)
	)
	(zone
		(net 193)
		(net_name "/OCuLink/PCIe_{REF0}.CK-")
		(layer "F.Cu")
		(name "$teardrop_padvia$")
		(hatch none 0.1)
		(priority 32057)
		(attr
			(teardrop
				(type padvia)
			)
		)
		(connect_pads yes
			(clearance 0)
		)
		(min_thickness 0.0254)
		(filled_areas_thickness no)
		(fill yes
			(thermal_gap 0.5)
			(thermal_bridge_width 0.5)
			(island_removal_mode 1)
			(island_area_min 10)
		)
		(polygon
			(pts
				(xy 111.301 152.91) (xy 111.293802 152.889352) (xy 111.284208 152.857016) (xy 111.291035 152.842993)
				(xy 111.3125 152.833004) (xy 111.2 152.584) (xy 111.0875 152.833004) (xy 111.108676 152.842729)
				(xy 111.115731 152.856357) (xy 111.106198 152.889352) (xy 111.099 152.91)
			)
		)
	)
	(zone
		(net 783)
		(net_name "/Misc/PWM_{B3V3}")
		(layer "F.Cu")
		(name "$teardrop_padvia$")
		(hatch none 0.1)
		(priority 30742)
		(attr
			(teardrop
				(type padvia)
			)
		)
		(connect_pads yes
			(clearance 0)
		)
		(min_thickness 0.0254)
		(filled_areas_thickness no)
		(fill yes
			(thermal_gap 0.5)
			(thermal_bridge_width 0.5)
			(island_removal_mode 1)
			(island_area_min 10)
		)
		(polygon
			(pts
				(xy 244.330708 79.0225) (xy 244.274257 79.002455) (xy 244.247447 78.976276) (xy 244.224656 78.939267)
				(xy 244.198773 78.8375) (xy 243.819708 79.085) (xy 244.198773 79.3325) (xy 244.208582 79.275174)
				(xy 244.225736 79.228495) (xy 244.248882 79.191945) (xy 244.275973 79.166305) (xy 244.330708 79.1475)
			)
		)
	)
	(zone
		(net 55)
		(net_name "/USB-C console/USB_D+")
		(layer "F.Cu")
		(name "$teardrop_padvia$")
		(hatch none 0.1)
		(priority 30458)
		(attr
			(teardrop
				(type padvia)
			)
		)
		(connect_pads yes
			(clearance 0)
		)
		(min_thickness 0.0254)
		(filled_areas_thickness no)
		(fill yes
			(thermal_gap 0.5)
			(thermal_bridge_width 0.5)
			(island_removal_mode 1)
			(island_area_min 10)
		)
		(polygon
			(pts
				(xy 110.367148 75.728501) (xy 110.517105 75.667221) (xy 110.608779 75.645408) (xy 110.705548 75.639302)
				(xy 110.762942 75.646) (xy 110.727999 75.326) (xy 110.431999 75.230268) (xy 110.438889 75.369192)
				(xy 110.426135 75.468272) (xy 110.409337 75.505688) (xy 110.384473 75.532847) (xy 110.367148 75.543501)
			)
		)
	)
	(zone
		(net 490)
		(net_name "/2xSFP+/MDIO1.MDIO")
		(layer "F.Cu")
		(name "$teardrop_padvia$")
		(hatch none 0.1)
		(priority 31802)
		(attr
			(teardrop
				(type padvia)
			)
		)
		(connect_pads yes
			(clearance 0)
		)
		(min_thickness 0.0254)
		(filled_areas_thickness no)
		(fill yes
			(thermal_gap 0.5)
			(thermal_bridge_width 0.5)
			(island_removal_mode 1)
			(island_area_min 10)
		)
		(polygon
			(pts
				(xy 197.225677 149.2875) (xy 197.156236 149.282682) (xy 197.104913 149.26896) (xy 197.029371 149.222246)
				(xy 197.017231 149.212701) (xy 196.950003 149.162919) (xy 196.824 149.35) (xy 196.950003 149.537081)
				(xy 197.017229 149.487299) (xy 197.100396 149.432894) (xy 197.153251 149.41781) (xy 197.225677 149.4125)
			)
		)
	)
	(zone
		(net 1)
		(net_name "GND")
		(layer "F.Cu")
		(hatch edge 0.5)
		(priority 36)
		(connect_pads yes
			(clearance 0.15)
		)
		(min_thickness 0.25)
		(filled_areas_thickness no)
		(fill yes
			(thermal_gap 0.5)
			(thermal_bridge_width 0.5)
			(smoothing fillet)
			(radius 0.2)
		)
		(polygon
			(pts
				(xy 116.3 92.16) (xy 116.3 91.46) (xy 116.25 91.41) (xy 112.9 91.41) (xy 112.35 91.96) (xy 109.3 91.96)
				(xy 109.3 94.06) (xy 113 94.06) (xy 114.9 92.16)
			)
		)
	)
	(zone
		(net 720)
		(net_name "Net-(U43C-REFCLK1+)")
		(layer "F.Cu")
		(name "$teardrop_padvia$")
		(hatch none 0.1)
		(priority 30102)
		(attr
			(teardrop
				(type padvia)
			)
		)
		(connect_pads yes
			(clearance 0)
		)
		(min_thickness 0.0254)
		(filled_areas_thickness no)
		(fill yes
			(thermal_gap 0.5)
			(thermal_bridge_width 0.5)
			(island_removal_mode 1)
			(island_area_min 10)
		)
		(polygon
			(pts
				(xy 145.3625 129.377794) (xy 145.367315 129.295733) (xy 145.381019 129.230388) (xy 145.427576 129.13712)
				(xy 145.495787 129.058657) (xy 145.551942 128.997158) (xy 145.611801 128.918339) (xy 145.3 128.709)
				(xy 144.988199 128.918339) (xy 145.085219 129.038517) (xy 145.104214 129.058658) (xy 145.157366 129.117541)
				(xy 145.199591 129.181624) (xy 145.227449 129.264008) (xy 145.2375 129.377794)
			)
		)
	)
	(zone
		(net 2)
		(net_name "+3V3")
		(layer "F.Cu")
		(name "$teardrop_padvia$")
		(hatch none 0.1)
		(priority 30405)
		(attr
			(teardrop
				(type padvia)
			)
		)
		(connect_pads yes
			(clearance 0)
		)
		(min_thickness 0.0254)
		(filled_areas_thickness no)
		(fill yes
			(thermal_gap 0.5)
			(thermal_bridge_width 0.5)
			(island_removal_mode 1)
			(island_area_min 10)
		)
		(polygon
			(pts
				(xy 114.15 149.467) (xy 114.170403 149.511645) (xy 114.189221 149.545192) (xy 114.197795 149.577655)
				(xy 114.183697 149.604365) (xy 114.1345 149.620652) (xy 114.4 149.881) (xy 114.6655 149.620652)
				(xy 114.627407 149.610832) (xy 114.607642 149.595425) (xy 114.604648 149.5611) (xy 114.629597 149.511645)
				(xy 114.65 149.467)
			)
		)
	)
	(zone
		(net 970)
		(net_name "/M.2 key M #2/M2_3V3")
		(layer "F.Cu")
		(name "$teardrop_padvia$")
		(hatch none 0.1)
		(priority 30767)
		(attr
			(teardrop
				(type padvia)
			)
		)
		(connect_pads yes
			(clearance 0)
		)
		(min_thickness 0.0254)
		(filled_areas_thickness no)
		(fill yes
			(thermal_gap 0.5)
			(thermal_bridge_width 0.5)
			(island_removal_mode 1)
			(island_area_min 10)
		)
		(polygon
			(pts
				(xy 287.097 80.978677) (xy 287.103932 80.8211) (xy 287.132456 80.707565) (xy 287.1495 80.665778)
				(xy 286.947 80.577) (xy 286.7445 80.665778) (xy 286.778883 80.761822) (xy 286.794101 80.863702)
				(xy 286.797 80.978677)
			)
		)
	)
	(zone
		(net 139)
		(net_name "/Com Express 7 MGMT/SPI_POWER")
		(layer "F.Cu")
		(name "$teardrop_padvia$")
		(hatch none 0.1)
		(priority 31238)
		(attr
			(teardrop
				(type padvia)
			)
		)
		(connect_pads yes
			(clearance 0)
		)
		(min_thickness 0.0254)
		(filled_areas_thickness no)
		(fill yes
			(thermal_gap 0.5)
			(thermal_bridge_width 0.5)
			(island_removal_mode 1)
			(island_area_min 10)
		)
		(polygon
			(pts
				(xy 221.125 167.300677) (xy 221.129737 167.209676) (xy 221.142896 167.142587) (xy 221.175418 167.055855)
				(xy 221.207644 166.975358) (xy 221 166.899) (xy 220.803541 167.002363) (xy 220.855343 167.085863)
				(xy 220.904833 167.171955) (xy 220.919614 167.22716) (xy 220.925 167.300677)
			)
		)
	)
	(zone
		(net 434)
		(net_name "/Com Express 7 MGMT/~{TYPE1}")
		(layer "F.Cu")
		(name "$teardrop_padvia$")
		(hatch none 0.1)
		(priority 31608)
		(attr
			(teardrop
				(type padvia)
			)
		)
		(connect_pads yes
			(clearance 0)
		)
		(min_thickness 0.0254)
		(filled_areas_thickness no)
		(fill yes
			(thermal_gap 0.5)
			(thermal_bridge_width 0.5)
			(island_removal_mode 1)
			(island_area_min 10)
		)
		(polygon
			(pts
				(xy 204.0875 155.875677) (xy 204.092253 155.814547) (xy 204.105521 155.768447) (xy 204.150771 155.701755)
				(xy 204.16863 155.682657) (xy 204.237081 155.600003) (xy 204.05 155.474) (xy 203.842355 155.550358)
				(xy 203.900666 155.66542) (xy 203.944145 155.749531) (xy 203.957549 155.803939) (xy 203.9625 155.875677)
			)
		)
	)
	(zone
		(net 1)
		(net_name "GND")
		(layer "F.Cu")
		(name "$teardrop_padvia$")
		(hatch none 0.1)
		(priority 30824)
		(attr
			(teardrop
				(type padvia)
			)
		)
		(connect_pads yes
			(clearance 0)
		)
		(min_thickness 0.0254)
		(filled_areas_thickness no)
		(fill yes
			(thermal_gap 0.5)
			(thermal_bridge_width 0.5)
			(island_removal_mode 1)
			(island_area_min 10)
		)
		(polygon
			(pts
				(xy 304.0702 106.818587) (xy 304.067596 106.838302) (xy 304.054443 106.854598) (xy 303.991047 106.881006)
				(xy 303.93295 106.89295) (xy 304.125707 107.410707) (xy 304.31705 106.89295) (xy 304.243927 106.86269)
				(xy 304.186432 106.80205) (xy 304.158587 106.7302)
			)
		)
	)
	(zone
		(net 664)
		(net_name "/2xSFP+/KR to SFI #1/KR_R.RX+")
		(layer "F.Cu")
		(name "$teardrop_padvia$")
		(hatch none 0.1)
		(priority 31167)
		(attr
			(teardrop
				(type padvia)
			)
		)
		(connect_pads yes
			(clearance 0)
		)
		(min_thickness 0.0254)
		(filled_areas_thickness no)
		(fill yes
			(thermal_gap 0.5)
			(thermal_bridge_width 0.5)
			(island_removal_mode 1)
			(island_area_min 10)
		)
		(polygon
			(pts
				(xy 153.22 143.17679) (xy 153.224788 143.139695) (xy 153.238304 143.115431) (xy 153.280007 143.096705)
				(xy 153.368927 143.101889) (xy 153.434222 143.108714) (xy 153.498773 143.105196) (xy 153.45 142.859)
				(xy 153.204804 142.811227) (xy 153.168876 142.909201) (xy 153.132391 142.964616) (xy 153.082365 143.048601)
				(xy 153.066125 143.104227) (xy 153.06 143.17679)
			)
		)
	)
	(zone
		(net 866)
		(net_name "/Backplane/PCIe_{x2}.TX0+")
		(layer "F.Cu")
		(name "$teardrop_padvia$")
		(hatch none 0.1)
		(priority 30249)
		(attr
			(teardrop
				(type padvia)
			)
		)
		(connect_pads yes
			(clearance 0)
		)
		(min_thickness 0.0254)
		(filled_areas_thickness no)
		(fill yes
			(thermal_gap 0.5)
			(thermal_bridge_width 0.5)
			(island_removal_mode 1)
			(island_area_min 10)
		)
		(polygon
			(pts
				(xy 201.4795 150.2) (xy 201.48258 150.214227) (xy 201.484749 150.244527) (xy 201.471877 150.255628)
				(xy 201.441705 150.26) (xy 201.525 151.136) (xy 201.675 150.887021) (xy 201.655644 150.645818) (xy 201.670401 150.373112)
				(xy 201.6815 150.2)
			)
		)
	)
	(zone
		(net 312)
		(net_name "/2xUSB3.0+RJ45/USB_1.D-")
		(layer "F.Cu")
		(name "$teardrop_padvia$")
		(hatch none 0.1)
		(priority 31547)
		(attr
			(teardrop
				(type padvia)
			)
		)
		(connect_pads yes
			(clearance 0)
		)
		(min_thickness 0.0254)
		(filled_areas_thickness no)
		(fill yes
			(thermal_gap 0.5)
			(thermal_bridge_width 0.5)
			(island_removal_mode 1)
			(island_area_min 10)
		)
		(polygon
			(pts
				(xy 153.6195 123.342084) (xy 153.624248 123.302213) (xy 153.63748 123.273549) (xy 153.681856 123.239406)
				(xy 153.72198 123.223769) (xy 153.802003 123.187081) (xy 153.677 122.999) (xy 153.456323 122.998242)
				(xy 153.446098 123.148454) (xy 153.4345 123.342084)
			)
		)
	)
	(zone
		(net 1)
		(net_name "GND")
		(layer "F.Cu")
		(name "$teardrop_padvia$")
		(hatch none 0.1)
		(priority 31931)
		(attr
			(teardrop
				(type padvia)
			)
		)
		(connect_pads yes
			(clearance 0)
		)
		(min_thickness 0.0254)
		(filled_areas_thickness no)
		(fill yes
			(thermal_gap 0.5)
			(thermal_bridge_width 0.5)
			(island_removal_mode 1)
			(island_area_min 10)
		)
		(polygon
			(pts
				(xy 107.5 152.23) (xy 107.500153 152.240115) (xy 107.49954 152.270832) (xy 107.491218 152.30332)
				(xy 107.467325 152.332475) (xy 107.42 152.353191) (xy 107.6 152.586) (xy 107.78 152.353191) (xy 107.744099 152.339833)
				(xy 107.720801 152.321601) (xy 107.701101 152.276276) (xy 107.699847 152.240115) (xy 107.7 152.23)
			)
		)
	)
	(zone
		(net 355)
		(net_name "Net-(J12D-LPC_CLK{slash}ESPI_CK)")
		(layer "F.Cu")
		(name "$teardrop_padvia$")
		(hatch none 0.1)
		(priority 31864)
		(attr
			(teardrop
				(type padvia)
			)
		)
		(connect_pads yes
			(clearance 0)
		)
		(min_thickness 0.0254)
		(filled_areas_thickness no)
		(fill yes
			(thermal_gap 0.5)
			(thermal_bridge_width 0.5)
			(island_removal_mode 1)
			(island_area_min 10)
		)
		(polygon
			(pts
				(xy 180.622485 165.510873) (xy 180.668181 165.563382) (xy 180.694768 165.609376) (xy 180.715152 165.695825)
				(xy 180.716988 165.711158) (xy 180.729323 165.793895) (xy 180.950707 165.750707) (xy 180.993895 165.529323)
				(xy 180.911158 165.516988) (xy 180.81388 165.496651) (xy 180.76584 165.469943) (xy 180.710873 165.422485)
			)
		)
	)
	(zone
		(net 339)
		(net_name "/Com Express 7 Interfaces/SDIO.CLK")
		(layer "F.Cu")
		(name "$teardrop_padvia$")
		(hatch none 0.1)
		(priority 31466)
		(attr
			(teardrop
				(type padvia)
			)
		)
		(connect_pads yes
			(clearance 0)
		)
		(min_thickness 0.0254)
		(filled_areas_thickness no)
		(fill yes
			(thermal_gap 0.5)
			(thermal_bridge_width 0.5)
			(island_removal_mode 1)
			(island_area_min 10)
		)
		(polygon
			(pts
				(xy 221.934 169.499323) (xy 221.929194 169.569237) (xy 221.915555 169.62142) (xy 221.868902 169.699106)
				(xy 221.858229 169.713003) (xy 221.812919 169.774997) (xy 222 169.901) (xy 222.207644 169.824641)
				(xy 222.168232 169.731564) (xy 222.13093 169.636314) (xy 222.116 169.499323)
			)
		)
	)
	(zone
		(net 735)
		(net_name "Net-(U43A-LS_OK_{IN_A})")
		(layer "F.Cu")
		(name "$teardrop_padvia$")
		(hatch none 0.1)
		(priority 31721)
		(attr
			(teardrop
				(type padvia)
			)
		)
		(connect_pads yes
			(clearance 0)
		)
		(min_thickness 0.0254)
		(filled_areas_thickness no)
		(fill yes
			(thermal_gap 0.5)
			(thermal_bridge_width 0.5)
			(island_removal_mode 1)
			(island_area_min 10)
		)
		(polygon
			(pts
				(xy 155.6375 130.459323) (xy 155.632682 130.528763) (xy 155.61896 130.580087) (xy 155.572245 130.655628)
				(xy 155.562702 130.667768) (xy 155.512919 130.734997) (xy 155.7 130.861) (xy 155.887081 130.734997)
				(xy 155.837299 130.667769) (xy 155.782894 130.584603) (xy 155.76781 130.531748) (xy 155.7625 130.459323)
			)
		)
	)
	(zone
		(net 667)
		(net_name "/2xSFP+/KR to SFI #1/SFI_R.RX+")
		(layer "F.Cu")
		(name "$teardrop_padvia$")
		(hatch none 0.1)
		(priority 31971)
		(attr
			(teardrop
				(type padvia)
			)
		)
		(connect_pads yes
			(clearance 0)
		)
		(min_thickness 0.0254)
		(filled_areas_thickness no)
		(fill yes
			(thermal_gap 0.5)
			(thermal_bridge_width 0.5)
			(island_removal_mode 1)
			(island_area_min 10)
		)
		(polygon
			(pts
				(xy 149.68 146.739321) (xy 149.660773 146.763574) (xy 149.630489 146.779871) (xy 149.537293 146.787898)
				(xy 149.509956 146.786) (xy 149.57 147.017) (xy 149.77 147.043457) (xy 149.768097 146.939652) (xy 149.799419 146.825164)
				(xy 149.84 146.739321)
			)
		)
	)
	(zone
		(net 38)
		(net_name "Net-(J100-SUSCLK)")
		(layer "F.Cu")
		(name "$teardrop_padvia$")
		(hatch none 0.1)
		(priority 30854)
		(attr
			(teardrop
				(type padvia)
			)
		)
		(connect_pads yes
			(clearance 0)
		)
		(min_thickness 0.0254)
		(filled_areas_thickness no)
		(fill yes
			(thermal_gap 0.5)
			(thermal_bridge_width 0.5)
			(island_removal_mode 1)
			(island_area_min 10)
		)
		(polygon
			(pts
				(xy 145.2405 83.372) (xy 145.279323 83.382938) (xy 145.294433 83.404695) (xy 145.3005 83.4445) (xy 146.0765 83.3095)
				(xy 145.3005 83.1745) (xy 145.295983 83.209781) (xy 145.284362 83.231297) (xy 145.251539 83.246495)
				(xy 145.2405 83.247)
			)
		)
	)
	(zone
		(net 80)
		(net_name "Net-(Q6-D)")
		(layer "F.Cu")
		(name "$teardrop_padvia$")
		(hatch none 0.1)
		(priority 30233)
		(attr
			(teardrop
				(type padvia)
			)
		)
		(connect_pads yes
			(clearance 0)
		)
		(min_thickness 0.0254)
		(filled_areas_thickness no)
		(fill yes
			(thermal_gap 0.5)
			(thermal_bridge_width 0.5)
			(island_removal_mode 1)
			(island_area_min 10)
		)
		(polygon
			(pts
				(xy 262.798684 91.717815) (xy 262.816695 91.735343) (xy 262.862589 91.782078) (xy 262.904964 91.841203)
				(xy 262.93153 91.91668) (xy 262.93 92.012474) (xy 263.250707 91.957707) (xy 263.330474 91.662) (xy 263.272918 91.66284)
				(xy 263.22199 91.654683) (xy 263.131211 91.614411) (xy 263.047325 91.543187) (xy 263.030147 91.525502)
				(xy 263.010815 91.505685)
			)
		)
	)
	(zone
		(net 584)
		(net_name "Net-(U21-EN)")
		(layer "F.Cu")
		(name "$teardrop_padvia$")
		(hatch none 0.1)
		(priority 32041)
		(attr
			(teardrop
				(type padvia)
			)
		)
		(connect_pads yes
			(clearance 0)
		)
		(min_thickness 0.0254)
		(filled_areas_thickness no)
		(fill yes
			(thermal_gap 0.5)
			(thermal_bridge_width 0.5)
			(island_removal_mode 1)
			(island_area_min 10)
		)
		(polygon
			(pts
				(xy 312.446522 96.198135) (xy 312.45155 96.182413) (xy 312.471544 96.172628) (xy 312.527533 96.161533)
				(xy 312.398793 95.882793) (xy 312.271467 96.161533) (xy 312.318741 96.186877) (xy 312.349464 96.240852)
				(xy 312.358135 96.286522)
			)
		)
	)
	(zone
		(net 544)
		(net_name "Net-(Q10-E)")
		(layer "F.Cu")
		(name "$teardrop_padvia$")
		(hatch none 0.1)
		(priority 31774)
		(attr
			(teardrop
				(type padvia)
			)
		)
		(connect_pads yes
			(clearance 0)
		)
		(min_thickness 0.0254)
		(filled_areas_thickness no)
		(fill yes
			(thermal_gap 0.5)
			(thermal_bridge_width 0.5)
			(island_removal_mode 1)
			(island_area_min 10)
		)
		(polygon
			(pts
				(xy 255.349323 85.162499) (xy 255.418763 85.167317) (xy 255.470087 85.181039) (xy 255.545628 85.227754)
				(xy 255.557769 85.237298) (xy 255.624997 85.287081) (xy 255.751 85.1) (xy 255.624997 84.912919)
				(xy 255.557769 84.962701) (xy 255.474603 85.017105) (xy 255.421748 85.032189) (xy 255.349323 85.037499)
			)
		)
	)
	(zone
		(net 602)
		(net_name "Net-(U37-~{OE0})")
		(layer "F.Cu")
		(name "$teardrop_padvia$")
		(hatch none 0.1)
		(priority 30480)
		(attr
			(teardrop
				(type padvia)
			)
		)
		(connect_pads yes
			(clearance 0)
		)
		(min_thickness 0.0254)
		(filled_areas_thickness no)
		(fill yes
			(thermal_gap 0.5)
			(thermal_bridge_width 0.5)
			(island_removal_mode 1)
			(island_area_min 10)
		)
		(polygon
			(pts
				(xy 212.149444 127.391056) (xy 212.094065 127.307713) (xy 212.057846 127.177724) (xy 212.051483 127.097134)
				(xy 212.055 127.009526) (xy 211.759293 127.089293) (xy 211.704526 127.41) (xy 211.855684 127.400982)
				(xy 211.923215 127.410826) (xy 211.982026 127.429091) (xy 212.061056 127.479444)
			)
		)
	)
	(zone
		(net 1)
		(net_name "GND")
		(layer "F.Cu")
		(name "$teardrop_padvia$")
		(hatch none 0.1)
		(priority 30586)
		(attr
			(teardrop
				(type padvia)
			)
		)
		(connect_pads yes
			(clearance 0)
		)
		(min_thickness 0.0254)
		(filled_areas_thickness no)
		(fill yes
			(thermal_gap 0.5)
			(thermal_bridge_width 0.5)
			(island_removal_mode 1)
			(island_area_min 10)
		)
		(polygon
			(pts
				(xy 201.125 152.07) (xy 201.121667 152.055514) (xy 201.11881 152.02539) (xy 201.130964 152.014349)
				(xy 201.16 152.01) (xy 201.025 151.134) (xy 200.89 152.01) (xy 200.919334 152.014475) (xy 200.931358 152.025801)
				(xy 200.928333 152.055514) (xy 200.925 152.07)
			)
		)
	)
	(zone
		(net 380)
		(net_name "Net-(J12G-USB0_HOST_PRSNT)")
		(layer "F.Cu")
		(name "$teardrop_padvia$")
		(hatch none 0.1)
		(priority 30685)
		(attr
			(teardrop
				(type padvia)
			)
		)
		(connect_pads yes
			(clearance 0)
		)
		(min_thickness 0.0254)
		(filled_areas_thickness no)
		(fill yes
			(thermal_gap 0.5)
			(thermal_bridge_width 0.5)
			(island_removal_mode 1)
			(island_area_min 10)
		)
		(polygon
			(pts
				(xy 199.4625 162.2) (xy 199.451563 162.238823) (xy 199.429805 162.253933) (xy 199.39 162.26) (xy 199.525 163.136)
				(xy 199.66 162.26) (xy 199.624719 162.255483) (xy 199.603203 162.243862) (xy 199.588005 162.211039)
				(xy 199.5875 162.2)
			)
		)
	)
	(zone
		(net 898)
		(net_name "/2xSFP+/SFP1_LEDY")
		(layer "F.Cu")
		(name "$teardrop_padvia$")
		(hatch none 0.1)
		(priority 31062)
		(attr
			(teardrop
				(type padvia)
			)
		)
		(connect_pads yes
			(clearance 0)
		)
		(min_thickness 0.0254)
		(filled_areas_thickness no)
		(fill yes
			(thermal_gap 0.5)
			(thermal_bridge_width 0.5)
			(island_removal_mode 1)
			(island_area_min 10)
		)
		(polygon
			(pts
				(xy 156.192 167.2975) (xy 156.132588 167.277727) (xy 156.076503 167.214453) (xy 156.054801 167.165828)
				(xy 156.040127 167.106468) (xy 156.038347 167.0945) (xy 155.778 167.36) (xy 156.038347 167.6255)
				(xy 156.051197 167.565361) (xy 156.071131 167.515477) (xy 156.097056 167.475358) (xy 156.126876 167.446345)
				(xy 156.158294 167.428854) (xy 156.190105 167.422521) (xy 156.192 167.4225)
			)
		)
	)
	(zone
		(net 73)
		(net_name "+3V3_AON")
		(layer "F.Cu")
		(name "$teardrop_padvia$")
		(hatch none 0.1)
		(priority 31288)
		(attr
			(teardrop
				(type padvia)
			)
		)
		(connect_pads yes
			(clearance 0)
		)
		(min_thickness 0.0254)
		(filled_areas_thickness no)
		(fill yes
			(thermal_gap 0.5)
			(thermal_bridge_width 0.5)
			(island_removal_mode 1)
			(island_area_min 10)
		)
		(polygon
			(pts
				(xy 190.60861 73.701486) (xy 190.603897 73.779397) (xy 190.59091 73.838181) (xy 190.548809 73.929211)
				(xy 190.50611 74.014384) (xy 190.70861 74.103163) (xy 190.91111 74.014384) (xy 190.868411 73.929213)
				(xy 190.825743 73.83638) (xy 190.813166 73.778241) (xy 190.80861 73.701486)
			)
		)
	)
	(zone
		(net 282)
		(net_name "/Misc/PWM_{B5V}")
		(layer "F.Cu")
		(name "$teardrop_padvia$")
		(hatch none 0.1)
		(priority 30006)
		(attr
			(teardrop
				(type padvia)
			)
		)
		(connect_pads yes
			(clearance 0)
		)
		(min_thickness 0.0254)
		(filled_areas_thickness no)
		(fill yes
			(thermal_gap 0.5)
			(thermal_bridge_width 0.5)
			(island_removal_mode 1)
			(island_area_min 10)
		)
		(polygon
			(pts
				(xy 244.953209 73.204379) (xy 244.97242 73.092884) (xy 245.034779 72.965774) (xy 245.1495 72.822593)
				(xy 245.322988 72.669697) (xy 245.550211 72.522375) (xy 245.60993 72.490568) (xy 244.890709 71.859)
				(xy 244.171488 72.490568) (xy 244.411708 72.635511) (xy 244.516959 72.716099) (xy 244.610523 72.800833)
				(xy 244.684619 72.881528) (xy 244.745161 72.96348) (xy 244.785848 73.035756) (xy 244.813532 73.107416)
				(xy 244.828209 73.204379)
			)
		)
	)
	(zone
		(net 313)
		(net_name "/2xUSB3.0+RJ45/USB_1.D+")
		(layer "F.Cu")
		(name "$teardrop_padvia$")
		(hatch none 0.1)
		(priority 30444)
		(attr
			(teardrop
				(type padvia)
			)
		)
		(connect_pads yes
			(clearance 0)
		)
		(min_thickness 0.0254)
		(filled_areas_thickness no)
		(fill yes
			(thermal_gap 0.5)
			(thermal_bridge_width 0.5)
			(island_removal_mode 1)
			(island_area_min 10)
		)
		(polygon
			(pts
				(xy 130.958645 118.068) (xy 130.932036 118.049178) (xy 130.912171 118.022574) (xy 130.889868 117.941195)
				(xy 130.894 117.754499) (xy 130.598 117.85) (xy 130.562755 118.17) (xy 130.680908 118.164879) (xy 130.816051 118.193631)
				(xy 130.958645 118.253)
			)
		)
	)
	(zone
		(net 548)
		(net_name "/2xUSB3.0+RJ45/P2_ISET")
		(layer "F.Cu")
		(name "$teardrop_padvia$")
		(hatch none 0.1)
		(priority 30076)
		(attr
			(teardrop
				(type padvia)
			)
		)
		(connect_pads yes
			(clearance 0)
		)
		(min_thickness 0.0254)
		(filled_areas_thickness no)
		(fill yes
			(thermal_gap 0.5)
			(thermal_bridge_width 0.5)
			(island_removal_mode 1)
			(island_area_min 10)
		)
		(polygon
			(pts
				(xy 118.939 91.7015) (xy 118.883736 91.682104) (xy 118.834452 91.620761) (xy 118.802899 91.512049)
				(xy 118.799 91.449) (xy 118.198 91.764) (xy 118.799 92.079) (xy 118.803756 92.009663) (xy 118.817044 91.950293)
				(xy 118.837444 91.901557) (xy 118.863462 91.864336) (xy 118.891726 91.84052) (xy 118.922426 91.828176)
				(xy 118.939 91.8265)
			)
		)
	)
	(zone
		(net 280)
		(net_name "/Misc/PWM_{A5V}")
		(layer "F.Cu")
		(name "$teardrop_padvia$")
		(hatch none 0.1)
		(priority 30005)
		(attr
			(teardrop
				(type padvia)
			)
		)
		(connect_pads yes
			(clearance 0)
		)
		(min_thickness 0.0254)
		(filled_areas_thickness no)
		(fill yes
			(thermal_gap 0.5)
			(thermal_bridge_width 0.5)
			(island_removal_mode 1)
			(island_area_min 10)
		)
		(polygon
			(pts
				(xy 258.683208 73.204379) (xy 258.702419 73.092884) (xy 258.764778 72.965774) (xy 258.879499 72.822593)
				(xy 259.052987 72.669697) (xy 259.28021 72.522375) (xy 259.339929 72.490568) (xy 258.620708 71.859)
				(xy 257.901487 72.490568) (xy 258.141707 72.635511) (xy 258.246958 72.716099) (xy 258.340522 72.800833)
				(xy 258.414618 72.881528) (xy 258.47516 72.96348) (xy 258.515847 73.035756) (xy 258.543531 73.107416)
				(xy 258.558208 73.204379)
			)
		)
	)
	(zone
		(net 252)
		(net_name "/Com Express 7 Interfaces/PCIe_{B2Bx4}.RX1-")
		(layer "F.Cu")
		(name "$teardrop_padvia$")
		(hatch none 0.1)
		(priority 31400)
		(attr
			(teardrop
				(type padvia)
			)
		)
		(connect_pads yes
			(clearance 0)
		)
		(min_thickness 0.0254)
		(filled_areas_thickness no)
		(fill yes
			(thermal_gap 0.5)
			(thermal_bridge_width 0.5)
			(island_removal_mode 1)
			(island_area_min 10)
		)
		(polygon
			(pts
				(xy 186.432504 124.2065) (xy 186.594035 124.201105) (xy 186.678445 124.197554) (xy 186.78014 124.202177)
				(xy 186.801 123.9815) (xy 186.651147 123.818268) (xy 186.597007 123.886935) (xy 186.587115 123.903393)
				(xy 186.562615 123.942065) (xy 186.533109 123.974279) (xy 186.491953 123.996327) (xy 186.432504 124.0045)
			)
		)
	)
	(zone
		(net 341)
		(net_name "/Com Express 7 MGMT/SPI.MOSI")
		(layer "F.Cu")
		(name "$teardrop_padvia$")
		(hatch none 0.1)
		(priority 31670)
		(attr
			(teardrop
				(type padvia)
			)
		)
		(connect_pads yes
			(clearance 0)
		)
		(min_thickness 0.0254)
		(filled_areas_thickness no)
		(fill yes
			(thermal_gap 0.5)
			(thermal_bridge_width 0.5)
			(island_removal_mode 1)
			(island_area_min 10)
		)
		(polygon
			(pts
				(xy 247.900677 159.935) (xy 247.830164 159.930171) (xy 247.778146 159.916371) (xy 247.689838 159.860433)
				(xy 247.625003 159.812919) (xy 247.499 160) (xy 247.625003 160.187081) (xy 247.689837 160.139568)
				(xy 247.774284 160.085196) (xy 247.827613 160.070243) (xy 247.900677 160.065)
			)
		)
	)
	(zone
		(net 73)
		(net_name "+3V3_AON")
		(layer "F.Cu")
		(name "$teardrop_padvia$")
		(hatch none 0.1)
		(priority 30454)
		(attr
			(teardrop
				(type padvia)
			)
		)
		(connect_pads yes
			(clearance 0)
		)
		(min_thickness 0.0254)
		(filled_areas_thickness no)
		(fill yes
			(thermal_gap 0.5)
			(thermal_bridge_width 0.5)
			(island_removal_mode 1)
			(island_area_min 10)
		)
		(polygon
			(pts
				(xy 247.492936 132.235452) (xy 247.56809 132.187867) (xy 247.686113 132.161953) (xy 247.849197 132.168928)
				(xy 247.884819 132.175) (xy 247.825707 131.879293) (xy 247.505 131.800074) (xy 247.499446 131.942747)
				(xy 247.45939 132.068257) (xy 247.404548 132.147064)
			)
		)
	)
	(zone
		(net 62)
		(net_name "+12V_AON")
		(layer "F.Cu")
		(name "$teardrop_padvia$")
		(hatch none 0.1)
		(priority 31278)
		(attr
			(teardrop
				(type padvia)
			)
		)
		(connect_pads yes
			(clearance 0)
		)
		(min_thickness 0.0254)
		(filled_areas_thickness no)
		(fill yes
			(thermal_gap 0.5)
			(thermal_bridge_width 0.5)
			(island_removal_mode 1)
			(island_area_min 10)
		)
		(polygon
			(pts
				(xy 186.60861 73.701486) (xy 186.603897 73.779397) (xy 186.59091 73.838181) (xy 186.548809 73.929211)
				(xy 186.50611 74.014384) (xy 186.70861 74.103163) (xy 186.91111 74.014384) (xy 186.868411 73.929213)
				(xy 186.825743 73.83638) (xy 186.813166 73.778241) (xy 186.80861 73.701486)
			)
		)
	)
	(zone
		(net 999)
		(net_name "Net-(C101-Pad1)")
		(layer "F.Cu")
		(name "$teardrop_padvia$")
		(hatch none 0.1)
		(priority 31104)
		(attr
			(teardrop
				(type padvia)
			)
		)
		(connect_pads yes
			(clearance 0)
		)
		(min_thickness 0.0254)
		(filled_areas_thickness no)
		(fill yes
			(thermal_gap 0.5)
			(thermal_bridge_width 0.5)
			(island_removal_mode 1)
			(island_area_min 10)
		)
		(polygon
			(pts
				(xy 247.287501 127.417001) (xy 247.267728 127.476413) (xy 247.204454 127.532497) (xy 247.155829 127.554199)
				(xy 247.09647 127.568873) (xy 247.084501 127.570653) (xy 247.350001 127.831001) (xy 247.615501 127.570653)
				(xy 247.555363 127.557804) (xy 247.505479 127.53787) (xy 247.465359 127.511945) (xy 247.436346 127.482125)
				(xy 247.418855 127.450707) (xy 247.412522 127.418896) (xy 247.412501 127.417001)
			)
		)
	)
	(zone
		(net 753)
		(net_name "Net-(U45C-CLKOUTB-)")
		(layer "F.Cu")
		(name "$teardrop_padvia$")
		(hatch none 0.1)
		(priority 31469)
		(attr
			(teardrop
				(type padvia)
			)
		)
		(connect_pads yes
			(clearance 0)
		)
		(min_thickness 0.0254)
		(filled_areas_thickness no)
		(fill yes
			(thermal_gap 0.5)
			(thermal_bridge_width 0.5)
			(island_removal_mode 1)
			(island_area_min 10)
		)
		(polygon
			(pts
				(xy 138.560607 140.501005) (xy 138.506866 140.547948) (xy 138.459353 140.576167) (xy 138.372203 140.598018)
				(xy 138.341545 140.601163) (xy 138.241227 140.614804) (xy 138.289293 140.860707) (xy 138.535196 140.908773)
				(xy 138.548837 140.808455) (xy 138.568924 140.702345) (xy 138.597485 140.649517) (xy 138.648995 140.589393)
			)
		)
	)
	(zone
		(net 981)
		(net_name "Net-(D28-C)")
		(layer "F.Cu")
		(name "$teardrop_padvia$")
		(hatch none 0.1)
		(priority 30883)
		(attr
			(teardrop
				(type padvia)
			)
		)
		(connect_pads yes
			(clearance 0)
		)
		(min_thickness 0.0254)
		(filled_areas_thickness no)
		(fill yes
			(thermal_gap 0.5)
			(thermal_bridge_width 0.5)
			(island_removal_mode 1)
			(island_area_min 10)
		)
		(polygon
			(pts
				(xy 197.60861 76.259163) (xy 197.602838 76.2999) (xy 197.582434 76.341815) (xy 197.555259 76.370116)
				(xy 197.515713 76.393544) (xy 197.44311 76.412815) (xy 197.70861 76.673163) (xy 197.97411 76.412815)
				(xy 197.920968 76.400948) (xy 197.879929 76.382501) (xy 197.828228 76.331827) (xy 197.808892 76.268258)
				(xy 197.80861 76.259163)
			)
		)
	)
	(zone
		(net 585)
		(net_name "Net-(U21-FB)")
		(layer "F.Cu")
		(name "$teardrop_padvia$")
		(hatch none 0.1)
		(priority 30459)
		(attr
			(teardrop
				(type padvia)
			)
		)
		(connect_pads yes
			(clearance 0)
		)
		(min_thickness 0.0254)
		(filled_areas_thickness no)
		(fill yes
			(thermal_gap 0.5)
			(thermal_bridge_width 0.5)
			(island_removal_mode 1)
			(island_area_min 10)
		)
		(polygon
			(pts
				(xy 314.355061 97.63445) (xy 314.410692 97.718418) (xy 314.432081 97.778653) (xy 314.445572 97.847562)
				(xy 314.445499 97.987058) (xy 314.766206 97.917207) (xy 314.833425 97.6215) (xy 314.742659 97.630094)
				(xy 314.6593 97.62833) (xy 314.586322 97.617184) (xy 314.523236 97.597319) (xy 314.443449 97.546062)
			)
		)
	)
	(zone
		(net 239)
		(net_name "/Com Express 7 Interfaces/PCIe_{B2Bx4}.RX3+")
		(layer "F.Cu")
		(name "$teardrop_padvia$")
		(hatch none 0.1)
		(priority 31369)
		(attr
			(teardrop
				(type padvia)
			)
		)
		(connect_pads yes
			(clearance 0)
		)
		(min_thickness 0.0254)
		(filled_areas_thickness no)
		(fill yes
			(thermal_gap 0.5)
			(thermal_bridge_width 0.5)
			(island_removal_mode 1)
			(island_area_min 10)
		)
		(polygon
			(pts
				(xy 186.432504 127.6955) (xy 186.47929 127.700235) (xy 186.514742 127.713379) (xy 186.562939 127.758387)
				(xy 186.587116 127.796608) (xy 186.614485 127.839773) (xy 186.651147 127.881731) (xy 186.801 127.7185)
				(xy 186.78014 127.497823) (xy 186.679466 127.502452) (xy 186.596096 127.499019) (xy 186.594035 127.498895)
				(xy 186.432504 127.4935)
			)
		)
	)
	(zone
		(net 1)
		(net_name "GND")
		(layer "F.Cu")
		(name "$teardrop_padvia$")
		(hatch none 0.1)
		(priority 31059)
		(attr
			(teardrop
				(type padvia)
			)
		)
		(connect_pads yes
			(clearance 0)
		)
		(min_thickness 0.0254)
		(filled_areas_thickness no)
		(fill yes
			(thermal_gap 0.5)
			(thermal_bridge_width 0.5)
			(island_removal_mode 1)
			(island_area_min 10)
		)
		(polygon
			(pts
				(xy 306.7125 154.723) (xy 306.732273 154.663588) (xy 306.795547 154.607503) (xy 306.844172 154.585801)
				(xy 306.903532 154.571127) (xy 306.9155 154.569347) (xy 306.65 154.309) (xy 306.3845 154.569347)
				(xy 306.444639 154.582197) (xy 306.494523 154.602131) (xy 306.534642 154.628056) (xy 306.563655 154.657876)
				(xy 306.581146 154.689294) (xy 306.587479 154.721105) (xy 306.5875 154.723)
			)
		)
	)
	(zone
		(net 2)
		(net_name "+3V3")
		(layer "F.Cu")
		(name "$teardrop_padvia$")
		(hatch none 0.1)
		(priority 30876)
		(attr
			(teardrop
				(type padvia)
			)
		)
		(connect_pads yes
			(clearance 0)
		)
		(min_thickness 0.0254)
		(filled_areas_thickness no)
		(fill yes
			(thermal_gap 0.5)
			(thermal_bridge_width 0.5)
			(island_removal_mode 1)
			(island_area_min 10)
		)
		(polygon
			(pts
				(xy 159.65 157.703) (xy 159.655772 157.662263) (xy 159.676176 157.620348) (xy 159.703351 157.592047)
				(xy 159.742897 157.568618) (xy 159.8155 157.549347) (xy 159.55 157.289) (xy 159.2845 157.549347)
				(xy 159.337642 157.561214) (xy 159.378681 157.579662) (xy 159.430382 157.630336) (xy 159.449718 157.693905)
				(xy 159.45 157.703)
			)
		)
	)
	(zone
		(net 431)
		(net_name "/2xSFP+/MOD0_ABS")
		(layer "F.Cu")
		(name "$teardrop_padvia$")
		(hatch none 0.1)
		(priority 31589)
		(attr
			(teardrop
				(type padvia)
			)
		)
		(connect_pads yes
			(clearance 0)
		)
		(min_thickness 0.0254)
		(filled_areas_thickness no)
		(fill yes
			(thermal_gap 0.5)
			(thermal_bridge_width 0.5)
			(island_removal_mode 1)
			(island_area_min 10)
		)
		(polygon
			(pts
				(xy 200.835873 154.752515) (xy 200.890694 154.704284) (xy 200.938784 154.67404) (xy 201.027562 154.642265)
				(xy 201.148238 154.598167) (xy 201.050707 154.399293) (xy 200.829323 154.356105) (xy 200.82124 154.470636)
				(xy 200.812848 154.564051) (xy 200.790833 154.611503) (xy 200.747485 154.664127)
			)
		)
	)
	(zone
		(net 122)
		(net_name "/2xSFP+/KR to SFI #2/KR_C.TX-")
		(layer "F.Cu")
		(name "$teardrop_padvia$")
		(hatch none 0.1)
		(priority 31164)
		(attr
			(teardrop
				(type padvia)
			)
		)
		(connect_pads yes
			(clearance 0)
		)
		(min_thickness 0.0254)
		(filled_areas_thickness no)
		(fill yes
			(thermal_gap 0.5)
			(thermal_bridge_width 0.5)
			(island_removal_mode 1)
			(island_area_min 10)
		)
		(polygon
			(pts
				(xy 138.06 143.17679) (xy 138.064788 143.139695) (xy 138.078304 143.115431) (xy 138.120007 143.096705)
				(xy 138.208927 143.101889) (xy 138.274222 143.108714) (xy 138.338773 143.105196) (xy 138.29 142.859)
				(xy 138.044804 142.811227) (xy 138.008876 142.909201) (xy 137.972391 142.964616) (xy 137.922365 143.048601)
				(xy 137.906125 143.104227) (xy 137.9 143.17679)
			)
		)
	)
	(zone
		(net 2)
		(net_name "+3V3")
		(layer "F.Cu")
		(name "$teardrop_padvia$")
		(hatch none 0.1)
		(priority 31539)
		(attr
			(teardrop
				(type padvia)
			)
		)
		(connect_pads yes
			(clearance 0)
		)
		(min_thickness 0.0254)
		(filled_areas_thickness no)
		(fill yes
			(thermal_gap 0.5)
			(thermal_bridge_width 0.5)
			(island_removal_mode 1)
			(island_area_min 10)
		)
		(polygon
			(pts
				(xy 262.0625 93.722) (xy 262.082545 93.670069) (xy 262.108406 93.646949) (xy 262.144879 93.628433)
				(xy 262.2475 93.612) (xy 262 93.336) (xy 261.7525 93.612) (xy 261.810882 93.616701) (xy 261.85818 93.629606)
				(xy 261.894425 93.648916) (xy 261.919668 93.672838) (xy 261.9375 93.722)
			)
		)
	)
	(zone
		(net 2)
		(net_name "+3V3")
		(layer "F.Cu")
		(name "$teardrop_padvia$")
		(hatch none 0.1)
		(priority 31993)
		(attr
			(teardrop
				(type padvia)
			)
		)
		(connect_pads yes
			(clearance 0)
		)
		(min_thickness 0.0254)
		(filled_areas_thickness no)
		(fill yes
			(thermal_gap 0.5)
			(thermal_bridge_width 0.5)
			(island_removal_mode 1)
			(island_area_min 10)
		)
		(polygon
			(pts
				(xy 159.45 158.2095) (xy 159.456845 158.229356) (xy 159.465949 158.260994) (xy 159.458878 158.274569)
				(xy 159.437177 158.283984) (xy 159.548 158.673) (xy 159.662158 158.288976) (xy 159.641122 158.278773)
				(xy 159.633851 158.264823) (xy 159.643017 158.230543) (xy 159.65 158.2095)
			)
		)
	)
	(zone
		(net 1)
		(net_name "GND")
		(layer "F.Cu")
		(name "$teardrop_padvia$")
		(hatch none 0.1)
		(priority 31921)
		(attr
			(teardrop
				(type padvia)
			)
		)
		(connect_pads yes
			(clearance 0)
		)
		(min_thickness 0.0254)
		(filled_areas_thickness no)
		(fill yes
			(thermal_gap 0.5)
			(thermal_bridge_width 0.5)
			(island_removal_mode 1)
			(island_area_min 10)
		)
		(polygon
			(pts
				(xy 107.7 152.168) (xy 107.699847 152.157885) (xy 107.70046 152.127168) (xy 107.708782 152.09468)
				(xy 107.732675 152.065525) (xy 107.78 152.044808) (xy 107.6 151.812) (xy 107.42 152.044808) (xy 107.455901 152.058167)
				(xy 107.479199 152.076398) (xy 107.498899 152.121724) (xy 107.500153 152.157885) (xy 107.5 152.168)
			)
		)
	)
	(zone
		(net 314)
		(net_name "/2xUSB3.0+RJ45/FLG_1")
		(layer "F.Cu")
		(name "$teardrop_padvia$")
		(hatch none 0.1)
		(priority 31584)
		(attr
			(teardrop
				(type padvia)
			)
		)
		(connect_pads yes
			(clearance 0)
		)
		(min_thickness 0.0254)
		(filled_areas_thickness no)
		(fill yes
			(thermal_gap 0.5)
			(thermal_bridge_width 0.5)
			(island_removal_mode 1)
			(island_area_min 10)
		)
		(polygon
			(pts
				(xy 122.930677 92.9375) (xy 122.872721 92.932758) (xy 122.828721 92.919566) (xy 122.765827 92.874553)
				(xy 122.743241 92.85115) (xy 122.655003 92.772919) (xy 122.529 92.96) (xy 122.598622 93.170434)
				(xy 122.715668 93.118173) (xy 122.802402 93.078976) (xy 122.857895 93.066939) (xy 122.930677 93.0625)
			)
		)
	)
	(zone
		(net 2)
		(net_name "+3V3")
		(layer "F.Cu")
		(name "$teardrop_padvia$")
		(hatch none 0.1)
		(priority 30457)
		(attr
			(teardrop
				(type padvia)
			)
		)
		(connect_pads yes
			(clearance 0)
		)
		(min_thickness 0.0254)
		(filled_areas_thickness no)
		(fill yes
			(thermal_gap 0.5)
			(thermal_bridge_width 0.5)
			(island_removal_mode 1)
			(island_area_min 10)
		)
		(polygon
			(pts
				(xy 259.168708 78.273) (xy 259.096438 78.286703) (xy 258.99509 78.30478) (xy 258.946176 78.297614)
				(xy 258.903208 78.27) (xy 258.729708 78.565) (xy 259.044816 78.742118) (xy 259.050683 78.677808)
				(xy 259.06428 78.632235) (xy 259.082077 78.604024) (xy 259.1034 78.586522) (xy 259.155944 78.573252)
				(xy 259.168708 78.573)
			)
		)
	)
	(zone
		(net 401)
		(net_name "/Com Express 7 MGMT/FAM_TACH")
		(layer "F.Cu")
		(name "$teardrop_padvia$")
		(hatch none 0.1)
		(priority 30914)
		(attr
			(teardrop
				(type padvia)
			)
		)
		(connect_pads yes
			(clearance 0)
		)
		(min_thickness 0.0254)
		(filled_areas_thickness no)
		(fill yes
			(thermal_gap 0.5)
			(thermal_bridge_width 0.5)
			(island_removal_mode 1)
			(island_area_min 10)
		)
		(polygon
			(pts
				(xy 238.562001 79.1345) (xy 238.60819 79.139825) (xy 238.660045 79.157098) (xy 238.705062 79.183626)
				(xy 238.745045 79.222162) (xy 238.771055 79.263772) (xy 239.001001 78.98) (xy 238.691229 78.776054)
				(xy 238.683705 78.84836) (xy 238.66798 78.908257) (xy 238.646505 78.953269) (xy 238.619962 78.985555)
				(xy 238.592966 79.003086) (xy 238.563737 79.009481) (xy 238.562001 79.0095)
			)
		)
	)
	(zone
		(net 628)
		(net_name "/PCIe redriver/TX_SW")
		(layer "F.Cu")
		(name "$teardrop_padvia$")
		(hatch none 0.1)
		(priority 30964)
		(attr
			(teardrop
				(type padvia)
			)
		)
		(connect_pads yes
			(clearance 0)
		)
		(min_thickness 0.0254)
		(filled_areas_thickness no)
		(fill yes
			(thermal_gap 0.5)
			(thermal_bridge_width 0.5)
			(island_removal_mode 1)
			(island_area_min 10)
		)
		(polygon
			(pts
				(xy 113.962 143.9425) (xy 114.024866 143.962469) (xy 114.056844 143.988921) (xy 114.085358 144.026332)
				(xy 114.107882 144.073527) (xy 114.123093 144.131167) (xy 114.123202 144.131798) (xy 114.401 143.88)
				(xy 114.123202 143.628202) (xy 114.108905 143.683635) (xy 114.087825 143.72952) (xy 114.06046 143.767201)
				(xy 114.029552 143.794434) (xy 113.996265 143.811472) (xy 113.963434 143.817489) (xy 113.962 143.8175)
			)
		)
	)
	(zone
		(net 221)
		(net_name "/Com Express 7 Interfaces/PCIe_{B1x4}.RX0-")
		(layer "F.Cu")
		(name "$teardrop_padvia$")
		(hatch none 0.1)
		(priority 30269)
		(attr
			(teardrop
				(type padvia)
			)
		)
		(connect_pads yes
			(clearance 0)
		)
		(min_thickness 0.0254)
		(filled_areas_thickness no)
		(fill yes
			(thermal_gap 0.5)
			(thermal_bridge_width 0.5)
			(island_removal_mode 1)
			(island_area_min 10)
		)
		(polygon
			(pts
				(xy 209.8685 162.2) (xy 209.879599 162.373112) (xy 209.894216 162.60051) (xy 209.891181 162.735138)
				(xy 209.875 162.887021) (xy 210.025 163.136) (xy 210.108295 162.26) (xy 210.077864 162.255523) (xy 210.065097 162.244185)
				(xy 210.06742 162.214227) (xy 210.0705 162.2)
			)
		)
	)
	(zone
		(net 1)
		(net_name "GND")
		(layer "F.Cu")
		(name "$teardrop_padvia$")
		(hatch none 0.1)
		(priority 31225)
		(attr
			(teardrop
				(type padvia)
			)
		)
		(connect_pads yes
			(clearance 0)
		)
		(min_thickness 0.0254)
		(filled_areas_thickness no)
		(fill yes
			(thermal_gap 0.5)
			(thermal_bridge_width 0.5)
			(island_removal_mode 1)
			(island_area_min 10)
		)
		(polygon
			(pts
				(xy 217.125 167.950677) (xy 217.129737 167.859676) (xy 217.142896 167.792587) (xy 217.175418 167.705855)
				(xy 217.207644 167.625358) (xy 217 167.549) (xy 216.803541 167.652363) (xy 216.855343 167.735863)
				(xy 216.904833 167.821955) (xy 216.919614 167.87716) (xy 216.925 167.950677)
			)
		)
	)
	(zone
		(net 725)
		(net_name "/2xSFP+/KR to SFI #1/TCK")
		(layer "F.Cu")
		(name "$teardrop_padvia$")
		(hatch none 0.1)
		(priority 31710)
		(attr
			(teardrop
				(type padvia)
			)
		)
		(connect_pads yes
			(clearance 0)
		)
		(min_thickness 0.0254)
		(filled_areas_thickness no)
		(fill yes
			(thermal_gap 0.5)
			(thermal_bridge_width 0.5)
			(island_removal_mode 1)
			(island_area_min 10)
		)
		(polygon
			(pts
				(xy 152.3875 130.109323) (xy 152.382682 130.178763) (xy 152.36896 130.230087) (xy 152.322245 130.305628)
				(xy 152.312702 130.317768) (xy 152.262919 130.384997) (xy 152.45 130.511) (xy 152.637081 130.384997)
				(xy 152.587299 130.317769) (xy 152.532894 130.234603) (xy 152.51781 130.181748) (xy 152.5125 130.109323)
			)
		)
	)
	(zone
		(net 2)
		(net_name "+3V3")
		(layer "F.Cu")
		(name "$teardrop_padvia$")
		(hatch none 0.1)
		(priority 31508)
		(attr
			(teardrop
				(type padvia)
			)
		)
		(connect_pads yes
			(clearance 0)
		)
		(min_thickness 0.0254)
		(filled_areas_thickness no)
		(fill yes
			(thermal_gap 0.5)
			(thermal_bridge_width 0.5)
			(island_removal_mode 1)
			(island_area_min 10)
		)
		(polygon
			(pts
				(xy 215.78 131.456409) (xy 215.775249 131.492747) (xy 215.761995 131.517786) (xy 215.718659 131.543106)
				(xy 215.665187 131.552822) (xy 215.610683 131.562249) (xy 215.558646 131.583164) (xy 215.677 131.774)
				(xy 215.897677 131.804751) (xy 215.929057 131.688082) (xy 215.937584 131.666541) (xy 215.966868 131.580373)
				(xy 215.98 131.456409)
			)
		)
	)
	(zone
		(net 78)
		(net_name "+1V8")
		(layer "F.Cu")
		(name "$teardrop_padvia$")
		(hatch none 0.1)
		(priority 31247)
		(attr
			(teardrop
				(type padvia)
			)
		)
		(connect_pads yes
			(clearance 0)
		)
		(min_thickness 0.0254)
		(filled_areas_thickness no)
		(fill yes
			(thermal_gap 0.5)
			(thermal_bridge_width 0.5)
			(island_removal_mode 1)
			(island_area_min 10)
		)
		(polygon
			(pts
				(xy 200.207933 72.902163) (xy 200.285845 72.906876) (xy 200.34463 72.919863) (xy 200.435661 72.961965)
				(xy 200.520832 73.004663) (xy 200.60961 72.802163) (xy 200.520832 72.599663) (xy 200.43566 72.642362)
				(xy 200.342827 72.68503) (xy 200.284688 72.697607) (xy 200.207933 72.702163)
			)
		)
	)
	(zone
		(net 709)
		(net_name "Net-(U37-SCLK)")
		(layer "F.Cu")
		(name "$teardrop_padvia$")
		(hatch none 0.1)
		(priority 32104)
		(attr
			(teardrop
				(type padvia)
			)
		)
		(connect_pads yes
			(clearance 0)
		)
		(min_thickness 0.0254)
		(filled_areas_thickness no)
		(fill yes
			(thermal_gap 0.5)
			(thermal_bridge_width 0.5)
			(island_removal_mode 1)
			(island_area_min 10)
		)
		(polygon
			(pts
				(xy 214.2175 125.834) (xy 214.218952 125.845797) (xy 214.219129 125.874081) (xy 214.210153 125.886652)
				(xy 214.19 125.895596) (xy 214.28 126.25) (xy 214.37 125.895596) (xy 214.349044 125.885992) (xy 214.34037 125.872447)
				(xy 214.341048 125.845797) (xy 214.3425 125.834)
			)
		)
	)
	(zone
		(net 62)
		(net_name "+12V_AON")
		(layer "F.Cu")
		(name "$teardrop_padvia$")
		(hatch none 0.1)
		(priority 31256)
		(attr
			(teardrop
				(type padvia)
			)
		)
		(connect_pads yes
			(clearance 0)
		)
		(min_thickness 0.0254)
		(filled_areas_thickness no)
		(fill yes
			(thermal_gap 0.5)
			(thermal_bridge_width 0.5)
			(island_removal_mode 1)
			(island_area_min 10)
		)
		(polygon
			(pts
				(xy 198.83361 69.95284) (xy 198.838323 69.874927) (xy 198.85131 69.816143) (xy 198.893412 69.72511)
				(xy 198.93611 69.639941) (xy 198.73361 69.551163) (xy 198.53111 69.639941) (xy 198.573808 69.725112)
				(xy 198.616477 69.817946) (xy 198.629054 69.876085) (xy 198.63361 69.95284)
			)
		)
	)
	(zone
		(net 950)
		(net_name "/2xSFP+/KR to SFI #2/SFI_R.RX+")
		(layer "F.Cu")
		(name "$teardrop_padvia$")
		(hatch none 0.1)
		(priority 31179)
		(attr
			(teardrop
				(type padvia)
			)
		)
		(connect_pads yes
			(clearance 0)
		)
		(min_thickness 0.0254)
		(filled_areas_thickness no)
		(fill yes
			(thermal_gap 0.5)
			(thermal_bridge_width 0.5)
			(island_removal_mode 1)
			(island_area_min 10)
		)
		(polygon
			(pts
				(xy 131.68 143.17679) (xy 131.675347 143.112802) (xy 131.662777 143.062121) (xy 131.618645 142.980204)
				(xy 131.607609 142.964616) (xy 131.566024 142.899819) (xy 131.535196 142.811227) (xy 131.29 142.859)
				(xy 131.241227 143.105196) (xy 131.328185 143.107002) (xy 131.371073 143.101889) (xy 131.428443 143.095867)
				(xy 131.475848 143.099993) (xy 131.508097 143.123792) (xy 131.52 143.17679)
			)
		)
	)
	(zone
		(net 116)
		(net_name "/2xSFP+/KR to SFI #2/REFCLK+")
		(layer "F.Cu")
		(name "$teardrop_padvia$")
		(hatch none 0.1)
		(priority 31172)
		(attr
			(teardrop
				(type padvia)
			)
		)
		(connect_pads yes
			(clearance 0)
		)
		(min_thickness 0.0254)
		(filled_areas_thickness no)
		(fill yes
			(thermal_gap 0.5)
			(thermal_bridge_width 0.5)
			(island_removal_mode 1)
			(island_area_min 10)
		)
		(polygon
			(pts
				(xy 126.97321 141.25) (xy 127.037198 141.245347) (xy 127.087878 141.232777) (xy 127.169795 141.188645)
				(xy 127.185383 141.17761) (xy 127.25018 141.136024) (xy 127.338773 141.105196) (xy 127.291 140.86)
				(xy 127.044804 140.811227) (xy 127.042997 140.898185) (xy 127.04811 140.941074) (xy 127.054133 140.998444)
				(xy 127.050007 141.045848) (xy 127.026207 141.078097) (xy 126.97321 141.09)
			)
		)
	)
	(zone
		(net 623)
		(net_name "/PCIe redriver/TX_EQ0")
		(layer "F.Cu")
		(name "$teardrop_padvia$")
		(hatch none 0.1)
		(priority 31128)
		(attr
			(teardrop
				(type padvia)
			)
		)
		(connect_pads yes
			(clearance 0)
		)
		(min_thickness 0.0254)
		(filled_areas_thickness no)
		(fill yes
			(thermal_gap 0.5)
			(thermal_bridge_width 0.5)
			(island_removal_mode 1)
			(island_area_min 10)
		)
		(polygon
			(pts
				(xy 112.007 148.9225) (xy 112.066412 148.942273) (xy 112.122497 149.005547) (xy 112.144199 149.054172)
				(xy 112.158873 149.113531) (xy 112.160653 149.1255) (xy 112.421 148.86) (xy 112.160653 148.5945)
				(xy 112.147804 148.654638) (xy 112.12787 148.704522) (xy 112.101945 148.744641) (xy 112.072125 148.773654)
				(xy 112.040707 148.791146) (xy 112.008896 148.797479) (xy 112.007 148.7975)
			)
		)
	)
	(zone
		(net 648)
		(net_name "/2xSFP+/KR to SFI #1/MDIO_R")
		(layer "F.Cu")
		(name "$teardrop_padvia$")
		(hatch none 0.1)
		(priority 30346)
		(attr
			(teardrop
				(type padvia)
			)
		)
		(connect_pads yes
			(clearance 0)
		)
		(min_thickness 0.0254)
		(filled_areas_thickness no)
		(fill yes
			(thermal_gap 0.5)
			(thermal_bridge_width 0.5)
			(island_removal_mode 1)
			(island_area_min 10)
		)
		(polygon
			(pts
				(xy 141.8275 150.594) (xy 141.821719 150.627863) (xy 141.801254 150.662486) (xy 141.774188 150.684307)
				(xy 141.734849 150.7) (xy 141.719289 150.703289) (xy 141.89 151.41) (xy 142.060711 150.703289) (xy 142.02049 150.6917)
				(xy 141.991017 150.674116) (xy 141.957827 150.626533) (xy 141.9525 150.594)
			)
		)
	)
	(zone
		(net 645)
		(net_name "Net-(U41-IO0_6)")
		(layer "F.Cu")
		(name "$teardrop_padvia$")
		(hatch none 0.1)
		(priority 31097)
		(attr
			(teardrop
				(type padvia)
			)
		)
		(connect_pads yes
			(clearance 0)
		)
		(min_thickness 0.0254)
		(filled_areas_thickness no)
		(fill yes
			(thermal_gap 0.5)
			(thermal_bridge_width 0.5)
			(island_removal_mode 1)
			(island_area_min 10)
		)
		(polygon
			(pts
				(xy 129.0875 88.617001) (xy 129.067727 88.676413) (xy 129.004453 88.732497) (xy 128.955828 88.754199)
				(xy 128.896469 88.768873) (xy 128.8845 88.770653) (xy 129.15 89.031001) (xy 129.4155 88.770653)
				(xy 129.355362 88.757804) (xy 129.305478 88.73787) (xy 129.265358 88.711945) (xy 129.236345 88.682125)
				(xy 129.218854 88.650707) (xy 129.212521 88.618896) (xy 129.2125 88.617001)
			)
		)
	)
	(zone
		(net 698)
		(net_name "Net-(U5-IO0_7)")
		(layer "F.Cu")
		(name "$teardrop_padvia$")
		(hatch none 0.1)
		(priority 31662)
		(attr
			(teardrop
				(type padvia)
			)
		)
		(connect_pads yes
			(clearance 0)
		)
		(min_thickness 0.0254)
		(filled_areas_thickness no)
		(fill yes
			(thermal_gap 0.5)
			(thermal_bridge_width 0.5)
			(island_removal_mode 1)
			(island_area_min 10)
		)
		(polygon
			(pts
				(xy 158.4875 162.992166) (xy 158.492011 163.109486) (xy 158.503585 163.192236) (xy 158.509585 163.223869)
				(xy 158.529323 163.340279) (xy 158.75 163.311) (xy 158.869679 163.120713) (xy 158.799238 163.095172)
				(xy 158.73759 163.088649) (xy 158.689314 163.083904) (xy 158.649507 163.071525) (xy 158.622468 163.043588)
				(xy 158.6125 162.992166)
			)
		)
	)
	(zone
		(net 981)
		(net_name "Net-(D28-C)")
		(layer "F.Cu")
		(name "$teardrop_padvia$")
		(hatch none 0.1)
		(priority 30154)
		(attr
			(teardrop
				(type padvia)
			)
		)
		(connect_pads yes
			(clearance 0)
		)
		(min_thickness 0.0254)
		(filled_areas_thickness no)
		(fill yes
			(thermal_gap 0.5)
			(thermal_bridge_width 0.5)
			(island_removal_mode 1)
			(island_area_min 10)
		)
		(polygon
			(pts
				(xy 197.80861 76.062163) (xy 197.81367 76.028644) (xy 197.829091 75.995738) (xy 197.854873 75.965425)
				(xy 197.891483 75.938919) (xy 197.938658 75.918016) (xy 197.997093 75.90393) (xy 198.06861 75.898184)
				(xy 197.70861 75.501163) (xy 197.34861 75.898184) (xy 197.418681 75.903704) (xy 197.477217 75.917567)
				(xy 197.524564 75.938253) (xy 197.561037 75.964231) (xy 197.58712 75.9942) (xy 197.602852 76.026426)
				(xy 197.60861 76.062163)
			)
		)
	)
	(zone
		(net 85)
		(net_name "/Com Express 7 MGMT/MAFS_POWER")
		(layer "F.Cu")
		(name "$teardrop_padvia$")
		(hatch none 0.1)
		(priority 30748)
		(attr
			(teardrop
				(type padvia)
			)
		)
		(connect_pads yes
			(clearance 0)
		)
		(min_thickness 0.0254)
		(filled_areas_thickness no)
		(fill yes
			(thermal_gap 0.5)
			(thermal_bridge_width 0.5)
			(island_removal_mode 1)
			(island_area_min 10)
		)
		(polygon
			(pts
				(xy 259.27 161.973) (xy 259.269663 161.95791) (xy 259.27024 161.917674) (xy 259.282054 161.87613)
				(xy 259.316633 161.840835) (xy 259.3855 161.819347) (xy 259.12 161.559) (xy 258.8545 161.819347)
				(xy 258.900938 161.830291) (xy 258.933135 161.847391) (xy 258.964578 161.891856) (xy 258.970337 161.95791)
				(xy 258.97 161.973)
			)
		)
	)
	(zone
		(net 78)
		(net_name "+1V8")
		(layer "F.Cu")
		(name "$teardrop_padvia$")
		(hatch none 0.1)
		(priority 30848)
		(attr
			(teardrop
				(type padvia)
			)
		)
		(connect_pads yes
			(clearance 0)
		)
		(min_thickness 0.0254)
		(filled_areas_thickness no)
		(fill yes
			(thermal_gap 0.5)
			(thermal_bridge_width 0.5)
			(island_removal_mode 1)
			(island_area_min 10)
		)
		(polygon
			(pts
				(xy 199.11 83.818) (xy 199.11621 83.771789) (xy 199.139677 83.72339) (xy 199.167584 83.695034) (xy 199.20781 83.671988)
				(xy 199.261798 83.656798) (xy 199.01 83.379) (xy 198.758202 83.656798) (xy 198.807054 83.669931)
				(xy 198.844564 83.689335) (xy 198.891987 83.741945) (xy 198.909743 83.808446) (xy 198.91 83.818)
			)
		)
	)
	(zone
		(net 780)
		(net_name "/Misc/TACH_{A3V3}")
		(layer "F.Cu")
		(name "$teardrop_padvia$")
		(hatch none 0.1)
		(priority 30355)
		(attr
			(teardrop
				(type padvia)
			)
		)
		(connect_pads yes
			(clearance 0)
		)
		(min_thickness 0.0254)
		(filled_areas_thickness no)
		(fill yes
			(thermal_gap 0.5)
			(thermal_bridge_width 0.5)
			(island_removal_mode 1)
			(island_area_min 10)
		)
		(polygon
			(pts
				(xy 263.766708 79.1345) (xy 263.800571 79.140281) (xy 263.835192 79.160745) (xy 263.857014 79.18781)
				(xy 263.872708 79.22715) (xy 263.875997 79.242711) (xy 264.582708 79.072) (xy 263.875997 78.901289)
				(xy 263.864408 78.94151) (xy 263.846824 78.970984) (xy 263.799242 79.004173) (xy 263.766708 79.0095)
			)
		)
	)
	(zone
		(net 945)
		(net_name "/GPIO expander/GPIOEX5")
		(layer "F.Cu")
		(name "$teardrop_padvia$")
		(hatch none 0.1)
		(priority 31676)
		(attr
			(teardrop
				(type padvia)
			)
		)
		(connect_pads yes
			(clearance 0)
		)
		(min_thickness 0.0254)
		(filled_areas_thickness no)
		(fill yes
			(thermal_gap 0.5)
			(thermal_bridge_width 0.5)
			(island_removal_mode 1)
			(island_area_min 10)
		)
		(polygon
			(pts
				(xy 122.491185 147.349573) (xy 122.51271 147.377855) (xy 122.519149 147.403316) (xy 122.501376 147.444453)
				(xy 122.445806 147.494317) (xy 122.401147 147.531664) (xy 122.362919 147.574997) (xy 122.550707 147.700707)
				(xy 122.737081 147.574997) (xy 122.690118 147.477297) (xy 122.679033 147.438283) (xy 122.65052 147.355954)
				(xy 122.623083 147.311202) (xy 122.579573 147.261185)
			)
		)
	)
	(zone
		(net 195)
		(net_name "/OCuLink/PCIe_{x4}.RX2-")
		(layer "F.Cu")
		(name "$teardrop_padvia$")
		(hatch none 0.1)
		(priority 32076)
		(attr
			(teardrop
				(type padvia)
			)
		)
		(connect_pads yes
			(clearance 0)
		)
		(min_thickness 0.0254)
		(filled_areas_thickness no)
		(fill yes
			(thermal_gap 0.5)
			(thermal_bridge_width 0.5)
			(island_removal_mode 1)
			(island_area_min 10)
		)
		(polygon
			(pts
				(xy 107.999 152.26) (xy 108.006198 152.280648) (xy 108.015792 152.312984) (xy 108.008965 152.327007)
				(xy 107.9875 152.336995) (xy 108.1 152.586) (xy 108.2125 152.336995) (xy 108.191324 152.327271)
				(xy 108.184269 152.313643) (xy 108.193802 152.280648) (xy 108.201 152.26)
			)
		)
	)
	(zone
		(net 646)
		(net_name "Net-(U41-IO0_7)")
		(layer "F.Cu")
		(name "$teardrop_padvia$")
		(hatch none 0.1)
		(priority 31141)
		(attr
			(teardrop
				(type padvia)
			)
		)
		(connect_pads yes
			(clearance 0)
		)
		(min_thickness 0.0254)
		(filled_areas_thickness no)
		(fill yes
			(thermal_gap 0.5)
			(thermal_bridge_width 0.5)
			(island_removal_mode 1)
			(island_area_min 10)
		)
		(polygon
			(pts
				(xy 130.087501 88.617) (xy 130.067728 88.676411) (xy 130.004454 88.732496) (xy 129.955829 88.754198)
				(xy 129.896469 88.768871) (xy 129.8845 88.770652) (xy 130.15 89.030999) (xy 130.4155 88.770653)
				(xy 130.355362 88.757804) (xy 130.305478 88.73787) (xy 130.265358 88.711945) (xy 130.236345 88.682125)
				(xy 130.218854 88.650707) (xy 130.212521 88.618896) (xy 130.2125 88.617001)
			)
		)
	)
	(zone
		(net 338)
		(net_name "/Com Express 7 MGMT/SPI.MISO")
		(layer "F.Cu")
		(name "$teardrop_padvia$")
		(hatch none 0.1)
		(priority 31671)
		(attr
			(teardrop
				(type padvia)
			)
		)
		(connect_pads yes
			(clearance 0)
		)
		(min_thickness 0.0254)
		(filled_areas_thickness no)
		(fill yes
			(thermal_gap 0.5)
			(thermal_bridge_width 0.5)
			(island_removal_mode 1)
			(island_area_min 10)
		)
		(polygon
			(pts
				(xy 257.520717 162.762641) (xy 257.567163 162.815916) (xy 257.594186 162.862456) (xy 257.617075 162.964452)
				(xy 257.629323 163.043895) (xy 257.850707 163.000707) (xy 257.893895 162.779323) (xy 257.814452 162.767075)
				(xy 257.716294 162.745808) (xy 257.668012 162.718673) (xy 257.612641 162.670717)
			)
		)
	)
	(zone
		(net 1)
		(net_name "GND")
		(layer "F.Cu")
		(name "$teardrop_padvia$")
		(hatch none 0.1)
		(priority 30894)
		(attr
			(teardrop
				(type padvia)
			)
		)
		(connect_pads yes
			(clearance 0)
		)
		(min_thickness 0.0254)
		(filled_areas_thickness no)
		(fill yes
			(thermal_gap 0.5)
			(thermal_bridge_width 0.5)
			(island_removal_mode 1)
			(island_area_min 10)
		)
		(polygon
			(pts
				(xy 120.837 74.413219) (xy 120.832397 74.349898) (xy 120.820172 74.297767) (xy 120.772063 74.197868)
				(xy 120.739741 74.137256) (xy 120.720677 74.066302) (xy 120.5 74.089) (xy 120.374997 74.277081)
				(xy 120.437513 74.304763) (xy 120.5062 74.337867) (xy 120.528559 74.367571) (xy 120.537 74.413219)
			)
		)
	)
	(zone
		(net 986)
		(net_name "Net-(D34-C)")
		(layer "F.Cu")
		(name "$teardrop_padvia$")
		(hatch none 0.1)
		(priority 30880)
		(attr
			(teardrop
				(type padvia)
			)
		)
		(connect_pads yes
			(clearance 0)
		)
		(min_thickness 0.0254)
		(filled_areas_thickness no)
		(fill yes
			(thermal_gap 0.5)
			(thermal_bridge_width 0.5)
			(island_removal_mode 1)
			(island_area_min 10)
		)
		(polygon
			(pts
				(xy 195.60861 76.259163) (xy 195.602838 76.2999) (xy 195.582434 76.341815) (xy 195.555259 76.370116)
				(xy 195.515713 76.393544) (xy 195.44311 76.412815) (xy 195.70861 76.673163) (xy 195.97411 76.412815)
				(xy 195.920968 76.400948) (xy 195.879929 76.382501) (xy 195.828228 76.331827) (xy 195.808892 76.268258)
				(xy 195.80861 76.259163)
			)
		)
	)
	(zone
		(net 196)
		(net_name "/OCuLink/PCIe_{x4}.RX3+")
		(layer "F.Cu")
		(name "$teardrop_padvia$")
		(hatch none 0.1)
		(priority 31361)
		(attr
			(teardrop
				(type padvia)
			)
		)
		(connect_pads yes
			(clearance 0)
		)
		(min_thickness 0.0254)
		(filled_areas_thickness no)
		(fill yes
			(thermal_gap 0.5)
			(thermal_bridge_width 0.5)
			(island_removal_mode 1)
			(island_area_min 10)
		)
		(polygon
			(pts
				(xy 107.1475 151.167496) (xy 107.152235 151.12071) (xy 107.165379 151.085257) (xy 107.210387 151.03706)
				(xy 107.248608 151.012883) (xy 107.291774 150.985514) (xy 107.333731 150.948852) (xy 107.1705 150.799)
				(xy 106.949823 150.819859) (xy 106.954452 150.920536) (xy 106.951019 151.003908) (xy 106.950895 151.005963)
				(xy 106.9455 151.167496)
			)
		)
	)
	(zone
		(net 722)
		(net_name "/2xSFP+/KR to SFI #1/TDI")
		(layer "F.Cu")
		(name "$teardrop_padvia$")
		(hatch none 0.1)
		(priority 31707)
		(attr
			(teardrop
				(type padvia)
			)
		)
		(connect_pads yes
			(clearance 0)
		)
		(min_thickness 0.0254)
		(filled_areas_thickness no)
		(fill yes
			(thermal_gap 0.5)
			(thermal_bridge_width 0.5)
			(island_removal_mode 1)
			(island_area_min 10)
		)
		(polygon
			(pts
				(xy 153.0375 129.739323) (xy 153.032682 129.808763) (xy 153.01896 129.860087) (xy 152.972245 129.935628)
				(xy 152.962702 129.947768) (xy 152.912919 130.014997) (xy 153.1 130.141) (xy 153.287081 130.014997)
				(xy 153.237299 129.947769) (xy 153.182894 129.864603) (xy 153.16781 129.811748) (xy 153.1625 129.739323)
			)
		)
	)
	(zone
		(net 569)
		(net_name "/USB-C console/FTDI_D-")
		(layer "F.Cu")
		(name "$teardrop_padvia$")
		(hatch none 0.1)
		(priority 30460)
		(attr
			(teardrop
				(type padvia)
			)
		)
		(connect_pads yes
			(clearance 0)
		)
		(min_thickness 0.0254)
		(filled_areas_thickness no)
		(fill yes
			(thermal_gap 0.5)
			(thermal_bridge_width 0.5)
			(island_removal_mode 1)
			(island_area_min 10)
		)
		(polygon
			(pts
				(xy 112.046435 75.9225) (xy 111.911618 75.979725) (xy 111.829303 76.002076) (xy 111.74169 76.012811)
				(xy 111.650452 76.006) (xy 111.685998 76.326) (xy 111.981998 76.421269) (xy 111.975075 76.28201)
				(xy 111.987897 76.182687) (xy 112.004744 76.145229) (xy 112.029673 76.117951) (xy 112.046435 76.1075)
			)
		)
	)
	(zone
		(net 2)
		(net_name "+3V3")
		(layer "F.Cu")
		(name "$teardrop_padvia$")
		(hatch none 0.1)
		(priority 31911)
		(attr
			(teardrop
				(type padvia)
			)
		)
		(connect_pads yes
			(clearance 0)
		)
		(min_thickness 0.0254)
		(filled_areas_thickness no)
		(fill yes
			(thermal_gap 0.5)
			(thermal_bridge_width 0.5)
			(island_removal_mode 1)
			(island_area_min 10)
		)
		(polygon
			(pts
				(xy 177.812084 103.3275) (xy 177.772695 103.322739) (xy 177.745036 103.30941) (xy 177.715135 103.265728)
				(xy 177.701407 103.215713) (xy 177.687268 103.162744) (xy 177.662081 103.109997) (xy 177.474 103.235)
				(xy 177.518895 103.455677) (xy 177.597852 103.444688) (xy 177.659695 103.445011) (xy 177.690029 103.4472)
				(xy 177.812084 103.4525)
			)
		)
	)
	(zone
		(net 114)
		(net_name "/2xSFP+/KR to SFI #1/KR_C.TX-")
		(layer "F.Cu")
		(name "$teardrop_padvia$")
		(hatch none 0.1)
		(priority 31166)
		(attr
			(teardrop
				(type padvia)
			)
		)
		(connect_pads yes
			(clearance 0)
		)
		(min_thickness 0.0254)
		(filled_areas_thickness no)
		(fill yes
			(thermal_gap 0.5)
			(thermal_bridge_width 0.5)
			(island_removal_mode 1)
			(island_area_min 10)
		)
		(polygon
			(pts
				(xy 156.22 143.17679) (xy 156.224788 143.139695) (xy 156.238304 143.115431) (xy 156.280007 143.096705)
				(xy 156.368927 143.101889) (xy 156.434222 143.108714) (xy 156.498773 143.105196) (xy 156.45 142.859)
				(xy 156.204804 142.811227) (xy 156.168876 142.909201) (xy 156.132391 142.964616) (xy 156.082365 143.048601)
				(xy 156.066125 143.104227) (xy 156.06 143.17679)
			)
		)
	)
	(zone
		(net 2)
		(net_name "+3V3")
		(layer "F.Cu")
		(name "$teardrop_padvia$")
		(hatch none 0.1)
		(priority 31994)
		(attr
			(teardrop
				(type padvia)
			)
		)
		(connect_pads yes
			(clearance 0)
		)
		(min_thickness 0.0254)
		(filled_areas_thickness no)
		(fill yes
			(thermal_gap 0.5)
			(thermal_bridge_width 0.5)
			(island_removal_mode 1)
			(island_area_min 10)
		)
		(polygon
			(pts
				(xy 130.800001 83.159501) (xy 130.806846 83.179356) (xy 130.81595 83.210994) (xy 130.808879 83.224568)
				(xy 130.787178 83.233983) (xy 130.898 83.622999) (xy 131.012158 83.238978) (xy 130.991123 83.228775)
				(xy 130.983852 83.214824) (xy 130.993017 83.180543) (xy 131 83.1595)
			)
		)
	)
	(zone
		(net 489)
		(net_name "Net-(J12K-10G_SDP1)")
		(layer "F.Cu")
		(name "$teardrop_padvia$")
		(hatch none 0.1)
		(priority 30682)
		(attr
			(teardrop
				(type padvia)
			)
		)
		(connect_pads yes
			(clearance 0)
		)
		(min_thickness 0.0254)
		(filled_areas_thickness no)
		(fill yes
			(thermal_gap 0.5)
			(thermal_bridge_width 0.5)
			(island_removal_mode 1)
			(island_area_min 10)
		)
		(polygon
			(pts
				(xy 195.4625 150.2) (xy 195.451563 150.238823) (xy 195.429805 150.253933) (xy 195.39 150.26) (xy 195.525 151.136)
				(xy 195.66 150.26) (xy 195.624719 150.255483) (xy 195.603203 150.243862) (xy 195.588005 150.211039)
				(xy 195.5875 150.2)
			)
		)
	)
	(zone
		(net 585)
		(net_name "Net-(U21-FB)")
		(layer "F.Cu")
		(name "$teardrop_padvia$")
		(hatch none 0.1)
		(priority 30496)
		(attr
			(teardrop
				(type padvia)
			)
		)
		(connect_pads yes
			(clearance 0)
		)
		(min_thickness 0.0254)
		(filled_areas_thickness no)
		(fill yes
			(thermal_gap 0.5)
			(thermal_bridge_width 0.5)
			(island_removal_mode 1)
			(island_area_min 10)
		)
		(polygon
			(pts
				(xy 313.376055 96.655444) (xy 313.425908 96.733261) (xy 313.454028 96.854704) (xy 313.455242 96.928976)
				(xy 313.445991 97.009262) (xy 313.445499 97.011974) (xy 313.766206 96.957207) (xy 313.845973 96.6615)
				(xy 313.759533 96.665038) (xy 313.6799 96.658954) (xy 313.607361 96.643919) (xy 313.544547 96.620956)
				(xy 313.464443 96.567056)
			)
		)
	)
	(zone
		(net 247)
		(net_name "/Com Express 7 Interfaces/PCIe_{B2Bx4}.TX2-")
		(layer "F.Cu")
		(name "$teardrop_padvia$")
		(hatch none 0.1)
		(priority 31364)
		(attr
			(teardrop
				(type padvia)
			)
		)
		(connect_pads yes
			(clearance 0)
		)
		(min_thickness 0.0254)
		(filled_areas_thickness no)
		(fill yes
			(thermal_gap 0.5)
			(thermal_bridge_width 0.5)
			(island_removal_mode 1)
			(island_area_min 10)
		)
		(polygon
			(pts
				(xy 188.5705 167.367496) (xy 188.575235 167.32071) (xy 188.588379 167.285257) (xy 188.633387 167.23706)
				(xy 188.671608 167.212883) (xy 188.714774 167.185514) (xy 188.756731 167.148852) (xy 188.5935 166.999)
				(xy 188.372823 167.019859) (xy 188.377452 167.120536) (xy 188.374019 167.203908) (xy 188.373895 167.205963)
				(xy 188.3685 167.367496)
			)
		)
	)
	(zone
		(net 347)
		(net_name "/2xUSB3.0+RJ45/~{GBE0_ACT}")
		(layer "F.Cu")
		(name "$teardrop_padvia$")
		(hatch none 0.1)
		(priority 30675)
		(attr
			(teardrop
				(type padvia)
			)
		)
		(connect_pads yes
			(clearance 0)
		)
		(min_thickness 0.0254)
		(filled_areas_thickness no)
		(fill yes
			(thermal_gap 0.5)
			(thermal_bridge_width 0.5)
			(island_removal_mode 1)
			(island_area_min 10)
		)
		(polygon
			(pts
				(xy 176.4625 162.2) (xy 176.451563 162.238823) (xy 176.429805 162.253933) (xy 176.39 162.26) (xy 176.525 163.136)
				(xy 176.66 162.26) (xy 176.624719 162.255483) (xy 176.603203 162.243862) (xy 176.588005 162.211039)
				(xy 176.5875 162.2)
			)
		)
	)
	(zone
		(net 229)
		(net_name "/M.2 key M #1/PCIE_{REF}.CK-")
		(layer "F.Cu")
		(name "$teardrop_padvia$")
		(hatch none 0.1)
		(priority 31431)
		(attr
			(teardrop
				(type padvia)
			)
		)
		(connect_pads yes
			(clearance 0)
		)
		(min_thickness 0.0254)
		(filled_areas_thickness no)
		(fill yes
			(thermal_gap 0.5)
			(thermal_bridge_width 0.5)
			(island_removal_mode 1)
			(island_area_min 10)
		)
		(polygon
			(pts
				(xy 207.767496 128.4135) (xy 207.605964 128.418895) (xy 207.521554 128.422445) (xy 207.41986 128.417823)
				(xy 207.399 128.6385) (xy 207.548852 128.801731) (xy 207.602992 128.733062) (xy 207.612883 128.716608)
				(xy 207.637383 128.677935) (xy 207.66689 128.645721) (xy 207.708046 128.623673) (xy 207.767496 128.6155)
			)
		)
	)
	(zone
		(net 1)
		(net_name "GND")
		(layer "F.Cu")
		(name "$teardrop_padvia$")
		(hatch none 0.1)
		(priority 31297)
		(attr
			(teardrop
				(type padvia)
			)
		)
		(connect_pads yes
			(clearance 0)
		)
		(min_thickness 0.0254)
		(filled_areas_thickness no)
		(fill yes
			(thermal_gap 0.5)
			(thermal_bridge_width 0.5)
			(island_removal_mode 1)
			(island_area_min 10)
		)
		(polygon
			(pts
				(xy 220.73739 150.104031) (xy 220.795813 150.052272) (xy 220.846563 150.019889) (xy 220.940703 149.98529)
				(xy 221.031121 149.955257) (xy 220.950707 149.749293) (xy 220.744741 149.66888) (xy 220.714708 149.759299)
				(xy 220.679237 149.855112) (xy 220.64702 149.905115) (xy 220.595969 149.96261)
			)
		)
	)
	(zone
		(net 491)
		(net_name "/2xSFP+/MDIO0.MDIO")
		(layer "F.Cu")
		(name "$teardrop_padvia$")
		(hatch none 0.1)
		(priority 30341)
		(attr
			(teardrop
				(type padvia)
			)
		)
		(connect_pads yes
			(clearance 0)
		)
		(min_thickness 0.0254)
		(filled_areas_thickness no)
		(fill yes
			(thermal_gap 0.5)
			(thermal_bridge_width 0.5)
			(island_removal_mode 1)
			(island_area_min 10)
		)
		(polygon
			(pts
				(xy 143.9015 152.224) (xy 143.907281 152.190137) (xy 143.927745 152.155516) (xy 143.954811 152.133694)
				(xy 143.99415 152.118) (xy 144.009711 152.114711) (xy 143.839 151.408) (xy 143.668289 152.114711)
				(xy 143.70851 152.1263) (xy 143.737984 152.143885) (xy 143.771173 152.191467) (xy 143.7765 152.224)
			)
		)
	)
	(zone
		(net 531)
		(net_name "/Com Express 7 Interfaces/SD_CD")
		(layer "F.Cu")
		(name "$teardrop_padvia$")
		(hatch none 0.1)
		(priority 30050)
		(attr
			(teardrop
				(type padvia)
			)
		)
		(connect_pads yes
			(clearance 0)
		)
		(min_thickness 0.0254)
		(filled_areas_thickness no)
		(fill yes
			(thermal_gap 0.5)
			(thermal_bridge_width 0.5)
			(island_removal_mode 1)
			(island_area_min 10)
		)
		(polygon
			(pts
				(xy 110.65253 130.17111) (xy 110.608603 130.15475) (xy 110.561933 130.126291) (xy 110.520025 130.088318)
				(xy 110.485174 130.039899) (xy 110.465277 129.993092) (xy 110.45556 129.939674) (xy 110.455 129.922847)
				(xy 109.504293 130.209293) (xy 110.455 130.553135) (xy 110.454975 130.524172) (xy 110.461804 130.356033)
				(xy 110.478503 130.318248) (xy 110.51111 130.31253)
			)
		)
	)
	(zone
		(net 84)
		(net_name "/Com Express 7 MGMT/PWRBTN")
		(layer "F.Cu")
		(name "$teardrop_padvia$")
		(hatch none 0.1)
		(priority 30720)
		(attr
			(teardrop
				(type padvia)
			)
		)
		(connect_pads yes
			(clearance 0)
		)
		(min_thickness 0.0254)
		(filled_areas_thickness no)
		(fill yes
			(thermal_gap 0.5)
			(thermal_bridge_width 0.5)
			(island_removal_mode 1)
			(island_area_min 10)
		)
		(polygon
			(pts
				(xy 244.4395 128.6) (xy 244.444848 128.567909) (xy 244.462282 128.534743) (xy 244.488737 128.508583)
				(xy 244.527163 128.487804) (xy 244.56705 128.47705) (xy 244.375 127.959) (xy 244.18295 128.47705)
				(xy 244.228153 128.489446) (xy 244.262844 128.508095) (xy 244.305426 128.558896) (xy 244.3145 128.6)
			)
		)
	)
	(zone
		(net 525)
		(net_name "Net-(J14-Pad2)")
		(layer "F.Cu")
		(name "$teardrop_padvia$")
		(hatch none 0.1)
		(priority 30002)
		(attr
			(teardrop
				(type padvia)
			)
		)
		(connect_pads yes
			(clearance 0)
		)
		(min_thickness 0.0254)
		(filled_areas_thickness no)
		(fill yes
			(thermal_gap 0.5)
			(thermal_bridge_width 0.5)
			(island_removal_mode 1)
			(island_area_min 10)
		)
		(polygon
			(pts
				(xy 209.059 72.123667) (xy 209.063873 72.000473) (xy 209.077981 71.8944) (xy 209.099306 71.807003)
				(xy 209.127655 71.730703) (xy 209.205331 71.599332) (xy 209.32465 71.466474) (xy 209.37342 71.418773)
				(xy 209.516053 71.273646) (xy 209.590598 71.185626) (xy 209.665749 71.082235) (xy 208.959 70.609)
				(xy 208.252251 71.082235) (xy 208.394343 71.265193) (xy 208.544581 71.418773) (xy 208.668915 71.545794)
				(xy 208.722405 71.612579) (xy 208.76864 71.68636) (xy 208.80652 71.770749) (xy 208.834941 71.869356)
				(xy 208.852801 71.985792) (xy 208.859 72.123667)
			)
		)
	)
	(zone
		(net 56)
		(net_name "/USB-C console/USB_D-")
		(layer "F.Cu")
		(name "$teardrop_padvia$")
		(hatch none 0.1)
		(priority 30707)
		(attr
			(teardrop
				(type padvia)
			)
		)
		(connect_pads yes
			(clearance 0)
		)
		(min_thickness 0.0254)
		(filled_areas_thickness no)
		(fill yes
			(thermal_gap 0.5)
			(thermal_bridge_width 0.5)
			(island_removal_mode 1)
			(island_area_min 10)
		)
		(polygon
			(pts
				(xy 102.458481 82.929701) (xy 102.454605 83.062399) (xy 102.465876 83.18334) (xy 102.482014 83.375012)
				(xy 102.475 83.603983) (xy 102.599805 83.81048) (xy 102.664785 82.997) (xy 102.632938 82.992716)
				(xy 102.629398 82.982731) (xy 102.634898 82.97427) (xy 102.639925 82.965792)
			)
		)
	)
	(zone
		(net 304)
		(net_name "Net-(J12D-~{BATLOW})")
		(layer "F.Cu")
		(name "$teardrop_padvia$")
		(hatch none 0.1)
		(priority 31616)
		(attr
			(teardrop
				(type padvia)
			)
		)
		(connect_pads yes
			(clearance 0)
		)
		(min_thickness 0.0254)
		(filled_areas_thickness no)
		(fill yes
			(thermal_gap 0.5)
			(thermal_bridge_width 0.5)
			(island_removal_mode 1)
			(island_area_min 10)
		)
		(polygon
			(pts
				(xy 188.9625 169.549323) (xy 188.957747 169.610452) (xy 188.94448 169.656552) (xy 188.899229 169.723244)
				(xy 188.88137 169.742341) (xy 188.812919 169.824997) (xy 189 169.951) (xy 189.207644 169.874641)
				(xy 189.149334 169.759581) (xy 189.105855 169.67547) (xy 189.092451 169.621061) (xy 189.0875 169.549323)
			)
		)
	)
	(zone
		(net 870)
		(net_name "Net-(U21-SW)")
		(layer "F.Cu")
		(hatch edge 0.5)
		(priority 15)
		(connect_pads yes
			(clearance 0.15)
		)
		(min_thickness 0.25)
		(filled_areas_thickness no)
		(fill yes
			(thermal_gap 0.2)
			(thermal_bridge_width 0.5)
		)
		(polygon
			(pts
				(xy 312.2005 94.7365) (xy 312.6005 94.7365) (xy 312.6005 93.9865) (xy 313.1505 93.4365) (xy 313.1505 89.6865)
				(xy 312.9005 89.4365) (xy 311.9005 89.4365) (xy 311.6505 89.6865) (xy 311.6505 93.4365) (xy 312.2005 93.9865)
			)
		)
	)
	(zone
		(net 1)
		(net_name "GND")
		(layer "F.Cu")
		(name "$teardrop_padvia$")
		(hatch none 0.1)
		(priority 31191)
		(attr
			(teardrop
				(type padvia)
			)
		)
		(connect_pads yes
			(clearance 0)
		)
		(min_thickness 0.0254)
		(filled_areas_thickness no)
		(fill yes
			(thermal_gap 0.5)
			(thermal_bridge_width 0.5)
			(island_removal_mode 1)
			(island_area_min 10)
		)
		(polygon
			(pts
				(xy 205.625 155.800677) (xy 205.62972 155.731353) (xy 205.642756 155.678449) (xy 205.694658 155.58586)
				(xy 205.746458 155.502363) (xy 205.55 155.399) (xy 205.342355 155.475358) (xy 205.374583 155.555861)
				(xy 205.410965 155.657318) (xy 205.425 155.800677)
			)
		)
	)
	(zone
		(net 147)
		(net_name "/2xUSB3.0+RJ45/DA-")
		(layer "F.Cu")
		(name "$teardrop_padvia$")
		(hatch none 0.1)
		(priority 30017)
		(attr
			(teardrop
				(type padvia)
			)
		)
		(connect_pads yes
			(clearance 0)
		)
		(min_thickness 0.0254)
		(filled_areas_thickness no)
		(fill yes
			(thermal_gap 0.5)
			(thermal_bridge_width 0.5)
			(island_removal_mode 1)
			(island_area_min 10)
		)
		(polygon
			(pts
				(xy 116.81203 108.465) (xy 116.703742 108.460143) (xy 116.612158 108.446147) (xy 116.538003 108.425133)
				(xy 116.474073 108.397365) (xy 116.361783 108.319755) (xy 116.253982 108.213931) (xy 116.138242 108.099061)
				(xy 115.98501 107.978758) (xy 115.609 108.54) (xy 115.98501 109.101242) (xy 116.144239 108.975439)
				(xy 116.253982 108.866069) (xy 116.354229 108.76688) (xy 116.4654 108.687238) (xy 116.532231 108.656965)
				(xy 116.610374 108.634243) (xy 116.702687 108.619959) (xy 116.81203 108.615)
			)
		)
	)
	(zone
		(net 303)
		(net_name "/Com Express 7 MGMT/~{SUS_S5}")
		(layer "F.Cu")
		(name "$teardrop_padvia$")
		(hatch none 0.1)
		(priority 31821)
		(attr
			(teardrop
				(type padvia)
			)
		)
		(connect_pads yes
			(clearance 0)
		)
		(min_thickness 0.0254)
		(filled_areas_thickness no)
		(fill yes
			(thermal_gap 0.5)
			(thermal_bridge_width 0.5)
			(island_removal_mode 1)
			(island_area_min 10)
		)
		(polygon
			(pts
				(xy 185.500677 170.7375) (xy 185.431236 170.732682) (xy 185.379913 170.71896) (xy 185.304371 170.672246)
				(xy 185.292231 170.662701) (xy 185.225003 170.612919) (xy 185.099 170.8) (xy 185.225003 170.987081)
				(xy 185.292229 170.937299) (xy 185.375396 170.882894) (xy 185.428251 170.86781) (xy 185.500677 170.8625)
			)
		)
	)
	(zone
		(net 970)
		(net_name "/M.2 key M #2/M2_3V3")
		(layer "F.Cu")
		(name "$teardrop_padvia$")
		(hatch none 0.1)
		(priority 30762)
		(attr
			(teardrop
				(type padvia)
			)
		)
		(connect_pads yes
			(clearance 0)
		)
		(min_thickness 0.0254)
		(filled_areas_thickness no)
		(fill yes
			(thermal_gap 0.5)
			(thermal_bridge_width 0.5)
			(island_removal_mode 1)
			(island_area_min 10)
		)
		(polygon
			(pts
				(xy 289.098 80.978677) (xy 289.104932 80.8211) (xy 289.133456 80.707565) (xy 289.1505 80.665778)
				(xy 288.948 80.577) (xy 288.7455 80.665778) (xy 288.779883 80.761822) (xy 288.795101 80.863702)
				(xy 288.798 80.978677)
			)
		)
	)
	(zone
		(net 607)
		(net_name "Net-(U37-~{HIBW_BYPM_LOBW})")
		(layer "F.Cu")
		(name "$teardrop_padvia$")
		(hatch none 0.1)
		(priority 30926)
		(attr
			(teardrop
				(type padvia)
			)
		)
		(connect_pads yes
			(clearance 0)
		)
		(min_thickness 0.0254)
		(filled_areas_thickness no)
		(fill yes
			(thermal_gap 0.5)
			(thermal_bridge_width 0.5)
			(island_removal_mode 1)
			(island_area_min 10)
		)
		(polygon
			(pts
				(xy 219.3125 123.338) (xy 219.332469 123.275134) (xy 219.358921 123.243156) (xy 219.396332 123.214642)
				(xy 219.443527 123.192118) (xy 219.501167 123.176907) (xy 219.501798 123.176798) (xy 219.25 122.899)
				(xy 218.998202 123.176798) (xy 219.053635 123.191095) (xy 219.09952 123.212175) (xy 219.137201 123.23954)
				(xy 219.164434 123.270448) (xy 219.181472 123.303735) (xy 219.187489 123.336566) (xy 219.1875 123.338)
			)
		)
	)
	(zone
		(net 434)
		(net_name "/Com Express 7 MGMT/~{TYPE1}")
		(layer "F.Cu")
		(name "$teardrop_padvia$")
		(hatch none 0.1)
		(priority 31981)
		(attr
			(teardrop
				(type padvia)
			)
		)
		(connect_pads yes
			(clearance 0)
		)
		(min_thickness 0.0254)
		(filled_areas_thickness no)
		(fill yes
			(thermal_gap 0.5)
			(thermal_bridge_width 0.5)
			(island_removal_mode 1)
			(island_area_min 10)
		)
		(polygon
			(pts
				(xy 249.5375 133.322) (xy 249.548184 133.283236) (xy 249.569681 133.268089) (xy 249.609187 133.262)
				(xy 249.469 132.886) (xy 249.339162 133.262) (xy 249.37477 133.266519) (xy 249.396534 133.27815)
				(xy 249.411978 133.310994) (xy 249.4125 133.322)
			)
		)
	)
	(zone
		(net 940)
		(net_name "Net-(D8-C)")
		(layer "F.Cu")
		(name "$teardrop_padvia$")
		(hatch none 0.1)
		(priority 30177)
		(attr
			(teardrop
				(type padvia)
			)
		)
		(connect_pads yes
			(clearance 0)
		)
		(min_thickness 0.0254)
		(filled_areas_thickness no)
		(fill yes
			(thermal_gap 0.5)
			(thermal_bridge_width 0.5)
			(island_removal_mode 1)
			(island_area_min 10)
		)
		(polygon
			(pts
				(xy 139.88 168.3775) (xy 139.82156 168.358243) (xy 139.767486 168.297235) (xy 139.727203 168.187634)
				(xy 139.716022 168.08) (xy 139.319 168.44) (xy 139.716022 168.8) (xy 139.721642 168.724212) (xy 139.735856 168.657749)
				(xy 139.757451 168.601481) (xy 139.785051 168.556792) (xy 139.815041 168.526501) (xy 139.848017 168.508124)
				(xy 139.88 168.5025)
			)
		)
	)
	(zone
		(net 237)
		(net_name "/Com Express 7 Interfaces/PCIe_{B2Bx4}.RX3-")
		(layer "F.Cu")
		(name "$teardrop_padvia$")
		(hatch none 0.1)
		(priority 31413)
		(attr
			(teardrop
				(type padvia)
			)
		)
		(connect_pads yes
			(clearance 0)
		)
		(min_thickness 0.0254)
		(filled_areas_thickness no)
		(fill yes
			(thermal_gap 0.5)
			(thermal_bridge_width 0.5)
			(island_removal_mode 1)
			(island_area_min 10)
		)
		(polygon
			(pts
				(xy 186.432504 127.3065) (xy 186.594035 127.301105) (xy 186.678445 127.297554) (xy 186.78014 127.302177)
				(xy 186.801 127.0815) (xy 186.651147 126.918268) (xy 186.597007 126.986935) (xy 186.587115 127.003393)
				(xy 186.562615 127.042065) (xy 186.533109 127.074279) (xy 186.491953 127.096327) (xy 186.432504 127.1045)
			)
		)
	)
	(zone
		(net 526)
		(net_name "/Backplane/~{PRSNT}")
		(layer "F.Cu")
		(name "$teardrop_padvia$")
		(hatch none 0.1)
		(priority 32111)
		(attr
			(teardrop
				(type padvia)
			)
		)
		(connect_pads yes
			(clearance 0)
		)
		(min_thickness 0.0254)
		(filled_areas_thickness no)
		(fill yes
			(thermal_gap 0.5)
			(thermal_bridge_width 0.5)
			(island_removal_mode 1)
			(island_area_min 10)
		)
		(polygon
			(pts
				(xy 314.81 164.5205) (xy 314.816322 164.520404) (xy 314.855825 164.525989) (xy 314.874047 164.540922)
				(xy 314.886995 164.5705) (xy 315.136 164.458) (xy 314.886995 164.3455) (xy 314.875879 164.372493)
				(xy 314.860352 164.387595) (xy 314.816322 164.395596) (xy 314.81 164.3955)
			)
		)
	)
	(zone
		(net 288)
		(net_name "/2xUSB3.0+RJ45/~{GBE0_LINK_1000}")
		(layer "F.Cu")
		(name "$teardrop_padvia$")
		(hatch none 0.1)
		(priority 31610)
		(attr
			(teardrop
				(type padvia)
			)
		)
		(connect_pads yes
			(clearance 0)
		)
		(min_thickness 0.0254)
		(filled_areas_thickness no)
		(fill yes
			(thermal_gap 0.5)
			(thermal_bridge_width 0.5)
			(island_removal_mode 1)
			(island_area_min 10)
		)
		(polygon
			(pts
				(xy 177.9625 169.599323) (xy 177.957747 169.660452) (xy 177.94448 169.706552) (xy 177.899229 169.773244)
				(xy 177.88137 169.792341) (xy 177.812919 169.874997) (xy 178 170.001) (xy 178.207644 169.924641)
				(xy 178.149334 169.809581) (xy 178.105855 169.72547) (xy 178.092451 169.671061) (xy 178.0875 169.599323)
			)
		)
	)
	(zone
		(net 942)
		(net_name "/2xUSB3.0+RJ45/EN_2")
		(layer "F.Cu")
		(name "$teardrop_padvia$")
		(hatch none 0.1)
		(priority 31122)
		(attr
			(teardrop
				(type padvia)
			)
		)
		(connect_pads yes
			(clearance 0)
		)
		(min_thickness 0.0254)
		(filled_areas_thickness no)
		(fill yes
			(thermal_gap 0.5)
			(thermal_bridge_width 0.5)
			(island_removal_mode 1)
			(island_area_min 10)
		)
		(polygon
			(pts
				(xy 125.532 87.122501) (xy 125.591412 87.142274) (xy 125.647497 87.205548) (xy 125.669199 87.254173)
				(xy 125.683873 87.313532) (xy 125.685653 87.325501) (xy 125.946 87.060001) (xy 125.685653 86.794501)
				(xy 125.672804 86.854639) (xy 125.65287 86.904523) (xy 125.626945 86.944642) (xy 125.597125 86.973655)
				(xy 125.565707 86.991147) (xy 125.533896 86.99748) (xy 125.532 86.997501)
			)
		)
	)
	(zone
		(net 641)
		(net_name "Net-(U41-IO0_2)")
		(layer "F.Cu")
		(name "$teardrop_padvia$")
		(hatch none 0.1)
		(priority 31082)
		(attr
			(teardrop
				(type padvia)
			)
		)
		(connect_pads yes
			(clearance 0)
		)
		(min_thickness 0.0254)
		(filled_areas_thickness no)
		(fill yes
			(thermal_gap 0.5)
			(thermal_bridge_width 0.5)
			(island_removal_mode 1)
			(island_area_min 10)
		)
		(polygon
			(pts
				(xy 127.318 84.997501) (xy 127.258588 84.977728) (xy 127.202503 84.914454) (xy 127.180801 84.865829)
				(xy 127.166127 84.806469) (xy 127.164347 84.794501) (xy 126.904 85.060001) (xy 127.164347 85.325501)
				(xy 127.177197 85.265362) (xy 127.197131 85.215478) (xy 127.223056 85.175359) (xy 127.252876 85.146346)
				(xy 127.284294 85.128855) (xy 127.316105 85.122522) (xy 127.318 85.122501)
			)
		)
	)
	(zone
		(net 2)
		(net_name "+3V3")
		(layer "F.Cu")
		(name "$teardrop_padvia$")
		(hatch none 0.1)
		(priority 30221)
		(attr
			(teardrop
				(type padvia)
			)
		)
		(connect_pads yes
			(clearance 0)
		)
		(min_thickness 0.0254)
		(filled_areas_thickness no)
		(fill yes
			(thermal_gap 0.5)
			(thermal_bridge_width 0.5)
			(island_removal_mode 1)
			(island_area_min 10)
		)
		(polygon
			(pts
				(xy 124.883 150.596) (xy 124.89135 150.626608) (xy 124.901961 150.679593) (xy 124.888956 150.702725)
				(xy 124.853 150.719191) (xy 125.033 151.412) (xy 125.213 150.719191) (xy 125.183041 150.707257)
				(xy 125.167728 150.690936) (xy 125.165892 150.653262) (xy 125.17465 150.626608) (xy 125.183 150.596)
			)
		)
	)
	(zone
		(net 62)
		(net_name "+12V_AON")
		(layer "F.Cu")
		(name "$teardrop_padvia$")
		(hatch none 0.1)
		(priority 30085)
		(attr
			(teardrop
				(type padvia)
			)
		)
		(connect_pads yes
			(clearance 0)
		)
		(min_thickness 0.0254)
		(filled_areas_thickness no)
		(fill yes
			(thermal_gap 0.5)
			(thermal_bridge_width 0.5)
			(island_removal_mode 1)
			(island_area_min 10)
		)
		(polygon
			(pts
				(xy 186.80861 73.469957) (xy 186.813461 73.37858) (xy 186.827419 73.306651) (xy 186.87436 73.2051)
				(xy 186.93378 73.126257) (xy 187.020411 73.010502) (xy 186.70861 72.801163) (xy 186.396809 73.010502)
				(xy 186.48344 73.126258) (xy 186.53478 73.19314) (xy 186.574276 73.262875) (xy 186.599646 73.350226)
				(xy 186.60861 73.469957)
			)
		)
	)
	(zone
		(net 50)
		(net_name "Net-(C12-Pad2)")
		(layer "F.Cu")
		(name "$teardrop_padvia$")
		(hatch none 0.1)
		(priority 30873)
		(attr
			(teardrop
				(type padvia)
			)
		)
		(connect_pads yes
			(clearance 0)
		)
		(min_thickness 0.0254)
		(filled_areas_thickness no)
		(fill yes
			(thermal_gap 0.5)
			(thermal_bridge_width 0.5)
			(island_removal_mode 1)
			(island_area_min 10)
		)
		(polygon
			(pts
				(xy 137.493 105.2) (xy 137.452263 105.194228) (xy 137.410348 105.173824) (xy 137.382047 105.146649)
				(xy 137.358618 105.107103) (xy 137.339347 105.0345) (xy 137.079 105.3) (xy 137.339347 105.5655)
				(xy 137.351214 105.512358) (xy 137.369662 105.471319) (xy 137.420336 105.419618) (xy 137.483905 105.400282)
				(xy 137.493 105.4)
			)
		)
	)
	(zone
		(net 523)
		(net_name "Net-(J13-Pad1)")
		(layer "F.Cu")
		(name "$teardrop_padvia$")
		(hatch none 0.1)
		(priority 30837)
		(attr
			(teardrop
				(type padvia)
			)
		)
		(connect_pads yes
			(clearance 0)
		)
		(min_thickness 0.0254)
		(filled_areas_thickness no)
		(fill yes
			(thermal_gap 0.5)
			(thermal_bridge_width 0.5)
			(island_removal_mode 1)
			(island_area_min 10)
		)
		(polygon
			(pts
				(xy 216.32 77.672) (xy 216.313219 77.723013) (xy 216.285749 77.77641) (xy 216.256862 77.802823)
				(xy 216.215896 77.823404) (xy 216.178202 77.833202) (xy 216.43 78.111) (xy 216.681798 77.833202)
				(xy 216.63011 77.81992) (xy 216.590179 77.800333) (xy 216.539467 77.747565) (xy 216.520301 77.681782)
				(xy 216.52 77.672)
			)
		)
	)
	(zone
		(net 146)
		(net_name "/2xUSB3.0+RJ45/DA+")
		(layer "F.Cu")
		(name "$teardrop_padvia$")
		(hatch none 0.1)
		(priority 30015)
		(attr
			(teardrop
				(type padvia)
			)
		)
		(connect_pads yes
			(clearance 0)
		)
		(min_thickness 0.0254)
		(filled_areas_thickness no)
		(fill yes
			(thermal_gap 0.5)
			(thermal_bridge_width 0.5)
			(island_removal_mode 1)
			(island_area_min 10)
		)
		(polygon
			(pts
				(xy 118.209454 108.621968) (xy 118.039546 108.798888) (xy 117.920707 108.938527) (xy 117.763396 109.164875)
				(xy 117.732972 109.212647) (xy 117.588758 109.43499) (xy 118.149293 109.810707) (xy 118.711242 109.43499)
				(xy 118.612553 109.317877) (xy 118.450336 109.177759) (xy 118.327508 109.073454) (xy 118.279542 109.022144)
				(xy 118.245251 108.969864) (xy 118.22817 108.915462) (xy 118.231832 108.85779) (xy 118.259771 108.795697)
				(xy 118.31552 108.728034)
			)
		)
	)
	(zone
		(net 771)
		(net_name "/Backplane/PCIe_{x2}.RX1+")
		(layer "F.Cu")
		(name "$teardrop_padvia$")
		(hatch none 0.1)
		(priority 32094)
		(attr
			(teardrop
				(type padvia)
			)
		)
		(connect_pads yes
			(clearance 0)
		)
		(min_thickness 0.0254)
		(filled_areas_thickness no)
		(fill yes
			(thermal_gap 0.5)
			(thermal_bridge_width 0.5)
			(island_removal_mode 1)
			(island_area_min 10)
		)
		(polygon
			(pts
				(xy 314.81 161.511) (xy 314.831227 161.503702) (xy 314.864264 161.493978) (xy 314.878732 161.500702)
				(xy 314.889264 161.522015) (xy 315.136 161.408) (xy 314.884691 161.297039) (xy 314.875384 161.318505)
				(xy 314.862008 161.325545) (xy 314.830071 161.316104) (xy 314.81 161.309)
			)
		)
	)
	(zone
		(net 772)
		(net_name "/Backplane/PCIe_{x2}.RX1-")
		(layer "F.Cu")
		(name "$teardrop_padvia$")
		(hatch none 0.1)
		(priority 30019)
		(attr
			(teardrop
				(type padvia)
			)
		)
		(connect_pads yes
			(clearance 0)
		)
		(min_thickness 0.0254)
		(filled_areas_thickness no)
		(fill yes
			(thermal_gap 0.5)
			(thermal_bridge_width 0.5)
			(island_removal_mode 1)
			(island_area_min 10)
		)
		(polygon
			(pts
				(xy 317.860744 162.4055) (xy 317.893777 162.411457) (xy 317.923712 162.433158) (xy 317.939644 162.460607)
				(xy 317.949306 162.500407) (xy 317.95 162.565591) (xy 319.451 162.51) (xy 319.254117 162.235) (xy 318.774522 162.244225)
				(xy 318.255858 162.220754) (xy 317.860744 162.2035)
			)
		)
	)
	(zone
		(net 528)
		(net_name "/Backplane/~{PERST}")
		(layer "F.Cu")
		(name "$teardrop_padvia$")
		(hatch none 0.1)
		(priority 32121)
		(attr
			(teardrop
				(type padvia)
			)
		)
		(connect_pads yes
			(clearance 0)
		)
		(min_thickness 0.0254)
		(filled_areas_thickness no)
		(fill yes
			(thermal_gap 0.5)
			(thermal_bridge_width 0.5)
			(island_removal_mode 1)
			(island_area_min 10)
		)
		(polygon
			(pts
				(xy 314.688 163.3975) (xy 314.681678 163.397596) (xy 314.642175 163.392011) (xy 314.623953 163.377078)
				(xy 314.611005 163.3475) (xy 314.362 163.46) (xy 314.611005 163.5725) (xy 314.622121 163.545506)
				(xy 314.637648 163.530405) (xy 314.681678 163.522404) (xy 314.688 163.5225)
			)
		)
	)
	(zone
		(net 750)
		(net_name "Net-(U45C-CLKOUTA+)")
		(layer "F.Cu")
		(name "$teardrop_padvia$")
		(hatch none 0.1)
		(priority 31736)
		(attr
			(teardrop
				(type padvia)
			)
		)
		(connect_pads yes
			(clearance 0)
		)
		(min_thickness 0.0254)
		(filled_areas_thickness no)
		(fill yes
			(thermal_gap 0.5)
			(thermal_bridge_width 0.5)
			(island_removal_mode 1)
			(island_area_min 10)
		)
		(polygon
			(pts
				(xy 136.8275 130.109323) (xy 136.822682 130.178763) (xy 136.80896 130.230087) (xy 136.762245 130.305628)
				(xy 136.752702 130.317768) (xy 136.702919 130.384997) (xy 136.89 130.511) (xy 137.077081 130.384997)
				(xy 137.027299 130.317769) (xy 136.972894 130.234603) (xy 136.95781 130.181748) (xy 136.9525 130.109323)
			)
		)
	)
	(zone
		(net 931)
		(net_name "/2xSFP+/SFP0_LEDG")
		(layer "F.Cu")
		(name "$teardrop_padvia$")
		(hatch none 0.1)
		(priority 30505)
		(attr
			(teardrop
				(type padvia)
			)
		)
		(connect_pads yes
			(clearance 0)
		)
		(min_thickness 0.0254)
		(filled_areas_thickness no)
		(fill yes
			(thermal_gap 0.5)
			(thermal_bridge_width 0.5)
			(island_removal_mode 1)
			(island_area_min 10)
		)
		(polygon
			(pts
				(xy 154.517944 160.499444) (xy 154.595761 160.449591) (xy 154.717204 160.421471) (xy 154.791476 160.420257)
				(xy 154.871762 160.429508) (xy 154.874474 160.43) (xy 154.819707 160.109293) (xy 154.524 160.029526)
				(xy 154.527538 160.115966) (xy 154.521454 160.195599) (xy 154.506419 160.268138) (xy 154.483456 160.330952)
				(xy 154.429556 160.411056)
			)
		)
	)
	(zone
		(net 314)
		(net_name "/2xUSB3.0+RJ45/FLG_1")
		(layer "F.Cu")
		(name "$teardrop_padvia$")
		(hatch none 0.1)
		(priority 31880)
		(attr
			(teardrop
				(type padvia)
			)
		)
		(connect_pads yes
			(clearance 0)
		)
		(min_thickness 0.0254)
		(filled_areas_thickness no)
		(fill yes
			(thermal_gap 0.5)
			(thermal_bridge_width 0.5)
			(island_removal_mode 1)
			(island_area_min 10)
		)
		(polygon
			(pts
				(xy 135.727515 123.239127) (xy 135.681819 123.186618) (xy 135.655231 123.140623) (xy 135.634847 123.054175)
				(xy 135.633011 123.03884) (xy 135.620677 122.956105) (xy 135.399293 122.999293) (xy 135.356105 123.220677)
				(xy 135.43884 123.233011) (xy 135.536119 123.253349) (xy 135.584159 123.280057) (xy 135.639127 123.327515)
			)
		)
	)
	(zone
		(net 1)
		(net_name "GND")
		(layer "F.Cu")
		(name "$teardrop_padvia$")
		(hatch none 0.1)
		(priority 30583)
		(attr
			(teardrop
				(type padvia)
			)
		)
		(connect_pads yes
			(clearance 0)
		)
		(min_thickness 0.0254)
		(filled_areas_thickness no)
		(fill yes
			(thermal_gap 0.5)
			(thermal_bridge_width 0.5)
			(island_removal_mode 1)
			(island_area_min 10)
		)
		(polygon
			(pts
				(xy 210.625 164.07) (xy 210.621667 164.055514) (xy 210.61881 164.02539) (xy 210.630964 164.014349)
				(xy 210.66 164.01) (xy 210.525 163.134) (xy 210.39 164.01) (xy 210.419334 164.014475) (xy 210.431358 164.025801)
				(xy 210.428333 164.055514) (xy 210.425 164.07)
			)
		)
	)
	(zone
		(net 1)
		(net_name "GND")
		(layer "F.Cu")
		(name "$teardrop_padvia$")
		(hatch none 0.1)
		(priority 31520)
		(attr
			(teardrop
				(type padvia)
			)
		)
		(connect_pads yes
			(clearance 0)
		)
		(min_thickness 0.0254)
		(filled_areas_thickness no)
		(fill yes
			(thermal_gap 0.5)
			(thermal_bridge_width 0.5)
			(island_removal_mode 1)
			(island_area_min 10)
		)
		(polygon
			(pts
				(xy 215.625 155.828189) (xy 215.629744 155.790692) (xy 215.642953 155.764285) (xy 215.686807 155.735049)
				(xy 215.731837 155.722287) (xy 215.779059 155.709143) (xy 215.825003 155.687081) (xy 215.7 155.499)
				(xy 215.479323 155.482712) (xy 215.453216 155.623045) (xy 215.433805 155.708057) (xy 215.425 155.828189)
			)
		)
	)
	(zone
		(net 149)
		(net_name "/2xUSB3.0+RJ45/DC+")
		(layer "F.Cu")
		(name "$teardrop_padvia$")
		(hatch none 0.1)
		(priority 30012)
		(attr
			(teardrop
				(type padvia)
			)
		)
		(connect_pads yes
			(clearance 0)
		)
		(min_thickness 0.0254)
		(filled_areas_thickness no)
		(fill yes
			(thermal_gap 0.5)
			(thermal_bridge_width 0.5)
			(island_removal_mode 1)
			(island_area_min 10)
		)
		(polygon
			(pts
				(xy 116.794089 106.1) (xy 116.700692 106.095146) (xy 116.620955 106.081165) (xy 116.555686 106.059996)
				(xy 116.499791 106.03201) (xy 116.406606 105.95515) (xy 116.319499 105.837758) (xy 116.28473 105.781706)
				(xy 116.167142 105.607825) (xy 116.088502 105.522298) (xy 115.988152 105.4419) (xy 115.609 106)
				(xy 115.792138 106.641131) (xy 115.983246 106.568982) (xy 116.149437 106.472236) (xy 116.194667 106.441798)
				(xy 116.306701 106.369224) (xy 116.43161 106.308027) (xy 116.587903 106.265767) (xy 116.794089 106.25)
			)
		)
	)
	(zone
		(net 671)
		(net_name "/2xSFP+/KR to SFI #2/MDC_R")
		(layer "F.Cu")
		(name "$teardrop_padvia$")
		(hatch none 0.1)
		(priority 30921)
		(attr
			(teardrop
				(type padvia)
			)
		)
		(connect_pads yes
			(clearance 0)
		)
		(min_thickness 0.0254)
		(filled_areas_thickness no)
		(fill yes
			(thermal_gap 0.5)
			(thermal_bridge_width 0.5)
			(island_removal_mode 1)
			(island_area_min 10)
		)
		(polygon
			(pts
				(xy 123.7955 145.488) (xy 123.815521 145.424631) (xy 123.841983 145.392419) (xy 123.87945 145.363745)
				(xy 123.925578 145.341677) (xy 123.981798 145.326798) (xy 123.73 145.049) (xy 123.478202 145.326798)
				(xy 123.534609 145.34115) (xy 123.581333 145.3623) (xy 123.61957 145.389651) (xy 123.647216 145.420574)
				(xy 123.664386 145.453667) (xy 123.670487 145.486446) (xy 123.6705 145.488)
			)
		)
	)
	(zone
		(net 129)
		(net_name "Net-(D17-C_{R})")
		(layer "F.Cu")
		(name "$teardrop_padvia$")
		(hatch none 0.1)
		(priority 30043)
		(attr
			(teardrop
				(type padvia)
			)
		)
		(connect_pads yes
			(clearance 0)
		)
		(min_thickness 0.0254)
		(filled_areas_thickness no)
		(fill yes
			(thermal_gap 0.5)
			(thermal_bridge_width 0.5)
			(island_removal_mode 1)
			(island_area_min 10)
		)
		(polygon
			(pts
				(xy 100.93 78.8725) (xy 100.996119 78.891662) (xy 101.058575 78.951682) (xy 101.113056 79.061369)
				(xy 101.14619 79.222166) (xy 101.15 79.305) (xy 101.701 78.81) (xy 101.15 78.315) (xy 101.145167 78.408055)
				(xy 101.131336 78.493163) (xy 101.109363 78.569111) (xy 101.080322 78.633751) (xy 101.047847 78.682298)
				(xy 101.010956 78.718314) (xy 100.975921 78.73842) (xy 100.938706 78.747181) (xy 100.93 78.7475)
			)
		)
	)
	(zone
		(net 967)
		(net_name "/2xSFP+/KR to SFI #1/BYP_RX-")
		(layer "F.Cu")
		(name "$teardrop_padvia$")
		(hatch none 0.1)
		(priority 31960)
		(attr
			(teardrop
				(type padvia)
			)
		)
		(connect_pads yes
			(clearance 0)
		)
		(min_thickness 0.0254)
		(filled_areas_thickness no)
		(fill yes
			(thermal_gap 0.5)
			(thermal_bridge_width 0.5)
			(island_removal_mode 1)
			(island_area_min 10)
		)
		(polygon
			(pts
				(xy 152.84 148.527721) (xy 152.815938 148.458348) (xy 152.779423 148.348401) (xy 152.769113 148.288313)
				(xy 152.77 148.226463) (xy 152.57 148.254) (xy 152.511231 148.485) (xy 152.592579 148.479702) (xy 152.644596 148.488493)
				(xy 152.666116 148.502345) (xy 152.678354 148.522403) (xy 152.68 148.527721)
			)
		)
	)
	(zone
		(net 147)
		(net_name "/2xUSB3.0+RJ45/DA-")
		(layer "F.Cu")
		(name "$teardrop_padvia$")
		(hatch none 0.1)
		(priority 31144)
		(attr
			(teardrop
				(type padvia)
			)
		)
		(connect_pads yes
			(clearance 0)
		)
		(min_thickness 0.0254)
		(filled_areas_thickness no)
		(fill yes
			(thermal_gap 0.5)
			(thermal_bridge_width 0.5)
			(island_removal_mode 1)
			(island_area_min 10)
		)
		(polygon
			(pts
				(xy 125.973139 113.172927) (xy 126.057997 113.117339) (xy 126.116278 113.098091) (xy 126.184276 113.086472)
				(xy 126.326943 113.0875) (xy 126.290707 112.849293) (xy 125.9525 112.831575) (xy 125.949601 112.924947)
				(xy 125.913761 113.009194) (xy 125.867073 113.066861)
			)
		)
	)
	(zone
		(net 1)
		(net_name "GND")
		(layer "F.Cu")
		(name "$teardrop_padvia$")
		(hatch none 0.1)
		(priority 31239)
		(attr
			(teardrop
				(type padvia)
			)
		)
		(connect_pads yes
			(clearance 0)
		)
		(min_thickness 0.0254)
		(filled_areas_thickness no)
		(fill yes
			(thermal_gap 0.5)
			(thermal_bridge_width 0.5)
			(island_removal_mode 1)
			(island_area_min 10)
		)
		(polygon
			(pts
				(xy 200.925 151.799323) (xy 200.920263 151.890322) (xy 200.907104 151.957411) (xy 200.874583 152.044139)
				(xy 200.842355 152.124641) (xy 201.05 152.201) (xy 201.246458 152.097636) (xy 201.194657 152.014138)
				(xy 201.145166 151.928045) (xy 201.130386 151.87284) (xy 201.125 151.799323)
			)
		)
	)
	(zone
		(net 189)
		(net_name "/OCuLink/PCIe_{x4}.RX1-")
		(layer "F.Cu")
		(name "$teardrop_padvia$")
		(hatch none 0.1)
		(priority 31403)
		(attr
			(teardrop
				(type padvia)
			)
		)
		(connect_pads yes
			(clearance 0)
		)
		(min_thickness 0.0254)
		(filled_areas_thickness no)
		(fill yes
			(thermal_gap 0.5)
			(thermal_bridge_width 0.5)
			(island_removal_mode 1)
			(island_area_min 10)
		)
		(polygon
			(pts
				(xy 98.662504 164.2615) (xy 98.824035 164.256105) (xy 98.908445 164.252554) (xy 99.01014 164.257177)
				(xy 99.031 164.0365) (xy 98.881147 163.873268) (xy 98.827007 163.941935) (xy 98.817115 163.958393)
				(xy 98.792615 163.997065) (xy 98.763109 164.029279) (xy 98.721953 164.051327) (xy 98.662504 164.0595)
			)
		)
	)
	(zone
		(net 135)
		(net_name "Net-(D19-Pad3)")
		(layer "F.Cu")
		(name "$teardrop_padvia$")
		(hatch none 0.1)
		(priority 30000)
		(attr
			(teardrop
				(type padvia)
			)
		)
		(connect_pads yes
			(clearance 0)
		)
		(min_thickness 0.0254)
		(filled_areas_thickness no)
		(fill yes
			(thermal_gap 0.5)
			(thermal_bridge_width 0.5)
			(island_removal_mode 1)
			(island_area_min 10)
		)
		(polygon
			(pts
				(xy 221.748 72.123667) (xy 221.752915 71.974822) (xy 221.767319 71.848709) (xy 221.788492 71.749149)
				(xy 221.816855 71.661841) (xy 221.895634 71.507361) (xy 222.029388 71.32268) (xy 222.204749 71.082235)
				(xy 221.498 70.609) (xy 220.791251 71.082235) (xy 220.966613 71.322682) (xy 221.083408 71.481289)
				(xy 221.131508 71.55996) (xy 221.172043 71.644099) (xy 221.204485 71.738122) (xy 221.228309 71.846446)
				(xy 221.24299 71.973489) (xy 221.248 72.123667)
			)
		)
	)
	(zone
		(net 651)
		(net_name "/2xSFP+/KR to SFI #1/MDC")
		(layer "F.Cu")
		(name "$teardrop_padvia$")
		(hatch none 0.1)
		(priority 31781)
		(attr
			(teardrop
				(type padvia)
			)
		)
		(connect_pads yes
			(clearance 0)
		)
		(min_thickness 0.0254)
		(filled_areas_thickness no)
		(fill yes
			(thermal_gap 0.5)
			(thermal_bridge_width 0.5)
			(island_removal_mode 1)
			(island_area_min 10)
		)
		(polygon
			(pts
				(xy 143.9125 143.510677) (xy 143.917318 143.441236) (xy 143.93104 143.389912) (xy 143.977755 143.31437)
				(xy 143.987299 143.302229) (xy 144.037081 143.235003) (xy 143.85 143.109) (xy 143.662919 143.235003)
				(xy 143.712701 143.302231) (xy 143.767106 143.385397) (xy 143.78219 143.438251) (xy 143.7875 143.510677)
			)
		)
	)
	(zone
		(net 127)
		(net_name "/USB-C console/FTDI_LED_RX")
		(layer "F.Cu")
		(name "$teardrop_padvia$")
		(hatch none 0.1)
		(priority 31859)
		(attr
			(teardrop
				(type padvia)
			)
		)
		(connect_pads yes
			(clearance 0)
		)
		(min_thickness 0.0254)
		(filled_areas_thickness no)
		(fill yes
			(thermal_gap 0.5)
			(thermal_bridge_width 0.5)
			(island_removal_mode 1)
			(island_area_min 10)
		)
		(polygon
			(pts
				(xy 112.972485 73.720873) (xy 113.018181 73.773382) (xy 113.044768 73.819376) (xy 113.065152 73.905825)
				(xy 113.066988 73.921158) (xy 113.079323 74.003895) (xy 113.300707 73.960707) (xy 113.343895 73.739323)
				(xy 113.261158 73.726988) (xy 113.16388 73.706651) (xy 113.11584 73.679943) (xy 113.060873 73.632485)
			)
		)
	)
	(zone
		(net 208)
		(net_name "/Backplane/UART.RX")
		(layer "F.Cu")
		(name "$teardrop_padvia$")
		(hatch none 0.1)
		(priority 32108)
		(attr
			(teardrop
				(type padvia)
			)
		)
		(connect_pads yes
			(clearance 0)
		)
		(min_thickness 0.0254)
		(filled_areas_thickness no)
		(fill yes
			(thermal_gap 0.5)
			(thermal_bridge_width 0.5)
			(island_removal_mode 1)
			(island_area_min 10)
		)
		(polygon
			(pts
				(xy 314.81 167.5705) (xy 314.816322 167.570404) (xy 314.855825 167.575989) (xy 314.874047 167.590922)
				(xy 314.886995 167.6205) (xy 315.136 167.508) (xy 314.886995 167.3955) (xy 314.875879 167.422493)
				(xy 314.860352 167.437595) (xy 314.816322 167.445596) (xy 314.81 167.4455)
			)
		)
	)
	(zone
		(net 533)
		(net_name "/Com Express 7 MGMT/PSON")
		(layer "F.Cu")
		(name "$teardrop_padvia$")
		(hatch none 0.1)
		(priority 31606)
		(attr
			(teardrop
				(type padvia)
			)
		)
		(connect_pads yes
			(clearance 0)
		)
		(min_thickness 0.0254)
		(filled_areas_thickness no)
		(fill yes
			(thermal_gap 0.5)
			(thermal_bridge_width 0.5)
			(island_removal_mode 1)
			(island_area_min 10)
		)
		(polygon
			(pts
				(xy 258.187 130.810677) (xy 258.19167 130.740932) (xy 258.204359 130.687646) (xy 258.249038 130.600572)
				(xy 258.307547 130.485592) (xy 258.1 130.409) (xy 257.912919 130.535003) (xy 257.981032 130.617437)
				(xy 258.038806 130.692054) (xy 258.055832 130.741998) (xy 258.062 130.810677)
			)
		)
	)
	(zone
		(net 1)
		(net_name "GND")
		(layer "F.Cu")
		(name "$teardrop_padvia$")
		(hatch none 0.1)
		(priority 31277)
		(attr
			(teardrop
				(type padvia)
			)
		)
		(connect_pads yes
			(clearance 0)
		)
		(min_thickness 0.0254)
		(filled_areas_thickness no)
		(fill yes
			(thermal_gap 0.5)
			(thermal_bridge_width 0.5)
			(island_removal_mode 1)
			(island_area_min 10)
		)
		(polygon
			(pts
				(xy 186.60861 77.701486) (xy 186.603897 77.779397) (xy 186.59091 77.838181) (xy 186.548809 77.929211)
				(xy 186.50611 78.014384) (xy 186.70861 78.103163) (xy 186.91111 78.014384) (xy 186.868411 77.929213)
				(xy 186.825743 77.83638) (xy 186.813166 77.778241) (xy 186.80861 77.701486)
			)
		)
	)
	(zone
		(net 186)
		(net_name "/OCuLink/PCIe_{x4}.RX0+")
		(layer "F.Cu")
		(name "$teardrop_padvia$")
		(hatch none 0.1)
		(priority 32079)
		(attr
			(teardrop
				(type padvia)
			)
		)
		(connect_pads yes
			(clearance 0)
		)
		(min_thickness 0.0254)
		(filled_areas_thickness no)
		(fill yes
			(thermal_gap 0.5)
			(thermal_bridge_width 0.5)
			(island_removal_mode 1)
			(island_area_min 10)
		)
		(polygon
			(pts
				(xy 96.401 150.375) (xy 96.408198 150.395648) (xy 96.417792 150.427984) (xy 96.410965 150.442007)
				(xy 96.3895 150.451995) (xy 96.502 150.701) (xy 96.6145 150.451995) (xy 96.593324 150.442271) (xy 96.586269 150.428643)
				(xy 96.595802 150.395648) (xy 96.603 150.375)
			)
		)
	)
	(zone
		(net 1)
		(net_name "GND")
		(layer "F.Cu")
		(name "$teardrop_padvia$")
		(hatch none 0.1)
		(priority 31200)
		(attr
			(teardrop
				(type padvia)
			)
		)
		(connect_pads yes
			(clearance 0)
		)
		(min_thickness 0.0254)
		(filled_areas_thickness no)
		(fill yes
			(thermal_gap 0.5)
			(thermal_bridge_width 0.5)
			(island_removal_mode 1)
			(island_area_min 10)
		)
		(polygon
			(pts
				(xy 223.425 157.399323) (xy 223.42028 157.468646) (xy 223.407244 157.521549) (xy 223.355344 157.614135)
				(xy 223.303541 157.697636) (xy 223.5 157.801) (xy 223.707644 157.724641) (xy 223.675418 157.644142)
				(xy 223.639035 157.542683) (xy 223.625 157.399323)
			)
		)
	)
	(zone
		(net 382)
		(net_name "Net-(J12D-~{CB_RESET})")
		(layer "F.Cu")
		(name "$teardrop_padvia$")
		(hatch none 0.1)
		(priority 31747)
		(attr
			(teardrop
				(type padvia)
			)
		)
		(connect_pads yes
			(clearance 0)
		)
		(min_thickness 0.0254)
		(filled_areas_thickness no)
		(fill yes
			(thermal_gap 0.5)
			(thermal_bridge_width 0.5)
			(island_removal_mode 1)
			(island_area_min 10)
		)
		(polygon
			(pts
				(xy 202.799323 165.4125) (xy 202.868764 165.417318) (xy 202.920088 165.43104) (xy 202.995629 165.477755)
				(xy 203.007769 165.487299) (xy 203.074997 165.537081) (xy 203.201 165.35) (xy 203.074997 165.162919)
				(xy 203.007768 165.212702) (xy 202.924602 165.267106) (xy 202.871748 165.28219) (xy 202.799323 165.2875)
			)
		)
	)
	(zone
		(net 586)
		(net_name "Net-(U22-FB)")
		(layer "F.Cu")
		(name "$teardrop_padvia$")
		(hatch none 0.1)
		(priority 32038)
		(attr
			(teardrop
				(type padvia)
			)
		)
		(connect_pads yes
			(clearance 0)
		)
		(min_thickness 0.0254)
		(filled_areas_thickness no)
		(fill yes
			(thermal_gap 0.5)
			(thermal_bridge_width 0.5)
			(island_removal_mode 1)
			(island_area_min 10)
		)
		(polygon
			(pts
				(xy 312.986999 135.317) (xy 312.99576 135.270297) (xy 313.015286 135.248785) (xy 313.052532 135.235033)
				(xy 312.924499 134.956) (xy 312.796466 135.235033) (xy 312.827234 135.24492) (xy 312.846459 135.260183)
				(xy 312.861393 135.300135) (xy 312.861999 135.317)
			)
		)
	)
	(zone
		(net 1)
		(net_name "GND")
		(layer "F.Cu")
		(name "$teardrop_padvia$")
		(hatch none 0.1)
		(priority 30955)
		(attr
			(teardrop
				(type padvia)
			)
		)
		(connect_pads yes
			(clearance 0)
		)
		(min_thickness 0.0254)
		(filled_areas_thickness no)
		(fill yes
			(thermal_gap 0.5)
			(thermal_bridge_width 0.5)
			(island_removal_mode 1)
			(island_area_min 10)
		)
		(polygon
			(pts
				(xy 113.3175 146.422) (xy 113.297531 146.484866) (xy 113.271079 146.516844) (xy 113.233668 146.545358)
				(xy 113.186473 146.567882) (xy 113.128833 146.583093) (xy 113.128202 146.583202) (xy 113.38 146.861)
				(xy 113.631798 146.583202) (xy 113.576365 146.568905) (xy 113.53048 146.547825) (xy 113.492799 146.52046)
				(xy 113.465566 146.489552) (xy 113.448528 146.456265) (xy 113.442511 146.423434) (xy 113.4425 146.422)
			)
		)
	)
	(zone
		(net 1)
		(net_name "GND")
		(layer "F.Cu")
		(name "$teardrop_padvia$")
		(hatch none 0.1)
		(priority 31941)
		(attr
			(teardrop
				(type padvia)
			)
		)
		(connect_pads yes
			(clearance 0)
		)
		(min_thickness 0.0254)
		(filled_areas_thickness no)
		(fill yes
			(thermal_gap 0.5)
			(thermal_bridge_width 0.5)
			(island_removal_mode 1)
			(island_area_min 10)
		)
		(polygon
			(pts
				(xy 314.008 167.11) (xy 314.018115 167.109847) (xy 314.048832 167.11046) (xy 314.08132 167.118782)
				(xy 314.110475 167.142675) (xy 314.131191 167.19) (xy 314.364 167.01) (xy 314.131191 166.83) (xy 314.117833 166.865901)
				(xy 314.099601 166.889199) (xy 314.054276 166.908899) (xy 314.018115 166.910153) (xy 314.008 166.91)
			)
		)
	)
	(zone
		(net 120)
		(net_name "/2xSFP+/KR to SFI #2/KR_C.TX+")
		(layer "F.Cu")
		(name "$teardrop_padvia$")
		(hatch none 0.1)
		(priority 31180)
		(attr
			(teardrop
				(type padvia)
			)
		)
		(connect_pads yes
			(clearance 0)
		)
		(min_thickness 0.0254)
		(filled_areas_thickness no)
		(fill yes
			(thermal_gap 0.5)
			(thermal_bridge_width 0.5)
			(island_removal_mode 1)
			(island_area_min 10)
		)
		(polygon
			(pts
				(xy 137.68 143.17679) (xy 137.675347 143.112802) (xy 137.662777 143.062121) (xy 137.618645 142.980204)
				(xy 137.607609 142.964616) (xy 137.566024 142.899819) (xy 137.535196 142.811227) (xy 137.29 142.859)
				(xy 137.241227 143.105196) (xy 137.328185 143.107002) (xy 137.371073 143.101889) (xy 137.428443 143.095867)
				(xy 137.475848 143.099993) (xy 137.508097 143.123792) (xy 137.52 143.17679)
			)
		)
	)
	(zone
		(net 1)
		(net_name "GND")
		(layer "F.Cu")
		(name "$teardrop_padvia$")
		(hatch none 0.1)
		(priority 31306)
		(attr
			(teardrop
				(type padvia)
			)
		)
		(connect_pads yes
			(clearance 0)
		)
		(min_thickness 0.0254)
		(filled_areas_thickness no)
		(fill yes
			(thermal_gap 0.5)
			(thermal_bridge_width 0.5)
			(island_removal_mode 1)
			(island_area_min 10)
		)
		(polygon
			(pts
				(xy 203.299 82.45716) (xy 203.294285 82.538324) (xy 203.281284 82.599226) (xy 203.24206 82.689274)
				(xy 203.202293 82.773914) (xy 203.40639 82.858837) (xy 203.607216 82.766019) (xy 203.561699 82.680837)
				(xy 203.517043 82.590089) (xy 203.503807 82.532855) (xy 203.499 82.45716)
			)
		)
	)
	(zone
		(net 589)
		(net_name "/Misc/~{ADDRSEL}")
		(layer "F.Cu")
		(name "$teardrop_padvia$")
		(hatch none 0.1)
		(priority 30821)
		(attr
			(teardrop
				(type padvia)
			)
		)
		(connect_pads yes
			(clearance 0)
		)
		(min_thickness 0.0254)
		(filled_areas_thickness no)
		(fill yes
			(thermal_gap 0.5)
			(thermal_bridge_width 0.5)
			(island_removal_mode 1)
			(island_area_min 10)
		)
		(polygon
			(pts
				(xy 254.056 83.252499) (xy 254.082609 83.257862) (xy 254.107883 83.275399) (xy 254.125522 83.301693)
				(xy 254.13695 83.339839) (xy 254.14 83.378999) (xy 254.701 83.19) (xy 254.14 83.000999) (xy 254.135373 83.048362)
				(xy 254.122982 83.08341) (xy 254.105123 83.107348) (xy 254.083985 83.121545) (xy 254.056 83.127499)
			)
		)
	)
	(zone
		(net 259)
		(net_name "/Com Express 7 Interfaces/PCIe_{B2Bx4}.TX1+")
		(layer "F.Cu")
		(name "$teardrop_padvia$")
		(hatch none 0.1)
		(priority 31437)
		(attr
			(teardrop
				(type padvia)
			)
		)
		(connect_pads yes
			(clearance 0)
		)
		(min_thickness 0.0254)
		(filled_areas_thickness no)
		(fill yes
			(thermal_gap 0.5)
			(thermal_bridge_width 0.5)
			(island_removal_mode 1)
			(island_area_min 10)
		)
		(polygon
			(pts
				(xy 190.367496 166.4935) (xy 190.205964 166.498895) (xy 190.121554 166.502445) (xy 190.01986 166.497823)
				(xy 189.999 166.7185) (xy 190.148852 166.881731) (xy 190.202992 166.813062) (xy 190.212883 166.796608)
				(xy 190.237383 166.757935) (xy 190.26689 166.725721) (xy 190.308046 166.703673) (xy 190.367496 166.6955)
			)
		)
	)
	(zone
		(net 2)
		(net_name "+3V3")
		(layer "F.Cu")
		(name "$teardrop_padvia$")
		(hatch none 0.1)
		(priority 30339)
		(attr
			(teardrop
				(type padvia)
			)
		)
		(connect_pads yes
			(clearance 0)
		)
		(min_thickness 0.0254)
		(filled_areas_thickness no)
		(fill yes
			(thermal_gap 0.5)
			(thermal_bridge_width 0.5)
			(island_removal_mode 1)
			(island_area_min 10)
		)
		(polygon
			(pts
				(xy 247.367709 78.3605) (xy 247.333846 78.354719) (xy 247.299224 78.334254) (xy 247.277402 78.307188)
				(xy 247.261709 78.267848) (xy 247.25842 78.252289) (xy 246.551709 78.423) (xy 247.25842 78.593711)
				(xy 247.27001 78.55349) (xy 247.287594 78.524016) (xy 247.335177 78.490827) (xy 247.367709 78.4855)
			)
		)
	)
	(zone
		(net 242)
		(net_name "/Com Express 7 Interfaces/PCIe_{B2Bx4}.TX3+")
		(layer "F.Cu")
		(name "$teardrop_padvia$")
		(hatch none 0.1)
		(priority 30242)
		(attr
			(teardrop
				(type padvia)
			)
		)
		(connect_pads yes
			(clearance 0)
		)
		(min_thickness 0.0254)
		(filled_areas_thickness no)
		(fill yes
			(thermal_gap 0.5)
			(thermal_bridge_width 0.5)
			(island_removal_mode 1)
			(island_area_min 10)
		)
		(polygon
			(pts
				(xy 186.4795 167.75) (xy 186.48258 167.764227) (xy 186.484749 167.794527) (xy 186.471877 167.805628)
				(xy 186.441705 167.81) (xy 186.525 168.686) (xy 186.675 168.437021) (xy 186.655644 168.195818) (xy 186.670401 167.923112)
				(xy 186.6815 167.75)
			)
		)
	)
	(zone
		(net 294)
		(net_name "/2xUSB3.0+RJ45/GbE.MDI0-")
		(layer "F.Cu")
		(name "$teardrop_padvia$")
		(hatch none 0.1)
		(priority 30304)
		(attr
			(teardrop
				(type padvia)
			)
		)
		(connect_pads yes
			(clearance 0)
		)
		(min_thickness 0.0254)
		(filled_areas_thickness no)
		(fill yes
			(thermal_gap 0.5)
			(thermal_bridge_width 0.5)
			(island_removal_mode 1)
			(island_area_min 10)
		)
		(polygon
			(pts
				(xy 181.525 167.75) (xy 181.525035 167.754084) (xy 181.517242 167.790449) (xy 181.497831 167.804416)
				(xy 181.459759 167.81) (xy 181.525 168.686) (xy 181.675 168.504204) (xy 181.658334 168.198008) (xy 181.667809 167.932252)
				(xy 181.675 167.75)
			)
		)
	)
	(zone
		(net 598)
		(net_name "Net-(U31-~{WC})")
		(layer "F.Cu")
		(name "$teardrop_padvia$")
		(hatch none 0.1)
		(priority 31998)
		(attr
			(teardrop
				(type padvia)
			)
		)
		(connect_pads yes
			(clearance 0)
		)
		(min_thickness 0.0254)
		(filled_areas_thickness no)
		(fill yes
			(thermal_gap 0.5)
			(thermal_bridge_width 0.5)
			(island_removal_mode 1)
			(island_area_min 10)
		)
		(polygon
			(pts
				(xy 238.1875 153.552) (xy 238.176563 153.590823) (xy 238.154805 153.605933) (xy 238.115 153.612)
				(xy 238.25 153.963) (xy 238.385 153.612) (xy 238.349719 153.607483) (xy 238.328203 153.595862) (xy 238.313005 153.563039)
				(xy 238.3125 153.552)
			)
		)
	)
	(zone
		(net 733)
		(net_name "Net-(U43C-CLKOUTB-)")
		(layer "F.Cu")
		(name "$teardrop_padvia$")
		(hatch none 0.1)
		(priority 30138)
		(attr
			(teardrop
				(type padvia)
			)
		)
		(connect_pads yes
			(clearance 0)
		)
		(min_thickness 0.0254)
		(filled_areas_thickness no)
		(fill yes
			(thermal_gap 0.5)
			(thermal_bridge_width 0.5)
			(island_removal_mode 1)
			(island_area_min 10)
		)
		(polygon
			(pts
				(xy 157.516396 129.138007) (xy 157.461775 129.076577) (xy 157.425259 129.02068) (xy 157.392229 128.921809)
				(xy 157.38498 128.818095) (xy 157.381201 128.7349) (xy 157.367794 128.636841) (xy 156.999293 128.709293)
				(xy 156.926841 129.077794) (xy 157.080423 129.094169) (xy 157.108095 129.09498) (xy 157.187316 129.099032)
				(xy 157.262488 129.114488) (xy 157.340441 129.153043) (xy 157.428007 129.226396)
			)
		)
	)
	(zone
		(net 694)
		(net_name "/2xUSB3.0+RJ45/DC_FL-")
		(layer "F.Cu")
		(name "$teardrop_padvia$")
		(hatch none 0.1)
		(priority 31914)
		(attr
			(teardrop
				(type padvia)
			)
		)
		(connect_pads yes
			(clearance 0)
		)
		(min_thickness 0.0254)
		(filled_areas_thickness no)
		(fill yes
			(thermal_gap 0.5)
			(thermal_bridge_width 0.5)
			(island_removal_mode 1)
			(island_area_min 10)
		)
		(polygon
			(pts
				(xy 130.285256 109.32) (xy 130.396614 109.304599) (xy 130.429855 109.297211) (xy 130.557639 109.272263)
				(xy 130.708385 109.265) (xy 130.746 109.125) (xy 130.32 109.105747) (xy 130.32157 109.145519) (xy 130.313159 109.164265)
				(xy 130.288946 109.170047) (xy 130.285256 109.17)
			)
		)
	)
	(zone
		(net 48)
		(net_name "Net-(U34-ONT)")
		(layer "F.Cu")
		(name "$teardrop_padvia$")
		(hatch none 0.1)
		(priority 30723)
		(attr
			(teardrop
				(type padvia)
			)
		)
		(connect_pads yes
			(clearance 0)
		)
		(min_thickness 0.0254)
		(filled_areas_thickness no)
		(fill yes
			(thermal_gap 0.5)
			(thermal_bridge_width 0.5)
			(island_removal_mode 1)
			(island_area_min 10)
		)
		(polygon
			(pts
				(xy 243.7875 128.6) (xy 243.792821 128.568265) (xy 243.810069 128.535565) (xy 243.836538 128.509374)
				(xy 243.874964 128.488445) (xy 243.91705 128.47705) (xy 243.725 127.959) (xy 243.53295 128.47705)
				(xy 243.577474 128.489409) (xy 243.6116 128.508008) (xy 243.653536 128.558803) (xy 243.6625 128.6)
			)
		)
	)
	(zone
		(net 527)
		(net_name "/Backplane/GPIO")
		(layer "F.Cu")
		(name "$teardrop_padvia$")
		(hatch none 0.1)
		(priority 32114)
		(attr
			(teardrop
				(type padvia)
			)
		)
		(connect_pads yes
			(clearance 0)
		)
		(min_thickness 0.0254)
		(filled_areas_thickness no)
		(fill yes
			(thermal_gap 0.5)
			(thermal_bridge_width 0.5)
			(island_removal_mode 1)
			(island_area_min 10)
		)
		(polygon
			(pts
				(xy 314.038 165.0205) (xy 314.044322 165.020404) (xy 314.083825 165.025989) (xy 314.102047 165.040922)
				(xy 314.114995 165.0705) (xy 314.364 164.958) (xy 314.114995 164.8455) (xy 314.103879 164.872493)
				(xy 314.088352 164.887595) (xy 314.044322 164.895596) (xy 314.038 164.8955)
			)
		)
	)
	(zone
		(net 704)
		(net_name "Net-(U24-GPIO2)")
		(layer "F.Cu")
		(name "$teardrop_padvia$")
		(hatch none 0.1)
		(priority 31836)
		(attr
			(teardrop
				(type padvia)
			)
		)
		(connect_pads yes
			(clearance 0)
		)
		(min_thickness 0.0254)
		(filled_areas_thickness no)
		(fill yes
			(thermal_gap 0.5)
			(thermal_bridge_width 0.5)
			(island_removal_mode 1)
			(island_area_min 10)
		)
		(polygon
			(pts
				(xy 260.439323 85.792498) (xy 260.508763 85.797316) (xy 260.560087 85.811038) (xy 260.635628 85.857753)
				(xy 260.647769 85.867297) (xy 260.714997 85.91708) (xy 260.840999 85.729999) (xy 260.714997 85.542918)
				(xy 260.647769 85.5927) (xy 260.564603 85.647105) (xy 260.511749 85.662189) (xy 260.439324 85.667499)
			)
		)
	)
	(zone
		(net 293)
		(net_name "/2xUSB3.0+RJ45/GbE.MDI1+")
		(layer "F.Cu")
		(name "$teardrop_padvia$")
		(hatch none 0.1)
		(priority 30313)
		(attr
			(teardrop
				(type padvia)
			)
		)
		(connect_pads yes
			(clearance 0)
		)
		(min_thickness 0.0254)
		(filled_areas_thickness no)
		(fill yes
			(thermal_gap 0.5)
			(thermal_bridge_width 0.5)
			(island_removal_mode 1)
			(island_area_min 10)
		)
		(polygon
			(pts
				(xy 180.375 167.75) (xy 180.382191 167.932252) (xy 180.391641 168.183885) (xy 180.388369 168.333893)
				(xy 180.375 168.504204) (xy 180.525 168.686) (xy 180.590241 167.81) (xy 180.555265 167.805495) (xy 180.535678 167.793958)
				(xy 180.524981 167.762811) (xy 180.524965 167.754084) (xy 180.525 167.75)
			)
		)
	)
	(zone
		(net 74)
		(net_name "+1V0")
		(layer "F.Cu")
		(name "$teardrop_padvia$")
		(hatch none 0.1)
		(priority 31294)
		(attr
			(teardrop
				(type padvia)
			)
		)
		(connect_pads yes
			(clearance 0)
		)
		(min_thickness 0.0254)
		(filled_areas_thickness no)
		(fill yes
			(thermal_gap 0.5)
			(thermal_bridge_width 0.5)
			(island_removal_mode 1)
			(island_area_min 10)
		)
		(polygon
			(pts
				(xy 203.012641 73.014773) (xy 202.960882 72.956349) (xy 202.928499 72.905599) (xy 202.8939 72.81146)
				(xy 202.863867 72.721042) (xy 202.657903 72.801456) (xy 202.577489 73.00742) (xy 202.667907 73.037453)
				(xy 202.763721 73.072925) (xy 202.813724 73.105142) (xy 202.87122 73.156194)
			)
		)
	)
	(zone
		(net 1)
		(net_name "GND")
		(layer "F.Cu")
		(name "$teardrop_padvia$")
		(hatch none 0.1)
		(priority 30572)
		(attr
			(teardrop
				(type padvia)
			)
		)
		(connect_pads yes
			(clearance 0)
		)
		(min_thickness 0.0254)
		(filled_areas_thickness no)
		(fill yes
			(thermal_gap 0.5)
			(thermal_bridge_width 0.5)
			(island_removal_mode 1)
			(island_area_min 10)
		)
		(polygon
			(pts
				(xy 205.625 152.07) (xy 205.621667 152.055514) (xy 205.61881 152.02539) (xy 205.630964 152.014349)
				(xy 205.66 152.01) (xy 205.525 151.134) (xy 205.39 152.01) (xy 205.419334 152.014475) (xy 205.431358 152.025801)
				(xy 205.428333 152.055514) (xy 205.425 152.07)
			)
		)
	)
	(zone
		(net 1)
		(net_name "GND")
		(layer "F.Cu")
		(name "$teardrop_padvia$")
		(hatch none 0.1)
		(priority 31185)
		(attr
			(teardrop
				(type padvia)
			)
		)
		(connect_pads yes
			(clearance 0)
		)
		(min_thickness 0.0254)
		(filled_areas_thickness no)
		(fill yes
			(thermal_gap 0.5)
			(thermal_bridge_width 0.5)
			(island_removal_mode 1)
			(island_area_min 10)
		)
		(polygon
			(pts
				(xy 217.625 150.321677) (xy 217.62972 150.252353) (xy 217.642756 150.199449) (xy 217.694658 150.10686)
				(xy 217.746458 150.023363) (xy 217.55 149.92) (xy 217.342355 149.996358) (xy 217.374583 150.076861)
				(xy 217.410965 150.178318) (xy 217.425 150.321677)
			)
		)
	)
	(zone
		(net 338)
		(net_name "/Com Express 7 MGMT/SPI.MISO")
		(layer "F.Cu")
		(name "$teardrop_padvia$")
		(hatch none 0.1)
		(priority 30702)
		(attr
			(teardrop
				(type padvia)
			)
		)
		(connect_pads yes
			(clearance 0)
		)
		(min_thickness 0.0254)
		(filled_areas_thickness no)
		(fill yes
			(thermal_gap 0.5)
			(thermal_bridge_width 0.5)
			(island_removal_mode 1)
			(island_area_min 10)
		)
		(polygon
			(pts
				(xy 221.4625 167.75) (xy 221.451563 167.788823) (xy 221.429805 167.803933) (xy 221.39 167.81) (xy 221.525 168.686)
				(xy 221.66 167.81) (xy 221.624719 167.805483) (xy 221.603203 167.793862) (xy 221.588005 167.761039)
				(xy 221.5875 167.75)
			)
		)
	)
	(zone
		(net 693)
		(net_name "/2xUSB3.0+RJ45/DC_FL+")
		(layer "F.Cu")
		(name "$teardrop_padvia$")
		(hatch none 0.1)
		(priority 31146)
		(attr
			(teardrop
				(type padvia)
			)
		)
		(connect_pads yes
			(clearance 0)
		)
		(min_thickness 0.0254)
		(filled_areas_thickness no)
		(fill yes
			(thermal_gap 0.5)
			(thermal_bridge_width 0.5)
			(island_removal_mode 1)
			(island_area_min 10)
		)
		(polygon
			(pts
				(xy 128.526861 109.557073) (xy 128.442002 109.612661) (xy 128.383721 109.63191) (xy 128.315724 109.643528)
				(xy 128.173057 109.6425) (xy 128.209293 109.880707) (xy 128.5475 109.898424) (xy 128.5504 109.805052)
				(xy 128.58624 109.720804) (xy 128.632927 109.663139)
			)
		)
	)
	(zone
		(net 751)
		(net_name "Net-(U45C-CLKOUTA-)")
		(layer "F.Cu")
		(name "$teardrop_padvia$")
		(hatch none 0.1)
		(priority 31727)
		(attr
			(teardrop
				(type padvia)
			)
		)
		(connect_pads yes
			(clearance 0)
		)
		(min_thickness 0.0254)
		(filled_areas_thickness no)
		(fill yes
			(thermal_gap 0.5)
			(thermal_bridge_width 0.5)
			(island_removal_mode 1)
			(island_area_min 10)
		)
		(polygon
			(pts
				(xy 130.3275 130.109323) (xy 130.322682 130.178763) (xy 130.30896 130.230087) (xy 130.262245 130.305628)
				(xy 130.252702 130.317768) (xy 130.202919 130.384997) (xy 130.39 130.511) (xy 130.577081 130.384997)
				(xy 130.527299 130.317769) (xy 130.472894 130.234603) (xy 130.45781 130.181748) (xy 130.4525 130.109323)
			)
		)
	)
	(zone
		(net 1)
		(net_name "GND")
		(layer "F.Cu")
		(name "$teardrop_padvia$")
		(hatch none 0.1)
		(priority 30544)
		(attr
			(teardrop
				(type padvia)
			)
		)
		(connect_pads yes
			(clearance 0)
		)
		(min_thickness 0.0254)
		(filled_areas_thickness no)
		(fill yes
			(thermal_gap 0.5)
			(thermal_bridge_width 0.5)
			(island_removal_mode 1)
			(island_area_min 10)
		)
		(polygon
			(pts
				(xy 211.925 167.75) (xy 211.928333 167.764486) (xy 211.93119 167.79461) (xy 211.919036 167.805651)
				(xy 211.89 167.81) (xy 212.025 168.686) (xy 212.16 167.81) (xy 212.130666 167.805525) (xy 212.118642 167.794199)
				(xy 212.121667 167.764486) (xy 212.125 167.75)
			)
		)
	)
	(zone
		(net 1)
		(net_name "GND")
		(layer "F.Cu")
		(name "$teardrop_padvia$")
		(hatch none 0.1)
		(priority 30535)
		(attr
			(teardrop
				(type padvia)
			)
		)
		(connect_pads yes
			(clearance 0)
		)
		(min_thickness 0.0254)
		(filled_areas_thickness no)
		(fill yes
			(thermal_gap 0.5)
			(thermal_bridge_width 0.5)
			(island_removal_mode 1)
			(island_area_min 10)
		)
		(polygon
			(pts
				(xy 225.425 150.2) (xy 225.428333 150.214486) (xy 225.43119 150.24461) (xy 225.419036 150.255651)
				(xy 225.39 150.26) (xy 225.525 151.136) (xy 225.66 150.26) (xy 225.630666 150.255525) (xy 225.618642 150.244199)
				(xy 225.621667 150.214486) (xy 225.625 150.2)
			)
		)
	)
	(zone
		(net 670)
		(net_name "/2xSFP+/KR to SFI #2/MDIO")
		(layer "F.Cu")
		(name "$teardrop_padvia$")
		(hatch none 0.1)
		(priority 31628)
		(attr
			(teardrop
				(type padvia)
			)
		)
		(connect_pads yes
			(clearance 0)
		)
		(min_thickness 0.0254)
		(filled_areas_thickness no)
		(fill yes
			(thermal_gap 0.5)
			(thermal_bridge_width 0.5)
			(island_removal_mode 1)
			(island_area_min 10)
		)
		(polygon
			(pts
				(xy 125.2225 143.411715) (xy 125.217946 143.314588) (xy 125.206069 143.244294) (xy 125.190812 143.18744)
				(xy 125.160677 143.062364) (xy 124.94 143.101165) (xy 124.829262 143.295154) (xy 124.900321 143.317267)
				(xy 124.967337 143.32081) (xy 125.017551 143.322931) (xy 125.058975 143.333269) (xy 125.087121 143.360104)
				(xy 125.0975 143.411715)
			)
		)
	)
	(zone
		(net 19)
		(net_name "/M.2 key E/PCIE_{REF}.CK+")
		(layer "F.Cu")
		(name "$teardrop_padvia$")
		(hatch none 0.1)
		(priority 30381)
		(attr
			(teardrop
				(type padvia)
			)
		)
		(connect_pads yes
			(clearance 0)
		)
		(min_thickness 0.0254)
		(filled_areas_thickness no)
		(fill yes
			(thermal_gap 0.5)
			(thermal_bridge_width 0.5)
			(island_removal_mode 1)
			(island_area_min 10)
		)
		(polygon
			(pts
				(xy 154.4085 82.903) (xy 154.252972 82.914103) (xy 154.048818 82.928717) (xy 153.928693 82.92568)
				(xy 153.793966 82.9095) (xy 153.5725 83.0595) (xy 154.3485 83.143279) (xy 154.352977 83.11269) (xy 154.364318 83.099799)
				(xy 154.394331 83.101976) (xy 154.4085 83.105)
			)
		)
	)
	(zone
		(net 121)
		(net_name "/2xSFP+/10GKR_SFP1.TX-")
		(layer "F.Cu")
		(name "$teardrop_padvia$")
		(hatch none 0.1)
		(priority 30908)
		(attr
			(teardrop
				(type padvia)
			)
		)
		(connect_pads yes
			(clearance 0)
		)
		(min_thickness 0.0254)
		(filled_areas_thickness no)
		(fill yes
			(thermal_gap 0.5)
			(thermal_bridge_width 0.5)
			(island_removal_mode 1)
			(island_area_min 10)
		)
		(polygon
			(pts
				(xy 197.045 152.07) (xy 197.044745 152.062548) (xy 197.050791 152.028161) (xy 197.068548 152.015168)
				(xy 197.104123 152.01) (xy 197.025 151.134) (xy 196.875 152.01) (xy 196.892936 152.014466) (xy 196.897965 152.025729)
				(xy 196.890417 152.052612) (xy 196.885 152.07)
			)
		)
	)
	(zone
		(net 1)
		(net_name "GND")
		(layer "F.Cu")
		(name "$teardrop_padvia$")
		(hatch none 0.1)
		(priority 30148)
		(attr
			(teardrop
				(type padvia)
			)
		)
		(connect_pads yes
			(clearance 0)
		)
		(min_thickness 0.0254)
		(filled_areas_thickness no)
		(fill yes
			(thermal_gap 0.5)
			(thermal_bridge_width 0.5)
			(island_removal_mode 1)
			(island_area_min 10)
		)
		(polygon
			(pts
				(xy 307.522425 78.672157) (xy 307.469323 78.775302) (xy 307.425116 78.827492) (xy 307.369963 78.874382)
				(xy 307.31471 78.907033) (xy 307.252296 78.930153) (xy 307.217762 78.937442) (xy 307.549293 79.335707)
				(xy 307.891421 78.943579) (xy 307.777457 78.918672) (xy 307.701995 78.888538) (xy 307.67438 78.866292)
				(xy 307.661823 78.840932) (xy 307.663845 78.813577)
			)
		)
	)
	(zone
		(net 2)
		(net_name "+3V3")
		(layer "F.Cu")
		(name "$teardrop_padvia$")
		(hatch none 0.1)
		(priority 30035)
		(attr
			(teardrop
				(type padvia)
			)
		)
		(connect_pads yes
			(clearance 0)
		)
		(min_thickness 0.0254)
		(filled_areas_thickness no)
		(fill yes
			(thermal_gap 0.5)
			(thermal_bridge_width 0.5)
			(island_removal_mode 1)
			(island_area_min 10)
		)
		(polygon
			(pts
				(xy 110.595 135.46) (xy 110.558269 135.4714) (xy 110.523146 135.484153) (xy 110.489757 135.484992)
				(xy 110.464807 135.459935) (xy 110.455 135.395) (xy 109.504 135.71) (xy 110.455 136.025) (xy 110.459654 135.976031)
				(xy 110.472232 135.947384) (xy 110.504994 135.933036) (xy 110.558269 135.9486) (xy 110.595 135.96)
			)
		)
	)
	(zone
		(net 647)
		(net_name "Net-(Y2-EN)")
		(layer "F.Cu")
		(name "$teardrop_padvia$")
		(hatch none 0.1)
		(priority 30967)
		(attr
			(teardrop
				(type padvia)
			)
		)
		(connect_pads yes
			(clearance 0)
		)
		(min_thickness 0.0254)
		(filled_areas_thickness no)
		(fill yes
			(thermal_gap 0.5)
			(thermal_bridge_width 0.5)
			(island_removal_mode 1)
			(island_area_min 10)
		)
		(polygon
			(pts
				(xy 142.5825 136.318) (xy 142.602469 136.255134) (xy 142.628921 136.223156) (xy 142.666332 136.194642)
				(xy 142.713527 136.172118) (xy 142.771167 136.156907) (xy 142.771798 136.156798) (xy 142.52 135.879)
				(xy 142.268202 136.156798) (xy 142.323635 136.171095) (xy 142.36952 136.192175) (xy 142.407201 136.21954)
				(xy 142.434434 136.250448) (xy 142.451472 136.283735) (xy 142.457489 136.316566) (xy 142.4575 136.318)
			)
		)
	)
	(zone
		(net 872)
		(net_name "Net-(U34-~{KILL})")
		(layer "F.Cu")
		(name "$teardrop_padvia$")
		(hatch none 0.1)
		(priority 31152)
		(attr
			(teardrop
				(type padvia)
			)
		)
		(connect_pads yes
			(clearance 0)
		)
		(min_thickness 0.0254)
		(filled_areas_thickness no)
		(fill yes
			(thermal_gap 0.5)
			(thermal_bridge_width 0.5)
			(island_removal_mode 1)
			(island_area_min 10)
		)
		(polygon
			(pts
				(xy 245.143834 131.129445) (xy 245.135848 131.111243) (xy 245.159825 131.091995) (xy 245.21705 131.07705)
				(xy 245.024293 130.559293) (xy 244.8872 131.104967) (xy 244.950193 131.124029) (xy 245.017329 131.178091)
				(xy 245.038501 131.200167) (xy 245.055446 131.217833)
			)
		)
	)
	(zone
		(net 166)
		(net_name "Net-(J2A-MOD_{ABS})")
		(layer "F.Cu")
		(name "$teardrop_padvia$")
		(hatch none 0.1)
		(priority 31573)
		(attr
			(teardrop
				(type padvia)
			)
		)
		(connect_pads yes
			(clearance 0)
		)
		(min_thickness 0.0254)
		(filled_areas_thickness no)
		(fill yes
			(thermal_gap 0.5)
			(thermal_bridge_width 0.5)
			(island_removal_mode 1)
			(island_area_min 10)
		)
		(polygon
			(pts
				(xy 144.125215 167.625714) (xy 144.083348 167.660882) (xy 144.044725 167.680898) (xy 143.97176 167.69038)
				(xy 143.933481 167.68725) (xy 143.874938 167.68327) (xy 143.806737 167.689323) (xy 143.849293 167.910707)
				(xy 144.044397 168.01734) (xy 144.09523 167.90162) (xy 144.132975 167.815137) (xy 144.213603 167.714102)
			)
		)
	)
	(zone
		(net 663)
		(net_name "Net-(U43C-ST)")
		(layer "F.Cu")
		(name "$teardrop_padvia$")
		(hatch none 0.1)
		(priority 31074)
		(attr
			(teardrop
				(type padvia)
			)
		)
		(connect_pads yes
			(clearance 0)
		)
		(min_thickness 0.0254)
		(filled_areas_thickness no)
		(fill yes
			(thermal_gap 0.5)
			(thermal_bridge_width 0.5)
			(island_removal_mode 1)
			(island_area_min 10)
		)
		(polygon
			(pts
				(xy 143.893 134.8175) (xy 143.833588 134.797727) (xy 143.777503 134.734453) (xy 143.755801 134.685828)
				(xy 143.741127 134.626468) (xy 143.739347 134.6145) (xy 143.479 134.88) (xy 143.739347 135.1455)
				(xy 143.752197 135.085361) (xy 143.772131 135.035477) (xy 143.798056 134.995358) (xy 143.827876 134.966345)
				(xy 143.859294 134.948854) (xy 143.891105 134.942521) (xy 143.893 134.9425)
			)
		)
	)
	(zone
		(net 1)
		(net_name "GND")
		(layer "F.Cu")
		(name "$teardrop_padvia$")
		(hatch none 0.1)
		(priority 30525)
		(attr
			(teardrop
				(type padvia)
			)
		)
		(connect_pads yes
			(clearance 0)
		)
		(min_thickness 0.0254)
		(filled_areas_thickness no)
		(fill yes
			(thermal_gap 0.5)
			(thermal_bridge_width 0.5)
			(island_removal_mode 1)
			(island_area_min 10)
		)
		(polygon
			(pts
				(xy 195.925 155.75) (xy 195.928333 155.764486) (xy 195.93119 155.79461) (xy 195.919036 155.805651)
				(xy 195.89 155.81) (xy 196.025 156.686) (xy 196.16 155.81) (xy 196.130666 155.805525) (xy 196.118642 155.794199)
				(xy 196.121667 155.764486) (xy 196.125 155.75)
			)
		)
	)
	(zone
		(net 554)
		(net_name "/2xUSB3.0+RJ45/FLG_2B")
		(layer "F.Cu")
		(name "$teardrop_padvia$")
		(hatch none 0.1)
		(priority 30075)
		(attr
			(teardrop
				(type padvia)
			)
		)
		(connect_pads yes
			(clearance 0)
		)
		(min_thickness 0.0254)
		(filled_areas_thickness no)
		(fill yes
			(thermal_gap 0.5)
			(thermal_bridge_width 0.5)
			(island_removal_mode 1)
			(island_area_min 10)
		)
		(polygon
			(pts
				(xy 116.339 92.6515) (xy 116.283736 92.632104) (xy 116.234452 92.570761) (xy 116.202899 92.462049)
				(xy 116.199 92.399) (xy 115.598 92.714) (xy 116.199 93.029) (xy 116.203756 92.959663) (xy 116.217044 92.900293)
				(xy 116.237444 92.851557) (xy 116.263462 92.814336) (xy 116.291726 92.79052) (xy 116.322426 92.778176)
				(xy 116.339 92.7765)
			)
		)
	)
	(zone
		(net 350)
		(net_name "Net-(J12D-LPC_AD1{slash}ESPI_IO_1)")
		(layer "F.Cu")
		(name "$teardrop_padvia$")
		(hatch none 0.1)
		(priority 31614)
		(attr
			(teardrop
				(type padvia)
			)
		)
		(connect_pads yes
			(clearance 0)
		)
		(min_thickness 0.0254)
		(filled_areas_thickness no)
		(fill yes
			(thermal_gap 0.5)
			(thermal_bridge_width 0.5)
			(island_removal_mode 1)
			(island_area_min 10)
		)
		(polygon
			(pts
				(xy 177.9625 164.099323) (xy 177.957747 164.160452) (xy 177.94448 164.206552) (xy 177.899229 164.273244)
				(xy 177.88137 164.292341) (xy 177.812919 164.374997) (xy 178 164.501) (xy 178.207644 164.424641)
				(xy 178.149334 164.309581) (xy 178.105855 164.22547) (xy 178.092451 164.171061) (xy 178.0875 164.099323)
			)
		)
	)
	(zone
		(net 74)
		(net_name "+1V0")
		(layer "F.Cu")
		(name "$teardrop_padvia$")
		(hatch none 0.1)
		(priority 30847)
		(attr
			(teardrop
				(type padvia)
			)
		)
		(connect_pads yes
			(clearance 0)
		)
		(min_thickness 0.0254)
		(filled_areas_thickness no)
		(fill yes
			(thermal_gap 0.5)
			(thermal_bridge_width 0.5)
			(island_removal_mode 1)
			(island_area_min 10)
		)
		(polygon
			(pts
				(xy 202.38239 82.909837) (xy 202.37618 82.956048) (xy 202.352713 83.004447) (xy 202.324806 83.032803)
				(xy 202.28458 83.055849) (xy 202.230592 83.071039) (xy 202.48239 83.348837) (xy 202.734188 83.071039)
				(xy 202.685336 83.057906) (xy 202.647826 83.038502) (xy 202.600403 82.985892) (xy 202.582647 82.919391)
				(xy 202.58239 82.909837)
			)
		)
	)
	(zone
		(net 128)
		(net_name "/USB-C console/FTDI_LED_TX")
		(layer "F.Cu")
		(name "$teardrop_padvia$")
		(hatch none 0.1)
		(priority 30171)
		(attr
			(teardrop
				(type padvia)
			)
		)
		(connect_pads yes
			(clearance 0)
		)
		(min_thickness 0.0254)
		(filled_areas_thickness no)
		(fill yes
			(thermal_gap 0.5)
			(thermal_bridge_width 0.5)
			(island_removal_mode 1)
			(island_area_min 10)
		)
		(polygon
			(pts
				(xy 110.9625 71.12) (xy 110.981757 71.06156) (xy 111.042765 71.007485) (xy 111.152366 70.967203)
				(xy 111.26 70.956021) (xy 110.9 70.559) (xy 110.54 70.956021) (xy 110.615789 70.961642) (xy 110.682251 70.975856)
				(xy 110.73852 70.997451) (xy 110.783209 71.025051) (xy 110.813499 71.055041) (xy 110.831876 71.088017)
				(xy 110.8375 71.12)
			)
		)
	)
	(zone
		(net 1)
		(net_name "GND")
		(layer "F.Cu")
		(name "$teardrop_padvia$")
		(hatch none 0.1)
		(priority 30551)
		(attr
			(teardrop
				(type padvia)
			)
		)
		(connect_pads yes
			(clearance 0)
		)
		(min_thickness 0.0254)
		(filled_areas_thickness no)
		(fill yes
			(thermal_gap 0.5)
			(thermal_bridge_width 0.5)
			(island_removal_mode 1)
			(island_area_min 10)
		)
		(polygon
			(pts
				(xy 211.925 150.2) (xy 211.928333 150.214486) (xy 211.93119 150.24461) (xy 211.919036 150.255651)
				(xy 211.89 150.26) (xy 212.025 151.136) (xy 212.16 150.26) (xy 212.130666 150.255525) (xy 212.118642 150.244199)
				(xy 212.121667 150.214486) (xy 212.125 150.2)
			)
		)
	)
	(zone
		(net 68)
		(net_name "Net-(U19-BST)")
		(layer "F.Cu")
		(name "$teardrop_padvia$")
		(hatch none 0.1)
		(priority 32139)
		(attr
			(teardrop
				(type padvia)
			)
		)
		(connect_pads yes
			(clearance 0)
		)
		(min_thickness 0.0254)
		(filled_areas_thickness no)
		(fill yes
			(thermal_gap 0.5)
			(thermal_bridge_width 0.5)
			(island_removal_mode 1)
			(island_area_min 10)
		)
		(polygon
			(pts
				(xy 313.453078 105.589499) (xy 313.434859 105.59104) (xy 313.392335 105.591334) (xy 313.370632 105.582494)
				(xy 313.350639 105.562602) (xy 313.113999 105.653999) (xy 313.357476 105.742564) (xy 313.374853 105.722883)
				(xy 313.394153 105.713573) (xy 313.436352 105.713084) (xy 313.453078 105.714499)
			)
		)
	)
	(zone
		(net 697)
		(net_name "Net-(U5-IO0_6)")
		(layer "F.Cu")
		(name "$teardrop_padvia$")
		(hatch none 0.1)
		(priority 32005)
		(attr
			(teardrop
				(type padvia)
			)
		)
		(connect_pads yes
			(clearance 0)
		)
		(min_thickness 0.0254)
		(filled_areas_thickness no)
		(fill yes
			(thermal_gap 0.5)
			(thermal_bridge_width 0.5)
			(island_removal_mode 1)
			(island_area_min 10)
		)
		(polygon
			(pts
				(xy 158.1125 163.0095) (xy 158.112404 163.003178) (xy 158.117989 162.963675) (xy 158.132922 162.945452)
				(xy 158.1625 162.932504) (xy 158.05 162.546) (xy 157.9375 162.932504) (xy 157.964493 162.94362)
				(xy 157.979595 162.959147) (xy 157.987596 163.003178) (xy 157.9875 163.0095)
			)
		)
	)
	(zone
		(net 1)
		(net_name "GND")
		(layer "F.Cu")
		(name "$teardrop_padvia$")
		(hatch none 0.1)
		(priority 31262)
		(attr
			(teardrop
				(type padvia)
			)
		)
		(connect_pads yes
			(clearance 0)
		)
		(min_thickness 0.0254)
		(filled_areas_thickness no)
		(fill yes
			(thermal_gap 0.5)
			(thermal_bridge_width 0.5)
			(island_removal_mode 1)
			(island_area_min 10)
		)
		(polygon
			(pts
				(xy 181.125 150.375677) (xy 181.129713 150.297764) (xy 181.1427 150.23898) (xy 181.184802 150.147947)
				(xy 181.2275 150.062778) (xy 181.025 149.974) (xy 180.8225 150.062778) (xy 180.865198 150.147949)
				(xy 180.907867 150.240783) (xy 180.920444 150.298922) (xy 180.925 150.375677)
			)
		)
	)
	(zone
		(net 52)
		(net_name "+5V")
		(layer "F.Cu")
		(name "$teardrop_padvia$")
		(hatch none 0.1)
		(priority 30160)
		(attr
			(teardrop
				(type padvia)
			)
		)
		(connect_pads yes
			(clearance 0)
		)
		(min_thickness 0.0254)
		(filled_areas_thickness no)
		(fill yes
			(thermal_gap 0.5)
			(thermal_bridge_width 0.5)
			(island_removal_mode 1)
			(island_area_min 10)
		)
		(polygon
			(pts
				(xy 195.60861 73.542163) (xy 195.60355 73.575682) (xy 195.588129 73.608588) (xy 195.562347 73.6389)
				(xy 195.525738 73.665407) (xy 195.478562 73.68631) (xy 195.420127 73.700395) (xy 195.34861 73.706141)
				(xy 195.70861 74.103163) (xy 196.06861 73.706141) (xy 195.998539 73.700621) (xy 195.940004 73.686759)
				(xy 195.892657 73.666073) (xy 195.856184 73.640095) (xy 195.8301 73.610127) (xy 195.814368 73.577901)
				(xy 195.80861 73.542163)
			)
		)
	)
	(zone
		(net 523)
		(net_name "Net-(J13-Pad1)")
		(layer "F.Cu")
		(name "$teardrop_padvia$")
		(hatch none 0.1)
		(priority 30008)
		(attr
			(teardrop
				(type padvia)
			)
		)
		(connect_pads yes
			(clearance 0)
		)
		(min_thickness 0.0254)
		(filled_areas_thickness no)
		(fill yes
			(thermal_gap 0.5)
			(thermal_bridge_width 0.5)
			(island_removal_mode 1)
			(island_area_min 10)
		)
		(polygon
			(pts
				(xy 216.52 71.8) (xy 216.539338 71.716751) (xy 216.598984 71.636679) (xy 216.706024 71.561573) (xy 216.866034 71.499937)
				(xy 217.074718 71.464374) (xy 217.185 71.46) (xy 216.42 70.609) (xy 215.655 71.46) (xy 215.771187 71.464864)
				(xy 215.879608 71.478913) (xy 215.979947 71.501589) (xy 216.069823 71.531961) (xy 216.145409 71.567763)
				(xy 216.208923 71.60919) (xy 216.255513 71.651414) (xy 216.290138 71.697144) (xy 216.310238 71.740503)
				(xy 216.319452 71.785788) (xy 216.32 71.8)
			)
		)
	)
	(zone
		(net 1)
		(net_name "GND")
		(layer "F.Cu")
		(name "$teardrop_padvia$")
		(hatch none 0.1)
		(priority 30584)
		(attr
			(teardrop
				(type padvia)
			)
		)
		(connect_pads yes
			(clearance 0)
		)
		(min_thickness 0.0254)
		(filled_areas_thickness no)
		(fill yes
			(thermal_gap 0.5)
			(thermal_bridge_width 0.5)
			(island_removal_mode 1)
			(island_area_min 10)
		)
		(polygon
			(pts
				(xy 180.925 162.2) (xy 180.928333 162.214486) (xy 180.93119 162.24461) (xy 180.919036 162.255651)
				(xy 180.89 162.26) (xy 181.025 163.136) (xy 181.16 162.26) (xy 181.130666 162.255525) (xy 181.118642 162.244199)
				(xy 181.121667 162.214486) (xy 181.125 162.2)
			)
		)
	)
	(zone
		(net 4)
		(net_name "/M.2 key E/WIFI_BT_USB_D_N")
		(layer "F.Cu")
		(name "$teardrop_padvia$")
		(hatch none 0.1)
		(priority 30411)
		(attr
			(teardrop
				(type padvia)
			)
		)
		(connect_pads yes
			(clearance 0)
		)
		(min_thickness 0.0254)
		(filled_areas_thickness no)
		(fill yes
			(thermal_gap 0.5)
			(thermal_bridge_width 0.5)
			(island_removal_mode 1)
			(island_area_min 10)
		)
		(polygon
			(pts
				(xy 154.4085 71.906) (xy 154.252283 71.915405) (xy 154.041239 71.927786) (xy 153.916698 71.924281)
				(xy 153.776657 71.9085) (xy 153.5725 72.0585) (xy 154.3485 72.138153) (xy 154.352984 72.106233)
				(xy 154.364373 72.091237) (xy 154.396394 72.089459) (xy 154.4085 72.091)
			)
		)
	)
	(zone
		(net 336)
		(net_name "/Com Express 7 Interfaces/PCIE_{REF}.CK+")
		(layer "F.Cu")
		(name "$teardrop_padvia$")
		(hatch none 0.1)
		(priority 31360)
		(attr
			(teardrop
				(type padvia)
			)
		)
		(connect_pads yes
			(clearance 0)
		)
		(min_thickness 0.0254)
		(filled_areas_thickness no)
		(fill yes
			(thermal_gap 0.5)
			(thermal_bridge_width 0.5)
			(island_removal_mode 1)
			(island_area_min 10)
		)
		(polygon
			(pts
				(xy 215.5745 122.967496) (xy 215.579235 122.92071) (xy 215.592379 122.885257) (xy 215.637387 122.83706)
				(xy 215.675608 122.812883) (xy 215.718774 122.785514) (xy 215.760731 122.748852) (xy 215.5975 122.599)
				(xy 215.376823 122.619859) (xy 215.381452 122.720536) (xy 215.378019 122.803908) (xy 215.377895 122.805963)
				(xy 215.3725 122.967496)
			)
		)
	)
	(zone
		(net 2)
		(net_name "+3V3")
		(layer "F.Cu")
		(name "$teardrop_padvia$")
		(hatch none 0.1)
		(priority 31016)
		(attr
			(teardrop
				(type padvia)
			)
		)
		(connect_pads yes
			(clearance 0)
		)
		(min_thickness 0.0254)
		(filled_areas_thickness no)
		(fill yes
			(thermal_gap 0.5)
			(thermal_bridge_width 0.5)
			(island_removal_mode 1)
			(island_area_min 10)
		)
		(polygon
			(pts
				(xy 193.03621 129.419) (xy 193.005878 129.360427) (xy 193.001971 129.319111) (xy 193.008262 129.272495)
				(xy 193.025707 129.223196) (xy 193.055709 129.171683) (xy 193.056078 129.17116) (xy 192.681597 129.152775)
				(xy 192.699982 129.527256) (xy 192.749288 129.498168) (xy 192.796639 129.480629) (xy 192.842634 129.473334)
				(xy 192.883746 129.475933) (xy 192.919331 129.487422) (xy 192.9468 129.506382) (xy 192.947822 129.507388)
			)
		)
	)
	(zone
		(net 585)
		(net_name "Net-(U21-FB)")
		(layer "F.Cu")
		(name "$teardrop_padvia$")
		(hatch none 0.1)
		(priority 32037)
		(attr
			(teardrop
				(type padvia)
			)
		)
		(connect_pads yes
			(clearance 0)
		)
		(min_thickness 0.0254)
		(filled_areas_thickness no)
		(fill yes
			(thermal_gap 0.5)
			(thermal_bridge_width 0.5)
			(island_removal_mode 1)
			(island_area_min 10)
		)
		(polygon
			(pts
				(xy 312.962 96.2435) (xy 312.970761 96.196797) (xy 312.990287 96.175285) (xy 313.027533 96.161533)
				(xy 312.8995 95.8825) (xy 312.771467 96.161533) (xy 312.802235 96.17142) (xy 312.82146 96.186683)
				(xy 312.836394 96.226635) (xy 312.837 96.2435)
			)
		)
	)
	(zone
		(net 556)
		(net_name "/2xUSB3.0+RJ45/EN_2B")
		(layer "F.Cu")
		(name "$teardrop_padvia$")
		(hatch none 0.1)
		(priority 31030)
		(attr
			(teardrop
				(type padvia)
			)
		)
		(connect_pads yes
			(clearance 0)
		)
		(min_thickness 0.0254)
		(filled_areas_thickness no)
		(fill yes
			(thermal_gap 0.5)
			(thermal_bridge_width 0.5)
			(island_removal_mode 1)
			(island_area_min 10)
		)
		(polygon
			(pts
				(xy 121.5075 90.522001) (xy 121.487531 90.584866) (xy 121.461079 90.616844) (xy 121.423668 90.645359)
				(xy 121.376472 90.667883) (xy 121.318832 90.683093) (xy 121.318202 90.683202) (xy 121.57 90.960999)
				(xy 121.821798 90.683202) (xy 121.766365 90.668905) (xy 121.72048 90.647825) (xy 121.682798 90.62046)
				(xy 121.655565 90.589551) (xy 121.638527 90.556265) (xy 121.63251 90.523434) (xy 121.632499 90.522)
			)
		)
	)
	(zone
		(net 9)
		(net_name "/Com Express 7 Interfaces/PCIe_{B1x2}.TX0+")
		(layer "F.Cu")
		(name "$teardrop_padvia$")
		(hatch none 0.1)
		(priority 30382)
		(attr
			(teardrop
				(type padvia)
			)
		)
		(connect_pads yes
			(clearance 0)
		)
		(min_thickness 0.0254)
		(filled_areas_thickness no)
		(fill yes
			(thermal_gap 0.5)
			(thermal_bridge_width 0.5)
			(island_removal_mode 1)
			(island_area_min 10)
		)
		(polygon
			(pts
				(xy 154.4085 79.903) (xy 154.252972 79.914103) (xy 154.048818 79.928717) (xy 153.928693 79.92568)
				(xy 153.793966 79.9095) (xy 153.5725 80.0595) (xy 154.3485 80.143279) (xy 154.352977 80.11269) (xy 154.364318 80.099799)
				(xy 154.394331 80.101976) (xy 154.4085 80.105)
			)
		)
	)
	(zone
		(net 382)
		(net_name "Net-(J12D-~{CB_RESET})")
		(layer "F.Cu")
		(name "$teardrop_padvia$")
		(hatch none 0.1)
		(priority 30979)
		(attr
			(teardrop
				(type padvia)
			)
		)
		(connect_pads yes
			(clearance 0)
		)
		(min_thickness 0.0254)
		(filled_areas_thickness no)
		(fill yes
			(thermal_gap 0.5)
			(thermal_bridge_width 0.5)
			(island_removal_mode 1)
			(island_area_min 10)
		)
		(polygon
			(pts
				(xy 306.212 156.2525) (xy 306.274866 156.272469) (xy 306.306844 156.298921) (xy 306.335358 156.336332)
				(xy 306.357882 156.383527) (xy 306.373093 156.441167) (xy 306.373202 156.441798) (xy 306.651 156.19)
				(xy 306.373202 155.938202) (xy 306.358905 155.993635) (xy 306.337825 156.03952) (xy 306.31046 156.077201)
				(xy 306.279552 156.104434) (xy 306.246265 156.121472) (xy 306.213434 156.127489) (xy 306.212 156.1275)
			)
		)
	)
	(zone
		(net 434)
		(net_name "/Com Express 7 MGMT/~{TYPE1}")
		(layer "F.Cu")
		(name "$teardrop_padvia$")
		(hatch none 0.1)
		(priority 31078)
		(attr
			(teardrop
				(type padvia)
			)
		)
		(connect_pads yes
			(clearance 0)
		)
		(min_thickness 0.0254)
		(filled_areas_thickness no)
		(fill yes
			(thermal_gap 0.5)
			(thermal_bridge_width 0.5)
			(island_removal_mode 1)
			(island_area_min 10)
		)
		(polygon
			(pts
				(xy 247.8875 133.253) (xy 247.907273 133.193588) (xy 247.970547 133.137503) (xy 248.019172 133.115801)
				(xy 248.078532 133.101127) (xy 248.0905 133.099347) (xy 247.825 132.839) (xy 247.5595 133.099347)
				(xy 247.619639 133.112197) (xy 247.669523 133.132131) (xy 247.709642 133.158056) (xy 247.738655 133.187876)
				(xy 247.756146 133.219294) (xy 247.762479 133.251105) (xy 247.7625 133.253)
			)
		)
	)
	(zone
		(net 73)
		(net_name "+3V3_AON")
		(layer "F.Cu")
		(name "$teardrop_padvia$")
		(hatch none 0.1)
		(priority 31558)
		(attr
			(teardrop
				(type padvia)
			)
		)
		(connect_pads yes
			(clearance 0)
		)
		(min_thickness 0.0254)
		(filled_areas_thickness no)
		(fill yes
			(thermal_gap 0.5)
			(thermal_bridge_width 0.5)
			(island_removal_mode 1)
			(island_area_min 10)
		)
		(polygon
			(pts
				(xy 250.317 132.432) (xy 250.325249 132.454077) (xy 250.335983 132.492572) (xy 250.323018 132.506525)
				(xy 250.287 132.512) (xy 250.467 132.888) (xy 250.647 132.512) (xy 250.613265 132.50746) (xy 250.599072 132.495677)
				(xy 250.602554 132.467183) (xy 250.608751 132.454077) (xy 250.617 132.432)
			)
		)
	)
	(zone
		(net 743)
		(net_name "/2xSFP+/KR to SFI #2/TDO")
		(layer "F.Cu")
		(name "$teardrop_padvia$")
		(hatch none 0.1)
		(priority 31694)
		(attr
			(teardrop
				(type padvia)
			)
		)
		(connect_pads yes
			(clearance 0)
		)
		(min_thickness 0.0254)
		(filled_areas_thickness no)
		(fill yes
			(thermal_gap 0.5)
			(thermal_bridge_width 0.5)
			(island_removal_mode 1)
			(island_area_min 10)
		)
		(polygon
			(pts
				(xy 133.5775 129.739323) (xy 133.572682 129.808763) (xy 133.55896 129.860087) (xy 133.512245 129.935628)
				(xy 133.502702 129.947768) (xy 133.452919 130.014997) (xy 133.64 130.141) (xy 133.827081 130.014997)
				(xy 133.777299 129.947769) (xy 133.722894 129.864603) (xy 133.70781 129.811748) (xy 133.7025 129.739323)
			)
		)
	)
	(zone
		(net 342)
		(net_name "Net-(J12D-TPM_PP)")
		(layer "F.Cu")
		(name "$teardrop_padvia$")
		(hatch none 0.1)
		(priority 31881)
		(attr
			(teardrop
				(type padvia)
			)
		)
		(connect_pads yes
			(clearance 0)
		)
		(min_thickness 0.0254)
		(filled_areas_thickness no)
		(fill yes
			(thermal_gap 0.5)
			(thermal_bridge_width 0.5)
			(island_removal_mode 1)
			(island_area_min 10)
		)
		(polygon
			(pts
				(xy 223.527515 165.489127) (xy 223.481819 165.436618) (xy 223.455231 165.390623) (xy 223.434847 165.304175)
				(xy 223.433011 165.28884) (xy 223.420677 165.206105) (xy 223.199293 165.249293) (xy 223.156105 165.470677)
				(xy 223.23884 165.483011) (xy 223.336119 165.503349) (xy 223.384159 165.530057) (xy 223.439127 165.577515)
			)
		)
	)
	(zone
		(net 73)
		(net_name "+3V3_AON")
		(layer "F.Cu")
		(name "$teardrop_padvia$")
		(hatch none 0.1)
		(priority 30935)
		(attr
			(teardrop
				(type padvia)
			)
		)
		(connect_pads yes
			(clearance 0)
		)
		(min_thickness 0.0254)
		(filled_areas_thickness no)
		(fill yes
			(thermal_gap 0.5)
			(thermal_bridge_width 0.5)
			(island_removal_mode 1)
			(island_area_min 10)
		)
		(polygon
			(pts
				(xy 236.262 154.0425) (xy 236.324866 154.062469) (xy 236.356844 154.088921) (xy 236.385358 154.126332)
				(xy 236.407882 154.173527) (xy 236.423093 154.231167) (xy 236.423202 154.231798) (xy 236.701 153.98)
				(xy 236.423202 153.728202) (xy 236.408905 153.783635) (xy 236.387825 153.82952) (xy 236.36046 153.867201)
				(xy 236.329552 153.894434) (xy 236.296265 153.911472) (xy 236.263434 153.917489) (xy 236.262 153.9175)
			)
		)
	)
	(zone
		(net 727)
		(net_name "Net-(U43C-PRBS_{PASS})")
		(layer "F.Cu")
		(name "$teardrop_padvia$")
		(hatch none 0.1)
		(priority 31712)
		(attr
			(teardrop
				(type padvia)
			)
		)
		(connect_pads yes
			(clearance 0)
		)
		(min_thickness 0.0254)
		(filled_areas_thickness no)
		(fill yes
			(thermal_gap 0.5)
			(thermal_bridge_width 0.5)
			(island_removal_mode 1)
			(island_area_min 10)
		)
		(polygon
			(pts
				(xy 149.1375 129.739323) (xy 149.132682 129.808763) (xy 149.11896 129.860087) (xy 149.072245 129.935628)
				(xy 149.062702 129.947768) (xy 149.012919 130.014997) (xy 149.2 130.141) (xy 149.387081 130.014997)
				(xy 149.337299 129.947769) (xy 149.282894 129.864603) (xy 149.26781 129.811748) (xy 149.2625 129.739323)
			)
		)
	)
	(zone
		(net 397)
		(net_name "/Com Express 7 MGMT/SPI.~{CS}")
		(layer "F.Cu")
		(name "$teardrop_padvia$")
		(hatch none 0.1)
		(priority 30064)
		(attr
			(teardrop
				(type padvia)
			)
		)
		(connect_pads yes
			(clearance 0)
		)
		(min_thickness 0.0254)
		(filled_areas_thickness no)
		(fill yes
			(thermal_gap 0.5)
			(thermal_bridge_width 0.5)
			(island_removal_mode 1)
			(island_area_min 10)
		)
		(polygon
			(pts
				(xy 257.478145 163.77) (xy 257.413595 163.750237) (xy 257.380018 163.723799) (xy 257.349498 163.686581)
				(xy 257.323902 163.63874) (xy 257.305163 163.580528) (xy 257.30055 163.557595) (xy 256.522145 163.835)
				(xy 257.30055 164.112405) (xy 257.315508 164.053222) (xy 257.337393 164.003395) (xy 257.365763 163.961663)
				(xy 257.397998 163.93049) (xy 257.432666 163.909902) (xy 257.467462 163.900572) (xy 257.478145 163.9)
			)
		)
	)
	(zone
		(net 590)
		(net_name "Net-(U24-+2.5V_{IN})")
		(layer "F.Cu")
		(name "$teardrop_padvia$")
		(hatch none 0.1)
		(priority 30713)
		(attr
			(teardrop
				(type padvia)
			)
		)
		(connect_pads yes
			(clearance 0)
		)
		(min_thickness 0.0254)
		(filled_areas_thickness no)
		(fill yes
			(thermal_gap 0.5)
			(thermal_bridge_width 0.5)
			(island_removal_mode 1)
			(island_area_min 10)
		)
		(polygon
			(pts
				(xy 254.056 88.369999) (xy 254.060806 88.36997) (xy 254.08628 88.371149) (xy 254.112048 88.380737)
				(xy 254.131993 88.407198) (xy 254.14 88.458999) (xy 254.701 88.27) (xy 254.14 88.080999) (xy 254.13542 88.122301)
				(xy 254.123361 88.148368) (xy 254.088848 88.168426) (xy 254.060806 88.170028) (xy 254.056 88.169999)
			)
		)
	)
	(zone
		(net 1)
		(net_name "GND")
		(layer "F.Cu")
		(name "$teardrop_padvia$")
		(hatch none 0.1)
		(priority 30734)
		(attr
			(teardrop
				(type padvia)
			)
		)
		(connect_pads yes
			(clearance 0)
		)
		(min_thickness 0.0254)
		(filled_areas_thickness no)
		(fill yes
			(thermal_gap 0.5)
			(thermal_bridge_width 0.5)
			(island_removal_mode 1)
			(island_area_min 10)
		)
		(polygon
			(pts
				(xy 302.8875 91.9) (xy 302.892821 91.868265) (xy 302.910069 91.835565) (xy 302.936538 91.809374)
				(xy 302.974964 91.788445) (xy 303.01705 91.77705) (xy 302.825 91.259) (xy 302.63295 91.77705) (xy 302.677474 91.789409)
				(xy 302.7116 91.808008) (xy 302.753536 91.858803) (xy 302.7625 91.9)
			)
		)
	)
	(zone
		(net 783)
		(net_name "/Misc/PWM_{B3V3}")
		(layer "F.Cu")
		(name "$teardrop_padvia$")
		(hatch none 0.1)
		(priority 30354)
		(attr
			(teardrop
				(type padvia)
			)
		)
		(connect_pads yes
			(clearance 0)
		)
		(min_thickness 0.0254)
		(filled_areas_thickness no)
		(fill yes
			(thermal_gap 0.5)
			(thermal_bridge_width 0.5)
			(island_removal_mode 1)
			(island_area_min 10)
		)
		(polygon
			(pts
				(xy 245.737709 79.1345) (xy 245.771572 79.140281) (xy 245.806193 79.160745) (xy 245.828015 79.18781)
				(xy 245.843709 79.22715) (xy 245.846998 79.242711) (xy 246.553709 79.072) (xy 245.846998 78.901289)
				(xy 245.835409 78.94151) (xy 245.817825 78.970984) (xy 245.770243 79.004173) (xy 245.737709 79.0095)
			)
		)
	)
	(zone
		(net 872)
		(net_name "Net-(U34-~{KILL})")
		(layer "F.Cu")
		(name "$teardrop_padvia$")
		(hatch none 0.1)
		(priority 30916)
		(attr
			(teardrop
				(type padvia)
			)
		)
		(connect_pads yes
			(clearance 0)
		)
		(min_thickness 0.0254)
		(filled_areas_thickness no)
		(fill yes
			(thermal_gap 0.5)
			(thermal_bridge_width 0.5)
			(island_removal_mode 1)
			(island_area_min 10)
		)
		(polygon
			(pts
				(xy 246.238 131.8175) (xy 246.176062 131.797624) (xy 246.14455 131.7712) (xy 246.116373 131.733909)
				(xy 246.0935 131.686024) (xy 246.077733 131.627556) (xy 246.076798 131.622201) (xy 245.799 131.873999)
				(xy 246.076798 132.125797) (xy 246.090987 132.072279) (xy 246.111931 132.028048) (xy 246.170205 131.965096)
				(xy 246.203891 131.948344) (xy 246.236827 131.942507) (xy 246.238 131.9425)
			)
		)
	)
	(zone
		(net 1)
		(net_name "GND")
		(layer "F.Cu")
		(name "$teardrop_padvia$")
		(hatch none 0.1)
		(priority 30596)
		(attr
			(teardrop
				(type padvia)
			)
		)
		(connect_pads yes
			(clearance 0)
		)
		(min_thickness 0.0254)
		(filled_areas_thickness no)
		(fill yes
			(thermal_gap 0.5)
			(thermal_bridge_width 0.5)
			(island_removal_mode 1)
			(island_area_min 10)
		)
		(polygon
			(pts
				(xy 212.125 164.07) (xy 212.121667 164.055514) (xy 212.11881 164.02539) (xy 212.130964 164.014349)
				(xy 212.16 164.01) (xy 212.025 163.134) (xy 211.89 164.01) (xy 211.919334 164.014475) (xy 211.931358 164.025801)
				(xy 211.928333 164.055514) (xy 211.925 164.07)
			)
		)
	)
	(zone
		(net 382)
		(net_name "Net-(J12D-~{CB_RESET})")
		(layer "F.Cu")
		(name "$teardrop_padvia$")
		(hatch none 0.1)
		(priority 31571)
		(attr
			(teardrop
				(type padvia)
			)
		)
		(connect_pads yes
			(clearance 0)
		)
		(min_thickness 0.0254)
		(filled_areas_thickness no)
		(fill yes
			(thermal_gap 0.5)
			(thermal_bridge_width 0.5)
			(island_removal_mode 1)
			(island_area_min 10)
		)
		(polygon
			(pts
				(xy 286.498148 153.2875) (xy 286.442375 153.282762) (xy 286.399937 153.269598) (xy 286.339854 153.224675)
				(xy 286.315668 153.197582) (xy 286.276941 153.155366) (xy 286.225003 153.112919) (xy 286.099 153.3)
				(xy 286.164229 153.512254) (xy 286.281874 153.463974) (xy 286.369504 153.427706) (xy 286.498148 153.4125)
			)
		)
	)
	(zone
		(net 2)
		(net_name "+3V3")
		(layer "F.Cu")
		(name "$teardrop_padvia$")
		(hatch none 0.1)
		(priority 31257)
		(attr
			(teardrop
				(type padvia)
			)
		)
		(connect_pads yes
			(clearance 0)
		)
		(min_thickness 0.0254)
		(filled_areas_thickness no)
		(fill yes
			(thermal_gap 0.5)
			(thermal_bridge_width 0.5)
			(island_removal_mode 1)
			(island_area_min 10)
		)
		(polygon
			(pts
				(xy 159.65 157.690677) (xy 159.654713 157.612764) (xy 159.6677 157.55398) (xy 159.709802 157.462947)
				(xy 159.7525 157.377778) (xy 159.55 157.289) (xy 159.3475 157.377778) (xy 159.390198 157.462949)
				(xy 159.432867 157.555783) (xy 159.445444 157.613922) (xy 159.45 157.690677)
			)
		)
	)
	(zone
		(net 1)
		(net_name "GND")
		(layer "F.Cu")
		(name "$teardrop_padvia$")
		(hatch none 0.1)
		(priority 31927)
		(attr
			(teardrop
				(type padvia)
			)
		)
		(connect_pads yes
			(clearance 0)
		)
		(min_thickness 0.0254)
		(filled_areas_thickness no)
		(fill yes
			(thermal_gap 0.5)
			(thermal_bridge_width 0.5)
			(island_removal_mode 1)
			(island_area_min 10)
		)
		(polygon
			(pts
				(xy 315.49 160.81) (xy 315.479885 160.810153) (xy 315.449169 160.80954) (xy 315.41668 160.801218)
				(xy 315.387526 160.777325) (xy 315.366809 160.73) (xy 315.134 160.91) (xy 315.366809 161.09) (xy 315.380168 161.054099)
				(xy 315.398399 161.030801) (xy 315.443725 161.011101) (xy 315.479885 161.009847) (xy 315.49 161.01)
			)
		)
	)
	(zone
		(net 567)
		(net_name "/2xSFP+/~{LED1_2}")
		(layer "F.Cu")
		(name "$teardrop_padvia$")
		(hatch none 0.1)
		(priority 32011)
		(attr
			(teardrop
				(type padvia)
			)
		)
		(connect_pads yes
			(clearance 0)
		)
		(min_thickness 0.0254)
		(filled_areas_thickness no)
		(fill yes
			(thermal_gap 0.5)
			(thermal_bridge_width 0.5)
			(island_removal_mode 1)
			(island_area_min 10)
		)
		(polygon
			(pts
				(xy 156.8995 161.9215) (xy 156.905822 161.921404) (xy 156.945325 161.926989) (xy 156.963547 161.941922)
				(xy 156.976495 161.9715) (xy 157.363 161.859) (xy 156.976495 161.7465) (xy 156.965379 161.773493)
				(xy 156.949852 161.788595) (xy 156.905822 161.796596) (xy 156.8995 161.7965)
			)
		)
	)
	(zone
		(net 78)
		(net_name "+1V8")
		(layer "F.Cu")
		(name "$teardrop_padvia$")
		(hatch none 0.1)
		(priority 30088)
		(attr
			(teardrop
				(type padvia)
			)
		)
		(connect_pads yes
			(clearance 0)
		)
		(min_thickness 0.0254)
		(filled_areas_thickness no)
		(fill yes
			(thermal_gap 0.5)
			(thermal_bridge_width 0.5)
			(island_removal_mode 1)
			(island_area_min 10)
		)
		(polygon
			(pts
				(xy 200.376404 72.702163) (xy 200.285027 72.697312) (xy 200.213098 72.683354) (xy 200.111548 72.636414)
				(xy 200.032705 72.576993) (xy 199.916949 72.490362) (xy 199.70761 72.802163) (xy 199.916949 73.113964)
				(xy 200.032704 73.027333) (xy 200.099586 72.975993) (xy 200.169321 72.936497) (xy 200.256673 72.911127)
				(xy 200.376404 72.902163)
			)
		)
	)
	(zone
		(net 189)
		(net_name "/OCuLink/PCIe_{x4}.RX1-")
		(layer "F.Cu")
		(name "$teardrop_padvia$")
		(hatch none 0.1)
		(priority 32052)
		(attr
			(teardrop
				(type padvia)
			)
		)
		(connect_pads yes
			(clearance 0)
		)
		(min_thickness 0.0254)
		(filled_areas_thickness no)
		(fill yes
			(thermal_gap 0.5)
			(thermal_bridge_width 0.5)
			(island_removal_mode 1)
			(island_area_min 10)
		)
		(polygon
			(pts
				(xy 98.601 151.025) (xy 98.593802 151.004352) (xy 98.584208 150.972016) (xy 98.591035 150.957993)
				(xy 98.6125 150.948004) (xy 98.5 150.699) (xy 98.3875 150.948004) (xy 98.408676 150.957729) (xy 98.415731 150.971357)
				(xy 98.406198 151.004352) (xy 98.399 151.025)
			)
		)
	)
	(zone
		(net 772)
		(net_name "/Backplane/PCIe_{x2}.RX1-")
		(layer "F.Cu")
		(name "$teardrop_padvia$")
		(hatch none 0.1)
		(priority 32093)
		(attr
			(teardrop
				(type padvia)
			)
		)
		(connect_pads yes
			(clearance 0)
		)
		(min_thickness 0.0254)
		(filled_areas_thickness no)
		(fill yes
			(thermal_gap 0.5)
			(thermal_bridge_width 0.5)
			(island_removal_mode 1)
			(island_area_min 10)
		)
		(polygon
			(pts
				(xy 314.81 162.011) (xy 314.831227 162.003702) (xy 314.864264 161.993978) (xy 314.878732 162.000702)
				(xy 314.889264 162.022015) (xy 315.136 161.908) (xy 314.884691 161.797039) (xy 314.875384 161.818505)
				(xy 314.862008 161.825545) (xy 314.830071 161.816104) (xy 314.81 161.809)
			)
		)
	)
	(zone
		(net 424)
		(net_name "/2xSFP+/I2C_{SFP1}.SDA")
		(layer "F.Cu")
		(name "$teardrop_padvia$")
		(hatch none 0.1)
		(priority 30700)
		(attr
			(teardrop
				(type padvia)
			)
		)
		(connect_pads yes
			(clearance 0)
		)
		(min_thickness 0.0254)
		(filled_areas_thickness no)
		(fill yes
			(thermal_gap 0.5)
			(thermal_bridge_width 0.5)
			(island_removal_mode 1)
			(island_area_min 10)
		)
		(polygon
			(pts
				(xy 194.4625 155.75) (xy 194.451563 155.788823) (xy 194.429805 155.803933) (xy 194.39 155.81) (xy 194.525 156.686)
				(xy 194.66 155.81) (xy 194.624719 155.805483) (xy 194.603203 155.793862) (xy 194.588005 155.761039)
				(xy 194.5875 155.75)
			)
		)
	)
	(zone
		(net 1)
		(net_name "GND")
		(layer "F.Cu")
		(name "$teardrop_padvia$")
		(hatch none 0.1)
		(priority 30960)
		(attr
			(teardrop
				(type padvia)
			)
		)
		(connect_pads yes
			(clearance 0)
		)
		(min_thickness 0.0254)
		(filled_areas_thickness no)
		(fill yes
			(thermal_gap 0.5)
			(thermal_bridge_width 0.5)
			(island_removal_mode 1)
			(island_area_min 10)
		)
		(polygon
			(pts
				(xy 124.4225 133.318) (xy 124.442469 133.255134) (xy 124.468921 133.223156) (xy 124.506332 133.194642)
				(xy 124.553527 133.172118) (xy 124.611167 133.156907) (xy 124.611798 133.156798) (xy 124.36 132.879)
				(xy 124.108202 133.156798) (xy 124.163635 133.171095) (xy 124.20952 133.192175) (xy 124.247201 133.21954)
				(xy 124.274434 133.250448) (xy 124.291472 133.283735) (xy 124.297489 133.316566) (xy 124.2975 133.318)
			)
		)
	)
	(zone
		(net 1)
		(net_name "GND")
		(layer "F.Cu")
		(name "$teardrop_padvia$")
		(hatch none 0.1)
		(priority 30540)
		(attr
			(teardrop
				(type padvia)
			)
		)
		(connect_pads yes
			(clearance 0)
		)
		(min_thickness 0.0254)
		(filled_areas_thickness no)
		(fill yes
			(thermal_gap 0.5)
			(thermal_bridge_width 0.5)
			(island_removal_mode 1)
			(island_area_min 10)
		)
		(polygon
			(pts
				(xy 176.125 169.62) (xy 176.121667 169.605514) (xy 176.11881 169.57539) (xy 176.130964 169.564349)
				(xy 176.16 169.56) (xy 176.025 168.684) (xy 175.89 169.56) (xy 175.919334 169.564475) (xy 175.931358 169.575801)
				(xy 175.928333 169.605514) (xy 175.925 169.62)
			)
		)
	)
	(zone
		(net 1)
		(net_name "GND")
		(layer "F.Cu")
		(name "$teardrop_padvia$")
		(hatch none 0.1)
		(priority 30797)
		(attr
			(teardrop
				(type padvia)
			)
		)
		(connect_pads yes
			(clearance 0)
		)
		(min_thickness 0.0254)
		(filled_areas_thickness no)
		(fill yes
			(thermal_gap 0.5)
			(thermal_bridge_width 0.5)
			(island_removal_mode 1)
			(island_area_min 10)
		)
		(polygon
			(pts
				(xy 303.547 74.639323) (xy 303.540069 74.796893) (xy 303.511549 74.910421) (xy 303.4945 74.952221)
				(xy 303.697 75.041) (xy 303.8995 74.952221) (xy 303.865117 74.856179) (xy 303.8499 74.754304) (xy 303.847 74.639323)
			)
		)
	)
	(zone
		(net 109)
		(net_name "/2xSFP+/KR to SFI #1/CLK-")
		(layer "F.Cu")
		(name "$teardrop_padvia$")
		(hatch none 0.1)
		(priority 30634)
		(attr
			(teardrop
				(type padvia)
			)
		)
		(connect_pads yes
			(clearance 0)
		)
		(min_thickness 0.0254)
		(filled_areas_thickness no)
		(fill yes
			(thermal_gap 0.5)
			(thermal_bridge_width 0.5)
			(island_removal_mode 1)
			(island_area_min 10)
		)
		(polygon
			(pts
				(xy 142.156343 141.25) (xy 142.273255 141.194698) (xy 142.348837 141.175971) (xy 142.430757 141.167603)
				(xy 142.554492 141.18) (xy 142.521 140.86) (xy 142.225 140.76316) (xy 142.228301 140.900081) (xy 142.21378 141.003261)
				(xy 142.19574 141.046666) (xy 142.169365 141.079712) (xy 142.156343 141.09)
			)
		)
	)
	(zone
		(net 970)
		(net_name "/M.2 key M #2/M2_3V3")
		(layer "F.Cu")
		(name "$teardrop_padvia$")
		(hatch none 0.1)
		(priority 30761)
		(attr
			(teardrop
				(type padvia)
			)
		)
		(connect_pads yes
			(clearance 0)
		)
		(min_thickness 0.0254)
		(filled_areas_thickness no)
		(fill yes
			(thermal_gap 0.5)
			(thermal_bridge_width 0.5)
			(island_removal_mode 1)
			(island_area_min 10)
		)
		(polygon
			(pts
				(xy 303.598 80.978677) (xy 303.604932 80.8211) (xy 303.633456 80.707565) (xy 303.6505 80.665778)
				(xy 303.448 80.577) (xy 303.2455 80.665778) (xy 303.279883 80.761822) (xy 303.295101 80.863702)
				(xy 303.298 80.978677)
			)
		)
	)
	(zone
		(net 262)
		(net_name "/Com Express 7 Interfaces/PCIe_{B2Bx4}.RX0-")
		(layer "F.Cu")
		(name "$teardrop_padvia$")
		(hatch none 0.1)
		(priority 31902)
		(attr
			(teardrop
				(type padvia)
			)
		)
		(connect_pads yes
			(clearance 0)
		)
		(min_thickness 0.0254)
		(filled_areas_thickness no)
		(fill yes
			(thermal_gap 0.5)
			(thermal_bridge_width 0.5)
			(island_removal_mode 1)
			(island_area_min 10)
		)
		(polygon
			(pts
				(xy 195.596417 161.751081) (xy 195.585315 161.733352) (xy 195.592016 161.721948) (xy 195.642918 161.708833)
				(xy 195.683945 161.700885) (xy 195.718503 161.687081) (xy 195.592793 161.499293) (xy 195.375284 161.549838)
				(xy 195.38327 161.650749) (xy 195.381595 161.681327) (xy 195.379686 161.733169) (xy 195.385828 161.784112)
				(xy 195.40785 161.836809) (xy 195.453582 161.893916)
			)
		)
	)
	(zone
		(net 1)
		(net_name "GND")
		(layer "F.Cu")
		(name "$teardrop_padvia$")
		(hatch none 0.1)
		(priority 30597)
		(attr
			(teardrop
				(type padvia)
			)
		)
		(connect_pads yes
			(clearance 0)
		)
		(min_thickness 0.0254)
		(filled_areas_thickness no)
		(fill yes
			(thermal_gap 0.5)
			(thermal_bridge_width 0.5)
			(island_removal_mode 1)
			(island_area_min 10)
		)
		(polygon
			(pts
				(xy 177.925 150.2) (xy 177.928333 150.214486) (xy 177.93119 150.24461) (xy 177.919036 150.255651)
				(xy 177.89 150.26) (xy 178.025 151.136) (xy 178.16 150.26) (xy 178.130666 150.255525) (xy 178.118642 150.244199)
				(xy 178.121667 150.214486) (xy 178.125 150.2)
			)
		)
	)
	(zone
		(net 1)
		(net_name "GND")
		(layer "F.Cu")
		(name "$teardrop_padvia$")
		(hatch none 0.1)
		(priority 32146)
		(attr
			(teardrop
				(type padvia)
			)
		)
		(connect_pads yes
			(clearance 0)
		)
		(min_thickness 0.0254)
		(filled_areas_thickness no)
		(fill yes
			(thermal_gap 0.5)
			(thermal_bridge_width 0.5)
			(island_removal_mode 1)
			(island_area_min 10)
		)
		(polygon
			(pts
				(xy 317.740677 161.01) (xy 317.753178 161.014575) (xy 317.751704 161.0266) (xy 317.721187 161.067227)
				(xy 317.696504 161.098724) (xy 317.693418 161.108775) (xy 317.701 161.1125) (xy 317.701 160.91)
				(xy 317.701 161.1125) (xy 317.748378 161.094246) (xy 317.794299 161.035619) (xy 317.823774 160.937901)
				(xy 317.823536 160.89066) (xy 317.811433 160.850434) (xy 317.793378 160.827528) (xy 317.766906 160.813477)
				(xy 317.740677 160.81)
			)
		)
	)
	(zone
		(net 782)
		(net_name "/Misc/PWM_{A3V3}")
		(layer "F.Cu")
		(name "$teardrop_padvia$")
		(hatch none 0.1)
		(priority 30353)
		(attr
			(teardrop
				(type padvia)
			)
		)
		(connect_pads yes
			(clearance 0)
		)
		(min_thickness 0.0254)
		(filled_areas_thickness no)
		(fill yes
			(thermal_gap 0.5)
			(thermal_bridge_width 0.5)
			(island_removal_mode 1)
			(island_area_min 10)
		)
		(polygon
			(pts
				(xy 259.467708 79.1345) (xy 259.501571 79.140281) (xy 259.536192 79.160745) (xy 259.558014 79.18781)
				(xy 259.573708 79.22715) (xy 259.576997 79.242711) (xy 260.283708 79.072) (xy 259.576997 78.901289)
				(xy 259.565408 78.94151) (xy 259.547824 78.970984) (xy 259.500242 79.004173) (xy 259.467708 79.0095)
			)
		)
	)
	(zone
		(net 300)
		(net_name "Net-(J12D-~{SUS_S4})")
		(layer "F.Cu")
		(name "$teardrop_padvia$")
		(hatch none 0.1)
		(priority 31854)
		(attr
			(teardrop
				(type padvia)
			)
		)
		(connect_pads yes
			(clearance 0)
		)
		(min_thickness 0.0254)
		(filled_areas_thickness no)
		(fill yes
			(thermal_gap 0.5)
			(thermal_bridge_width 0.5)
			(island_removal_mode 1)
			(island_area_min 10)
		)
		(polygon
			(pts
				(xy 183.739127 170.472485) (xy 183.686618 170.518181) (xy 183.640623 170.544768) (xy 183.554174 170.565152)
				(xy 183.538841 170.566988) (xy 183.456105 170.579323) (xy 183.499293 170.800707) (xy 183.720677 170.843895)
				(xy 183.733011 170.76116) (xy 183.753349 170.663881) (xy 183.780057 170.615841) (xy 183.827515 170.560873)
			)
		)
	)
	(zone
		(net 203)
		(net_name "/Backplane/PCIe_{REF}.CK+")
		(layer "F.Cu")
		(name "$teardrop_padvia$")
		(hatch none 0.1)
		(priority 30432)
		(attr
			(teardrop
				(type padvia)
			)
		)
		(connect_pads yes
			(clearance 0)
		)
		(min_thickness 0.0254)
		(filled_areas_thickness no)
		(fill yes
			(thermal_gap 0.5)
			(thermal_bridge_width 0.5)
			(island_removal_mode 1)
			(island_area_min 10)
		)
		(polygon
			(pts
				(xy 216.3865 133.965521) (xy 216.344541 133.887271) (xy 216.308528 133.788715) (xy 216.29317 133.71184)
				(xy 216.290559 133.631574) (xy 216.3 133.568245) (xy 215.98 133.599) (xy 215.881086 133.895) (xy 216.005471 133.892186)
				(xy 216.096359 133.904709) (xy 216.138391 133.921698) (xy 216.170036 133.946551) (xy 216.1845 133.965521)
			)
		)
	)
	(zone
		(net 784)
		(net_name "Net-(U30-1Y)")
		(layer "F.Cu")
		(name "$teardrop_padvia$")
		(hatch none 0.1)
		(priority 31988)
		(attr
			(teardrop
				(type padvia)
			)
		)
		(connect_pads yes
			(clearance 0)
		)
		(min_thickness 0.0254)
		(filled_areas_thickness no)
		(fill yes
			(thermal_gap 0.5)
			(thermal_bridge_width 0.5)
			(island_removal_mode 1)
			(island_area_min 10)
		)
		(polygon
			(pts
				(xy 308.6935 151.998) (xy 308.682563 152.036823) (xy 308.660805 152.051933) (xy 308.621 152.058)
				(xy 308.756 152.434) (xy 308.891 152.058) (xy 308.855719 152.053483) (xy 308.834203 152.041862)
				(xy 308.819005 152.009039) (xy 308.8185 151.998)
			)
		)
	)
	(zone
		(net 734)
		(net_name "Net-(U43A-LOSA)")
		(layer "F.Cu")
		(name "$teardrop_padvia$")
		(hatch none 0.1)
		(priority 30111)
		(attr
			(teardrop
				(type padvia)
			)
		)
		(connect_pads yes
			(clearance 0)
		)
		(min_thickness 0.0254)
		(filled_areas_thickness no)
		(fill yes
			(thermal_gap 0.5)
			(thermal_bridge_width 0.5)
			(island_removal_mode 1)
			(island_area_min 10)
		)
		(polygon
			(pts
				(xy 149.9125 130.227794) (xy 149.917315 130.145733) (xy 149.931019 130.080388) (xy 149.977576 129.98712)
				(xy 150.045787 129.908657) (xy 150.101942 129.847158) (xy 150.161801 129.768339) (xy 149.85 129.559)
				(xy 149.538199 129.768339) (xy 149.635219 129.888517) (xy 149.654214 129.908658) (xy 149.707366 129.967541)
				(xy 149.749591 130.031624) (xy 149.777449 130.114008) (xy 149.7875 130.227794)
			)
		)
	)
	(zone
		(net 2)
		(net_name "+3V3")
		(layer "F.Cu")
		(name "$teardrop_padvia$")
		(hatch none 0.1)
		(priority 30393)
		(attr
			(teardrop
				(type padvia)
			)
		)
		(connect_pads yes
			(clearance 0)
		)
		(min_thickness 0.0254)
		(filled_areas_thickness no)
		(fill yes
			(thermal_gap 0.5)
			(thermal_bridge_width 0.5)
			(island_removal_mode 1)
			(island_area_min 10)
		)
		(polygon
			(pts
				(xy 119.149 149.314) (xy 119.128678 149.269508) (xy 119.109904 149.236011) (xy 119.101385 149.203603)
				(xy 119.115561 149.176962) (xy 119.16487 149.160767) (xy 118.9 148.9) (xy 118.633871 149.159927)
				(xy 118.671856 149.169802) (xy 118.691562 149.185242) (xy 118.694514 149.219629) (xy 118.669484 149.269201)
				(xy 118.649 149.314)
			)
		)
	)
	(zone
		(net 745)
		(net_name "/2xSFP+/KR to SFI #2/TCK")
		(layer "F.Cu")
		(name "$teardrop_padvia$")
		(hatch none 0.1)
		(priority 31686)
		(attr
			(teardrop
				(type padvia)
			)
		)
		(connect_pads yes
			(clearance 0)
		)
		(min_thickness 0.0254)
		(filled_areas_thickness no)
		(fill yes
			(thermal_gap 0.5)
			(thermal_bridge_width 0.5)
			(island_removal_mode 1)
			(island_area_min 10)
		)
		(polygon
			(pts
				(xy 134.2275 130.109323) (xy 134.222682 130.178763) (xy 134.20896 130.230087) (xy 134.162245 130.305628)
				(xy 134.152702 130.317768) (xy 134.102919 130.384997) (xy 134.29 130.511) (xy 134.477081 130.384997)
				(xy 134.427299 130.317769) (xy 134.372894 130.234603) (xy 134.35781 130.181748) (xy 134.3525 130.109323)
			)
		)
	)
	(zone
		(net 150)
		(net_name "/2xUSB3.0+RJ45/DC-")
		(layer "F.Cu")
		(name "$teardrop_padvia$")
		(hatch none 0.1)
		(priority 31143)
		(attr
			(teardrop
				(type padvia)
			)
		)
		(connect_pads yes
			(clearance 0)
		)
		(min_thickness 0.0254)
		(filled_areas_thickness no)
		(fill yes
			(thermal_gap 0.5)
			(thermal_bridge_width 0.5)
			(island_removal_mode 1)
			(island_area_min 10)
		)
		(polygon
			(pts
				(xy 125.973139 109.282927) (xy 126.057997 109.227339) (xy 126.116278 109.208091) (xy 126.184276 109.196472)
				(xy 126.326943 109.1975) (xy 126.290707 108.959293) (xy 125.9525 108.941575) (xy 125.949601 109.034947)
				(xy 125.913761 109.119194) (xy 125.867073 109.176861)
			)
		)
	)
	(zone
		(net 949)
		(net_name "/2xSFP+/KR to SFI #2/BYP_RX+")
		(layer "F.Cu")
		(name "$teardrop_padvia$")
		(hatch none 0.1)
		(priority 31946)
		(attr
			(teardrop
				(type padvia)
			)
		)
		(connect_pads yes
			(clearance 0)
		)
		(min_thickness 0.0254)
		(filled_areas_thickness no)
		(fill yes
			(thermal_gap 0.5)
			(thermal_bridge_width 0.5)
			(island_removal_mode 1)
			(island_area_min 10)
		)
		(polygon
			(pts
				(xy 135.06 148.527721) (xy 135.071736 148.504685) (xy 135.094198 148.488987) (xy 135.170557 148.479864)
				(xy 135.228769 148.485) (xy 135.17 148.254) (xy 134.97 148.226463) (xy 134.965648 148.325256) (xy 134.924062 148.458347)
				(xy 134.9 148.527721)
			)
		)
	)
	(zone
		(net 365)
		(net_name "/Com Express 7 MGMT/PWR_OK")
		(layer "F.Cu")
		(name "$teardrop_padvia$")
		(hatch none 0.1)
		(priority 31729)
		(attr
			(teardrop
				(type padvia)
			)
		)
		(connect_pads yes
			(clearance 0)
		)
		(min_thickness 0.0254)
		(filled_areas_thickness no)
		(fill yes
			(thermal_gap 0.5)
			(thermal_bridge_width 0.5)
			(island_removal_mode 1)
			(island_area_min 10)
		)
		(polygon
			(pts
				(xy 190.8375 154.049323) (xy 190.832682 154.118763) (xy 190.81896 154.170087) (xy 190.772245 154.245628)
				(xy 190.762702 154.257768) (xy 190.712919 154.324997) (xy 190.9 154.451) (xy 191.087081 154.324997)
				(xy 191.037299 154.257769) (xy 190.982894 154.174603) (xy 190.96781 154.121748) (xy 190.9625 154.049323)
			)
		)
	)
	(zone
		(net 1)
		(net_name "GND")
		(layer "F.Cu")
		(name "$teardrop_padvia$")
		(hatch none 0.1)
		(priority 30952)
		(attr
			(teardrop
				(type padvia)
			)
		)
		(connect_pads yes
			(clearance 0)
		)
		(min_thickness 0.0254)
		(filled_areas_thickness no)
		(fill yes
			(thermal_gap 0.5)
			(thermal_bridge_width 0.5)
			(island_removal_mode 1)
			(island_area_min 10)
		)
		(polygon
			(pts
				(xy 253.76625 128.069248) (xy 253.703384 128.049279) (xy 253.671406 128.022827) (xy 253.642892 127.985416)
				(xy 253.620368 127.938221) (xy 253.605157 127.880581) (xy 253.605048 127.87995) (xy 253.32725 128.131748)
				(xy 253.605048 128.383546) (xy 253.619345 128.328113) (xy 253.640425 128.282228) (xy 253.66779 128.244547)
				(xy 253.698698 128.217314) (xy 253.731985 128.200276) (xy 253.764816 128.194259) (xy 253.76625 128.194248)
			)
		)
	)
	(zone
		(net 379)
		(net_name "Net-(J12D-~{ESPI_EN})")
		(layer "F.Cu")
		(name "$teardrop_padvia$")
		(hatch none 0.1)
		(priority 31825)
		(attr
			(teardrop
				(type padvia)
			)
		)
		(connect_pads yes
			(clearance 0)
		)
		(min_thickness 0.0254)
		(filled_areas_thickness no)
		(fill yes
			(thermal_gap 0.5)
			(thermal_bridge_width 0.5)
			(island_removal_mode 1)
			(island_area_min 10)
		)
		(polygon
			(pts
				(xy 198.450677 161.4375) (xy 198.381236 161.432682) (xy 198.329913 161.41896) (xy 198.254371 161.372246)
				(xy 198.242231 161.362701) (xy 198.175003 161.312919) (xy 198.049 161.5) (xy 198.175003 161.687081)
				(xy 198.242229 161.637299) (xy 198.325396 161.582894) (xy 198.378251 161.56781) (xy 198.450677 161.5625)
			)
		)
	)
	(zone
		(net 67)
		(net_name "Net-(C47-Pad2)")
		(layer "F.Cu")
		(name "$teardrop_padvia$")
		(hatch none 0.1)
		(priority 32134)
		(attr
			(teardrop
				(type padvia)
			)
		)
		(connect_pads yes
			(clearance 0)
		)
		(min_thickness 0.0254)
		(filled_areas_thickness no)
		(fill yes
			(thermal_gap 0.5)
			(thermal_bridge_width 0.5)
			(island_removal_mode 1)
			(island_area_min 10)
		)
		(polygon
			(pts
				(xy 312.680499 119.497078) (xy 312.679084 119.480352) (xy 312.679109 119.440027) (xy 312.688236 119.419733)
				(xy 312.708564 119.401476) (xy 312.619999 119.157999) (xy 312.528602 119.394639) (xy 312.547759 119.413529)
				(xy 312.556813 119.434025) (xy 312.55704 119.478859) (xy 312.555499 119.497078)
			)
		)
	)
	(zone
		(net 970)
		(net_name "/M.2 key M #2/M2_3V3")
		(layer "F.Cu")
		(name "$teardrop_padvia$")
		(hatch none 0.1)
		(priority 30759)
		(attr
			(teardrop
				(type padvia)
			)
		)
		(connect_pads yes
			(clearance 0)
		)
		(min_thickness 0.0254)
		(filled_areas_thickness no)
		(fill yes
			(thermal_gap 0.5)
			(thermal_bridge_width 0.5)
			(island_removal_mode 1)
			(island_area_min 10)
		)
		(polygon
			(pts
				(xy 286.597 80.978677) (xy 286.603932 80.8211) (xy 286.632456 80.707565) (xy 286.6495 80.665778)
				(xy 286.447 80.577) (xy 286.2445 80.665778) (xy 286.278883 80.761822) (xy 286.294101 80.863702)
				(xy 286.297 80.978677)
			)
		)
	)
	(zone
		(net 273)
		(net_name "/M.2 key M #2/PCIE_{REF}.CK+")
		(layer "F.Cu")
		(name "$teardrop_padvia$")
		(hatch none 0.1)
		(priority 31343)
		(attr
			(teardrop
				(type padvia)
			)
		)
		(connect_pads yes
			(clearance 0)
		)
		(min_thickness 0.0254)
		(filled_areas_thickness no)
		(fill yes
			(thermal_gap 0.5)
			(thermal_bridge_width 0.5)
			(island_removal_mode 1)
			(island_area_min 10)
		)
		(polygon
			(pts
				(xy 260.6045 136.632504) (xy 260.599765 136.67929) (xy 260.586621 136.714742) (xy 260.541613 136.762939)
				(xy 260.503393 136.787115) (xy 260.460226 136.814484) (xy 260.418268 136.851147) (xy 260.5815 137.001)
				(xy 260.802177 136.98014) (xy 260.797548 136.879469) (xy 260.80098 136.796102) (xy 260.801105 136.794035)
				(xy 260.8065 136.632504)
			)
		)
	)
	(zone
		(net 741)
		(net_name "Net-(U45C-REFCLK1-)")
		(layer "F.Cu")
		(name "$teardrop_padvia$")
		(hatch none 0.1)
		(priority 31692)
		(attr
			(teardrop
				(type padvia)
			)
		)
		(connect_pads yes
			(clearance 0)
		)
		(min_thickness 0.0254)
		(filled_areas_thickness no)
		(fill yes
			(thermal_gap 0.5)
			(thermal_bridge_width 0.5)
			(island_removal_mode 1)
			(island_area_min 10)
		)
		(polygon
			(pts
				(xy 126.2925 130.274323) (xy 126.287682 130.343763) (xy 126.27396 130.395087) (xy 126.227245 130.470628)
				(xy 126.217702 130.482768) (xy 126.167919 130.549997) (xy 126.355 130.676) (xy 126.542081 130.549997)
				(xy 126.492299 130.482769) (xy 126.437894 130.399603) (xy 126.42281 130.346748) (xy 126.4175 130.274323)
			)
		)
	)
	(zone
		(net 597)
		(net_name "/Misc/PWM1")
		(layer "F.Cu")
		(name "$teardrop_padvia$")
		(hatch none 0.1)
		(priority 30494)
		(attr
			(teardrop
				(type padvia)
			)
		)
		(connect_pads yes
			(clearance 0)
		)
		(min_thickness 0.0254)
		(filled_areas_thickness no)
		(fill yes
			(thermal_gap 0.5)
			(thermal_bridge_width 0.5)
			(island_removal_mode 1)
			(island_area_min 10)
		)
		(polygon
			(pts
				(xy 253.451056 90.060555) (xy 253.373239 90.110408) (xy 253.251796 90.138528) (xy 253.177524 90.139742)
				(xy 253.097238 90.130491) (xy 253.094526 90.129999) (xy 253.149293 90.450706) (xy 253.445 90.530473)
				(xy 253.441462 90.444033) (xy 253.447546 90.3644) (xy 253.462581 90.291861) (xy 253.485544 90.229047)
				(xy 253.539444 90.148943)
			)
		)
	)
	(zone
		(net 1)
		(net_name "GND")
		(layer "F.Cu")
		(name "$teardrop_padvia$")
		(hatch none 0.1)
		(priority 30864)
		(attr
			(teardrop
				(type padvia)
			)
		)
		(connect_pads yes
			(clearance 0)
		)
		(min_thickness 0.0254)
		(filled_areas_thickness no)
		(fill yes
			(thermal_gap 0.5)
			(thermal_bridge_width 0.5)
			(island_removal_mode 1)
			(island_area_min 10)
		)
		(polygon
			(pts
				(xy 193.80861 78.045163) (xy 193.814382 78.004426) (xy 193.834786 77.962511) (xy 193.861961 77.93421)
				(xy 193.901507 77.910781) (xy 193.97411 77.89151) (xy 193.70861 77.631163) (xy 193.44311 77.89151)
				(xy 193.496252 77.903377) (xy 193.537291 77.921825) (xy 193.588992 77.972499) (xy 193.608328 78.036068)
				(xy 193.60861 78.045163)
			)
		)
	)
	(zone
		(net 772)
		(net_name "/Backplane/PCIe_{x2}.RX1-")
		(layer "F.Cu")
		(name "$teardrop_padvia$")
		(hatch none 0.1)
		(priority 32032)
		(attr
			(teardrop
				(type padvia)
			)
		)
		(connect_pads yes
			(clearance 0)
		)
		(min_thickness 0.0254)
		(filled_areas_thickness no)
		(fill yes
			(thermal_gap 0.5)
			(thermal_bridge_width 0.5)
			(island_removal_mode 1)
			(island_area_min 10)
		)
		(polygon
			(pts
				(xy 314.038 161.9535) (xy 314.051941 161.948168) (xy 314.076365 161.941442) (xy 314.085289 161.950549)
				(xy 314.088953 161.975292) (xy 314.364 161.908) (xy 314.300083 161.783) (xy 314.217652 161.792335)
				(xy 314.117272 161.769146) (xy 314.038 161.7515)
			)
		)
	)
	(zone
		(net 137)
		(net_name "/Com Express 7 MGMT/~{TYPE2}")
		(layer "F.Cu")
		(name "$teardrop_padvia$")
		(hatch none 0.1)
		(priority 30826)
		(attr
			(teardrop
				(type padvia)
			)
		)
		(connect_pads yes
			(clearance 0)
		)
		(min_thickness 0.0254)
		(filled_areas_thickness no)
		(fill yes
			(thermal_gap 0.5)
			(thermal_bridge_width 0.5)
			(island_removal_mode 1)
			(island_area_min 10)
		)
		(polygon
			(pts
				(xy 255.144 132.7775) (xy 255.11691 132.772596) (xy 255.093479 132.758267) (xy 255.055683 132.699826)
				(xy 255.029618 132.581886) (xy 255.024 132.466775) (xy 254.723 132.61) (xy 255.005439 133.071967)
				(xy 255.01408 133.022725) (xy 255.030166 132.982206) (xy 255.080336 132.924282) (xy 255.142332 132.902516)
				(xy 255.144 132.9025)
			)
		)
	)
	(zone
		(net 73)
		(net_name "+3V3_AON")
		(layer "F.Cu")
		(name "$teardrop_padvia$")
		(hatch none 0.1)
		(priority 30326)
		(attr
			(teardrop
				(type padvia)
			)
		)
		(connect_pads yes
			(clearance 0)
		)
		(min_thickness 0.0254)
		(filled_areas_thickness no)
		(fill yes
			(thermal_gap 0.5)
			(thermal_bridge_width 0.5)
			(island_removal_mode 1)
			(island_area_min 10)
		)
		(polygon
			(pts
				(xy 298.612 104.165) (xy 298.657973 104.151706) (xy 298.696887 104.138065) (xy 298.735702 104.134515)
				(xy 298.769586 104.153009) (xy 298.793708 104.2055) (xy 299.051 103.94) (xy 298.793708 103.6745)
				(xy 298.779814 103.712335) (xy 298.76129 103.734765) (xy 298.719327 103.745961) (xy 298.657973 103.728294)
				(xy 298.612 103.715)
			)
		)
	)
	(zone
		(net 576)
		(net_name "Net-(U19-MODE)")
		(layer "F.Cu")
		(name "$teardrop_padvia$")
		(hatch none 0.1)
		(priority 31894)
		(attr
			(teardrop
				(type padvia)
			)
		)
		(connect_pads yes
			(clearance 0)
		)
		(min_thickness 0.0254)
		(filled_areas_thickness no)
		(fill yes
			(thermal_gap 0.5)
			(thermal_bridge_width 0.5)
			(island_removal_mode 1)
			(island_area_min 10)
		)
		(polygon
			(pts
				(xy 310.225676 105.589499) (xy 310.157105 105.584691) (xy 310.106314 105.571034) (xy 310.031644 105.524532)
				(xy 310.018899 105.514376) (xy 309.950002 105.462919) (xy 309.823999 105.65) (xy 309.950002 105.837081)
				(xy 310.015451 105.789022) (xy 310.099587 105.734688) (xy 310.152774 105.719741) (xy 310.225676 105.714499)
			)
		)
	)
	(zone
		(net 1)
		(net_name "GND")
		(layer "F.Cu")
		(name "$teardrop_padvia$")
		(hatch none 0.1)
		(priority 30462)
		(attr
			(teardrop
				(type padvia)
			)
		)
		(connect_pads yes
			(clearance 0)
		)
		(min_thickness 0.0254)
		(filled_areas_thickness no)
		(fill yes
			(thermal_gap 0.5)
			(thermal_bridge_width 0.5)
			(island_removal_mode 1)
			(island_area_min 10)
		)
		(polygon
			(pts
				(xy 262.100708 76.198) (xy 262.10037 76.18113) (xy 262.100949 76.136174) (xy 262.112767 76.088831)
				(xy 262.147346 76.046427) (xy 262.216208 76.016291) (xy 261.950708 75.759) (xy 261.685208 76.016291)
				(xy 261.729977 76.031848) (xy 261.761593 76.052565) (xy 261.794327 76.103701) (xy 261.801046 76.18113)
				(xy 261.800708 76.198)
			)
		)
	)
	(zone
		(net 321)
		(net_name "/Com Express 7 Interfaces/SDIO.DAT0")
		(layer "F.Cu")
		(name "$teardrop_padvia$")
		(hatch none 0.1)
		(priority 31556)
		(attr
			(teardrop
				(type padvia)
			)
		)
		(connect_pads yes
			(clearance 0)
		)
		(min_thickness 0.0254)
		(filled_areas_thickness no)
		(fill yes
			(thermal_gap 0.5)
			(thermal_bridge_width 0.5)
			(island_removal_mode 1)
			(island_area_min 10)
		)
		(polygon
			(pts
				(xy 113.337916 132.991) (xy 113.377784 132.995748) (xy 113.406418 133.008987) (xy 113.440393 133.053337)
				(xy 113.456001 133.09387) (xy 113.492919 133.175003) (xy 113.681 133.05) (xy 113.681758 132.829323)
				(xy 113.531532 132.819782) (xy 113.337916 132.809)
			)
		)
	)
	(zone
		(net 372)
		(net_name "/Com Express 7 MGMT/I2C.SDA")
		(layer "F.Cu")
		(name "$teardrop_padvia$")
		(hatch none 0.1)
		(priority 30673)
		(attr
			(teardrop
				(type padvia)
			)
		)
		(connect_pads yes
			(clearance 0)
		)
		(min_thickness 0.0254)
		(filled_areas_thickness no)
		(fill yes
			(thermal_gap 0.5)
			(thermal_bridge_width 0.5)
			(island_removal_mode 1)
			(island_area_min 10)
		)
		(polygon
			(pts
				(xy 192.4625 162.2) (xy 192.451563 162.238823) (xy 192.429805 162.253933) (xy 192.39 162.26) (xy 192.525 163.136)
				(xy 192.66 162.26) (xy 192.624719 162.255483) (xy 192.603203 162.243862) (xy 192.588005 162.211039)
				(xy 192.5875 162.2)
			)
		)
	)
	(zone
		(net 955)
		(net_name "/2xSFP+/KR to SFI #2/BYP_TX+")
		(layer "F.Cu")
		(name "$teardrop_padvia$")
		(hatch none 0.1)
		(priority 31944)
		(attr
			(teardrop
				(type padvia)
			)
		)
		(connect_pads yes
			(clearance 0)
		)
		(min_thickness 0.0254)
		(filled_areas_thickness no)
		(fill yes
			(thermal_gap 0.5)
			(thermal_bridge_width 0.5)
			(island_removal_mode 1)
			(island_area_min 10)
		)
		(polygon
			(pts
				(xy 129.06 148.527721) (xy 129.071736 148.504685) (xy 129.094198 148.488987) (xy 129.170557 148.479864)
				(xy 129.228769 148.485) (xy 129.17 148.254) (xy 128.97 148.226463) (xy 128.965648 148.325256) (xy 128.924062 148.458347)
				(xy 128.9 148.527721)
			)
		)
	)
	(zone
		(net 528)
		(net_name "/Backplane/~{PERST}")
		(layer "F.Cu")
		(name "$teardrop_padvia$")
		(hatch none 0.1)
		(priority 32113)
		(attr
			(teardrop
				(type padvia)
			)
		)
		(connect_pads yes
			(clearance 0)
		)
		(min_thickness 0.0254)
		(filled_areas_thickness no)
		(fill yes
			(thermal_gap 0.5)
			(thermal_bridge_width 0.5)
			(island_removal_mode 1)
			(island_area_min 10)
		)
		(polygon
			(pts
				(xy 314.81 163.5225) (xy 314.816322 163.522404) (xy 314.855825 163.527989) (xy 314.874047 163.542922)
				(xy 314.886995 163.5725) (xy 315.136 163.46) (xy 314.886995 163.3475) (xy 314.875879 163.374493)
				(xy 314.860352 163.389595) (xy 314.816322 163.397596) (xy 314.81 163.3975)
			)
		)
	)
	(zone
		(net 358)
		(net_name "/Com Express 7 MGMT/SMBus.SDA")
		(layer "F.Cu")
		(name "$teardrop_padvia$")
		(hatch none 0.1)
		(priority 30662)
		(attr
			(teardrop
				(type padvia)
			)
		)
		(connect_pads yes
			(clearance 0)
		)
		(min_thickness 0.0254)
		(filled_areas_thickness no)
		(fill yes
			(thermal_gap 0.5)
			(thermal_bridge_width 0.5)
			(island_removal_mode 1)
			(island_area_min 10)
		)
		(polygon
			(pts
				(xy 182.5875 164.07) (xy 182.598438 164.031177) (xy 182.620195 164.016067) (xy 182.66 164.01) (xy 182.525 163.134)
				(xy 182.39 164.01) (xy 182.425281 164.014517) (xy 182.446797 164.026138) (xy 182.461995 164.058961)
				(xy 182.4625 164.07)
			)
		)
	)
	(zone
		(net 208)
		(net_name "/Backplane/UART.RX")
		(layer "F.Cu")
		(name "$teardrop_padvia$")
		(hatch none 0.1)
		(priority 31654)
		(attr
			(teardrop
				(type padvia)
			)
		)
		(connect_pads yes
			(clearance 0)
		)
		(min_thickness 0.0254)
		(filled_areas_thickness no)
		(fill yes
			(thermal_gap 0.5)
			(thermal_bridge_width 0.5)
			(island_removal_mode 1)
			(island_area_min 10)
		)
		(polygon
			(pts
				(xy 312.640062 168.798269) (xy 312.553235 168.878366) (xy 312.4853 168.927483) (xy 312.451486 168.948825)
				(xy 312.374997 168.997919) (xy 312.499293 169.185707) (xy 312.720677 169.20175) (xy 312.711644 169.11628)
				(xy 312.697947 169.072173) (xy 312.684113 169.026517) (xy 312.679322 168.981941) (xy 312.691468 168.936103)
				(xy 312.72845 168.886657)
			)
		)
	)
	(zone
		(net 1)
		(net_name "GND")
		(layer "F.Cu")
		(name "$teardrop_padvia$")
		(hatch none 0.1)
		(priority 30229)
		(attr
			(teardrop
				(type padvia)
			)
		)
		(connect_pads yes
			(clearance 0)
		)
		(min_thickness 0.0254)
		(filled_areas_thickness no)
		(fill yes
			(thermal_gap 0.5)
			(thermal_bridge_width 0.5)
			(island_removal_mode 1)
			(island_area_min 10)
		)
		(polygon
			(pts
				(xy 232.007707 77.922) (xy 232.038315 77.91365) (xy 232.0913 77.903039) (xy 232.114432 77.916044)
				(xy 232.130898 77.952) (xy 232.823707 77.772) (xy 232.130898 77.592) (xy 232.118964 77.621959) (xy 232.102643 77.637272)
				(xy 232.064969 77.639108) (xy 232.038315 77.63035) (xy 232.007707 77.622)
			)
		)
	)
	(zone
		(net 131)
		(net_name "Net-(D17-C_{B})")
		(layer "F.Cu")
		(name "$teardrop_padvia$")
		(hatch none 0.1)
		(priority 31815)
		(attr
			(teardrop
				(type padvia)
			)
		)
		(connect_pads yes
			(clearance 0)
		)
		(min_thickness 0.0254)
		(filled_areas_thickness no)
		(fill yes
			(thermal_gap 0.5)
			(thermal_bridge_width 0.5)
			(island_removal_mode 1)
			(island_area_min 10)
		)
		(polygon
			(pts
				(xy 100.180677 77.7475) (xy 100.111236 77.742682) (xy 100.059913 77.72896) (xy 99.984371 77.682246)
				(xy 99.972231 77.672701) (xy 99.905003 77.622919) (xy 99.779 77.81) (xy 99.905003 77.997081) (xy 99.972229 77.947299)
				(xy 100.055396 77.892894) (xy 100.108251 77.87781) (xy 100.180677 77.8725)
			)
		)
	)
	(zone
		(net 340)
		(net_name "/Com Express 7 MGMT/SPI.CLK")
		(layer "F.Cu")
		(name "$teardrop_padvia$")
		(hatch none 0.1)
		(priority 31603)
		(attr
			(teardrop
				(type padvia)
			)
		)
		(connect_pads yes
			(clearance 0)
		)
		(min_thickness 0.0254)
		(filled_areas_thickness no)
		(fill yes
			(thermal_gap 0.5)
			(thermal_bridge_width 0.5)
			(island_removal_mode 1)
			(island_area_min 10)
		)
		(polygon
			(pts
				(xy 222.5875 167.700677) (xy 222.592169 167.630798) (xy 222.604856 167.57742) (xy 222.649334 167.490418)
				(xy 222.707644 167.375358) (xy 222.5 167.299) (xy 222.312919 167.425003) (xy 222.38137 167.507658)
				(xy 222.439245 167.582143) (xy 222.456315 167.632044) (xy 222.4625 167.700677)
			)
		)
	)
	(zone
		(net 532)
		(net_name "/Backplane/PCIe_{x2}.RX0+")
		(layer "F.Cu")
		(name "$teardrop_padvia$")
		(hatch none 0.1)
		(priority 30022)
		(attr
			(teardrop
				(type padvia)
			)
		)
		(connect_pads yes
			(clearance 0)
		)
		(min_thickness 0.0254)
		(filled_areas_thickness no)
		(fill yes
			(thermal_gap 0.5)
			(thermal_bridge_width 0.5)
			(island_removal_mode 1)
			(island_area_min 10)
		)
		(polygon
			(pts
				(xy 317.860744 159.6165) (xy 318.255858 159.599246) (xy 318.69849 159.577362) (xy 318.959827 159.575348)
				(xy 319.254117 159.585) (xy 319.451 159.31) (xy 317.95 159.254408) (xy 317.950007 159.313332) (xy 317.940774 159.356415)
				(xy 317.925619 159.384485) (xy 317.906098 159.402295) (xy 317.860744 159.4145)
			)
		)
	)
	(zone
		(net 73)
		(net_name "+3V3_AON")
		(layer "F.Cu")
		(name "$teardrop_padvia$")
		(hatch none 0.1)
		(priority 30328)
		(attr
			(teardrop
				(type padvia)
			)
		)
		(connect_pads yes
			(clearance 0)
		)
		(min_thickness 0.0254)
		(filled_areas_thickness no)
		(fill yes
			(thermal_gap 0.5)
			(thermal_bridge_width 0.5)
			(island_removal_mode 1)
			(island_area_min 10)
		)
		(polygon
			(pts
				(xy 304.675 148.45) (xy 304.669961 148.420375) (xy 304.663987 148.389497) (xy 304.66574 148.358303)
				(xy 304.683988 148.330904) (xy 304.7275 148.311409) (xy 304.525 147.809) (xy 304.3225 148.311409)
				(xy 304.356526 148.324339) (xy 304.376399 148.341896) (xy 304.386551 148.383326) (xy 304.380039 148.420375)
				(xy 304.375 148.45)
			)
		)
	)
	(zone
		(net 1)
		(net_name "GND")
		(layer "F.Cu")
		(name "$teardrop_padvia$")
		(hatch none 0.1)
		(priority 30592)
		(attr
			(teardrop
				(type padvia)
			)
		)
		(connect_pads yes
			(clearance 0)
		)
		(min_thickness 0.0254)
		(filled_areas_thickness no)
		(fill yes
			(thermal_gap 0.5)
			(thermal_bridge_width 0.5)
			(island_removal_mode 1)
			(island_area_min 10)
		)
		(polygon
			(pts
				(xy 213.425 162.2) (xy 213.428333 162.214486) (xy 213.43119 162.24461) (xy 213.419036 162.255651)
				(xy 213.39 162.26) (xy 213.525 163.136) (xy 213.66 162.26) (xy 213.630666 162.255525) (xy 213.618642 162.244199)
				(xy 213.621667 162.214486) (xy 213.625 162.2)
			)
		)
	)
	(zone
		(net 526)
		(net_name "/Backplane/~{PRSNT}")
		(layer "F.Cu")
		(name "$teardrop_padvia$")
		(hatch none 0.1)
		(priority 31865)
		(attr
			(teardrop
				(type padvia)
			)
		)
		(connect_pads yes
			(clearance 0)
		)
		(min_thickness 0.0254)
		(filled_areas_thickness no)
		(fill yes
			(thermal_gap 0.5)
			(thermal_bridge_width 0.5)
			(island_removal_mode 1)
			(island_area_min 10)
		)
		(polygon
			(pts
				(xy 163.622485 111.810873) (xy 163.668181 111.863382) (xy 163.694768 111.909376) (xy 163.715152 111.995825)
				(xy 163.716988 112.011158) (xy 163.729323 112.093895) (xy 163.950707 112.050707) (xy 163.993895 111.829323)
				(xy 163.911158 111.816988) (xy 163.81388 111.796651) (xy 163.76584 111.769943) (xy 163.710873 111.722485)
			)
		)
	)
	(zone
		(net 343)
		(net_name "Net-(J12D-~{TYPE10})")
		(layer "F.Cu")
		(name "$teardrop_padvia$")
		(hatch none 0.1)
		(priority 30695)
		(attr
			(teardrop
				(type padvia)
			)
		)
		(connect_pads yes
			(clearance 0)
		)
		(min_thickness 0.0254)
		(filled_areas_thickness no)
		(fill yes
			(thermal_gap 0.5)
			(thermal_bridge_width 0.5)
			(island_removal_mode 1)
			(island_area_min 10)
		)
		(polygon
			(pts
				(xy 223.9625 167.75) (xy 223.951563 167.788823) (xy 223.929805 167.803933) (xy 223.89 167.81) (xy 224.025 168.686)
				(xy 224.16 167.81) (xy 224.124719 167.805483) (xy 224.103203 167.793862) (xy 224.088005 167.761039)
				(xy 224.0875 167.75)
			)
		)
	)
	(zone
		(net 196)
		(net_name "/OCuLink/PCIe_{x4}.RX3+")
		(layer "F.Cu")
		(name "$teardrop_padvia$")
		(hatch none 0.1)
		(priority 32080)
		(attr
			(teardrop
				(type padvia)
			)
		)
		(connect_pads yes
			(clearance 0)
		)
		(min_thickness 0.0254)
		(filled_areas_thickness no)
		(fill yes
			(thermal_gap 0.5)
			(thermal_bridge_width 0.5)
			(island_removal_mode 1)
			(island_area_min 10)
		)
		(polygon
			(pts
				(xy 107.001 152.26) (xy 107.008198 152.280648) (xy 107.017792 152.312984) (xy 107.010965 152.327007)
				(xy 106.9895 152.336995) (xy 107.102 152.586) (xy 107.2145 152.336995) (xy 107.193324 152.327271)
				(xy 107.186269 152.313643) (xy 107.195802 152.280648) (xy 107.203 152.26)
			)
		)
	)
	(zone
		(net 352)
		(net_name "Net-(J12D-LPC_AD3{slash}ESPI_IO_3)")
		(layer "F.Cu")
		(name "$teardrop_padvia$")
		(hatch none 0.1)
		(priority 30658)
		(attr
			(teardrop
				(type padvia)
			)
		)
		(connect_pads yes
			(clearance 0)
		)
		(min_thickness 0.0254)
		(filled_areas_thickness no)
		(fill yes
			(thermal_gap 0.5)
			(thermal_bridge_width 0.5)
			(island_removal_mode 1)
			(island_area_min 10)
		)
		(polygon
			(pts
				(xy 179.0875 164.07) (xy 179.098438 164.031177) (xy 179.120195 164.016067) (xy 179.16 164.01) (xy 179.025 163.134)
				(xy 178.89 164.01) (xy 178.925281 164.014517) (xy 178.946797 164.026138) (xy 178.961995 164.058961)
				(xy 178.9625 164.07)
			)
		)
	)
	(zone
		(net 58)
		(net_name "/USB-C console/VBUS_FTDI")
		(layer "F.Cu")
		(name "$teardrop_padvia$")
		(hatch none 0.1)
		(priority 30217)
		(attr
			(teardrop
				(type padvia)
			)
		)
		(connect_pads yes
			(clearance 0)
		)
		(min_thickness 0.0254)
		(filled_areas_thickness no)
		(fill yes
			(thermal_gap 0.5)
			(thermal_bridge_width 0.5)
			(island_removal_mode 1)
			(island_area_min 10)
		)
		(polygon
			(pts
				(xy 120.837 72.274) (xy 120.82865 72.243391) (xy 120.818039 72.190406) (xy 120.831044 72.167274)
				(xy 120.867 72.150808) (xy 120.687 71.458) (xy 120.507 72.150808) (xy 120.536959 72.162742) (xy 120.552272 72.179064)
				(xy 120.554108 72.216738) (xy 120.54535 72.243391) (xy 120.537 72.274)
			)
		)
	)
	(zone
		(net 528)
		(net_name "/Backplane/~{PERST}")
		(layer "F.Cu")
		(name "$teardrop_padvia$")
		(hatch none 0.1)
		(priority 31001)
		(attr
			(teardrop
				(type padvia)
			)
		)
		(connect_pads yes
			(clearance 0)
		)
		(min_thickness 0.0254)
		(filled_areas_thickness no)
		(fill yes
			(thermal_gap 0.5)
			(thermal_bridge_width 0.5)
			(island_removal_mode 1)
			(island_area_min 10)
		)
		(polygon
			(pts
				(xy 290.3925 103.298) (xy 290.412469 103.235134) (xy 290.438921 103.203156) (xy 290.476332 103.174642)
				(xy 290.523527 103.152118) (xy 290.581167 103.136907) (xy 290.581798 103.136798) (xy 290.33 102.859)
				(xy 290.078202 103.136798) (xy 290.133635 103.151095) (xy 290.17952 103.172175) (xy 290.217201 103.19954)
				(xy 290.244434 103.230448) (xy 290.261472 103.263735) (xy 290.267489 103.296566) (xy 290.2675 103.298)
			)
		)
	)
	(zone
		(net 1)
		(net_name "GND")
		(layer "F.Cu")
		(name "$teardrop_padvia$")
		(hatch none 0.1)
		(priority 30556)
		(attr
			(teardrop
				(type padvia)
			)
		)
		(connect_pads yes
			(clearance 0)
		)
		(min_thickness 0.0254)
		(filled_areas_thickness no)
		(fill yes
			(thermal_gap 0.5)
			(thermal_bridge_width 0.5)
			(island_removal_mode 1)
			(island_area_min 10)
		)
		(polygon
			(pts
				(xy 230.625 169.62) (xy 230.621667 169.605514) (xy 230.61881 169.57539) (xy 230.630964 169.564349)
				(xy 230.66 169.56) (xy 230.525 168.684) (xy 230.39 169.56) (xy 230.419334 169.564475) (xy 230.431358 169.575801)
				(xy 230.428333 169.605514) (xy 230.425 169.62)
			)
		)
	)
	(zone
		(net 528)
		(net_name "/Backplane/~{PERST}")
		(layer "F.Cu")
		(name "$teardrop_padvia$")
		(hatch none 0.1)
		(priority 31885)
		(attr
			(teardrop
				(type padvia)
			)
		)
		(connect_pads yes
			(clearance 0)
		)
		(min_thickness 0.0254)
		(filled_areas_thickness no)
		(fill yes
			(thermal_gap 0.5)
			(thermal_bridge_width 0.5)
			(island_removal_mode 1)
			(island_area_min 10)
		)
		(polygon
			(pts
				(xy 313.727515 163.349127) (xy 313.681819 163.296618) (xy 313.655231 163.250623) (xy 313.634847 163.164175)
				(xy 313.633011 163.14884) (xy 313.620677 163.066105) (xy 313.399293 163.109293) (xy 313.356105 163.330677)
				(xy 313.43884 163.343011) (xy 313.536119 163.363349) (xy 313.584159 163.390057) (xy 313.639127 163.437515)
			)
		)
	)
	(zone
		(net 194)
		(net_name "/OCuLink/PCIe_{x4}.RX2+")
		(layer "F.Cu")
		(name "$teardrop_padvia$")
		(hatch none 0.1)
		(priority 31432)
		(attr
			(teardrop
				(type padvia)
			)
		)
		(connect_pads yes
			(clearance 0)
		)
		(min_thickness 0.0254)
		(filled_areas_thickness no)
		(fill yes
			(thermal_gap 0.5)
			(thermal_bridge_width 0.5)
			(island_removal_mode 1)
			(island_area_min 10)
		)
		(polygon
			(pts
				(xy 99.392496 159.9435) (xy 99.230964 159.948895) (xy 99.146554 159.952445) (xy 99.04486 159.947823)
				(xy 99.024 160.1685) (xy 99.173852 160.331731) (xy 99.227992 160.263062) (xy 99.237883 160.246608)
				(xy 99.262383 160.207935) (xy 99.29189 160.175721) (xy 99.333046 160.153673) (xy 99.392496 160.1455)
			)
		)
	)
	(zone
		(net 1)
		(net_name "GND")
		(layer "F.Cu")
		(name "$teardrop_padvia$")
		(hatch none 0.1)
		(priority 31562)
		(attr
			(teardrop
				(type padvia)
			)
		)
		(connect_pads yes
			(clearance 0)
		)
		(min_thickness 0.0254)
		(filled_areas_thickness no)
		(fill yes
			(thermal_gap 0.5)
			(thermal_bridge_width 0.5)
			(island_removal_mode 1)
			(island_area_min 10)
		)
		(polygon
			(pts
				(xy 309.407 155.637) (xy 309.398751 155.614923) (xy 309.388017 155.576428) (xy 309.400982 155.562475)
				(xy 309.437 155.557) (xy 309.257 155.181) (xy 309.077 155.557) (xy 309.110735 155.56154) (xy 309.124928 155.573323)
				(xy 309.121446 155.601817) (xy 309.115249 155.614923) (xy 309.107 155.637)
			)
		)
	)
	(zone
		(net 330)
		(net_name "/Com Express 7 Interfaces/PCIe_{B2Ax4}.TX3+")
		(layer "F.Cu")
		(name "$teardrop_padvia$")
		(hatch none 0.1)
		(priority 31904)
		(attr
			(teardrop
				(type padvia)
			)
		)
		(connect_pads yes
			(clearance 0)
		)
		(min_thickness 0.0254)
		(filled_areas_thickness no)
		(fill yes
			(thermal_gap 0.5)
			(thermal_bridge_width 0.5)
			(island_removal_mode 1)
			(island_area_min 10)
		)
		(polygon
			(pts
				(xy 216.096418 167.443916) (xy 216.133636 167.400005) (xy 216.15607 167.359009) (xy 216.170344 167.280542)
				(xy 216.168404 167.231328) (xy 216.166359 167.169576) (xy 216.174715 167.099837) (xy 215.957207 167.049293)
				(xy 215.831497 167.237081) (xy 215.88454 167.254912) (xy 215.907082 167.258833) (xy 215.957167 167.271444)
				(xy 215.964717 167.282951) (xy 215.953583 167.301081)
			)
		)
	)
	(zone
		(net 88)
		(net_name "/Com Express 7 Interfaces/PCIe_{B2Ax4}.RX2-")
		(layer "F.Cu")
		(name "$teardrop_padvia$")
		(hatch none 0.1)
		(priority 30268)
		(attr
			(teardrop
				(type padvia)
			)
		)
		(connect_pads yes
			(clearance 0)
		)
		(min_thickness 0.0254)
		(filled_areas_thickness no)
		(fill yes
			(thermal_gap 0.5)
			(thermal_bridge_width 0.5)
			(island_removal_mode 1)
			(island_area_min 10)
		)
		(polygon
			(pts
				(xy 214.3685 162.2) (xy 214.379599 162.373112) (xy 214.394216 162.60051) (xy 214.391181 162.735138)
				(xy 214.375 162.887021) (xy 214.525 163.136) (xy 214.608295 162.26) (xy 214.577864 162.255523) (xy 214.565097 162.244185)
				(xy 214.56742 162.214227) (xy 214.5705 162.2)
			)
		)
	)
	(zone
		(net 731)
		(net_name "Net-(U43C-CLKOUTA-)")
		(layer "F.Cu")
		(name "$teardrop_padvia$")
		(hatch none 0.1)
		(priority 31719)
		(attr
			(teardrop
				(type padvia)
			)
		)
		(connect_pads yes
			(clearance 0)
		)
		(min_thickness 0.0254)
		(filled_areas_thickness no)
		(fill yes
			(thermal_gap 0.5)
			(thermal_bridge_width 0.5)
			(island_removal_mode 1)
			(island_area_min 10)
		)
		(polygon
			(pts
				(xy 148.4875 130.109323) (xy 148.482682 130.178763) (xy 148.46896 130.230087) (xy 148.422245 130.305628)
				(xy 148.412702 130.317768) (xy 148.362919 130.384997) (xy 148.55 130.511) (xy 148.737081 130.384997)
				(xy 148.687299 130.317769) (xy 148.632894 130.234603) (xy 148.61781 130.181748) (xy 148.6125 130.109323)
			)
		)
	)
	(zone
		(net 56)
		(net_name "/USB-C console/USB_D-")
		(layer "F.Cu")
		(name "$teardrop_padvia$")
		(hatch none 0.1)
		(priority 30213)
		(attr
			(teardrop
				(type padvia)
			)
		)
		(connect_pads yes
			(clearance 0)
		)
		(min_thickness 0.0254)
		(filled_areas_thickness no)
		(fill yes
			(thermal_gap 0.5)
			(thermal_bridge_width 0.5)
			(island_removal_mode 1)
			(island_area_min 10)
		)
		(polygon
			(pts
				(xy 107.598445 79.19974) (xy 107.546537 79.244027) (xy 107.480896 79.28461) (xy 107.410915 79.314883)
				(xy 107.330204 79.337083) (xy 107.197163 79.35) (xy 107.278293 79.650707) (xy 107.579 79.731838)
				(xy 107.597039 79.575698) (xy 107.647558 79.442091) (xy 107.723673 79.336252) (xy 107.72926 79.330555)
			)
		)
	)
	(zone
		(net 1)
		(net_name "GND")
		(layer "F.Cu")
		(name "$teardrop_padvia$")
		(hatch none 0.1)
		(priority 30547)
		(attr
			(teardrop
				(type padvia)
			)
		)
		(connect_pads yes
			(clearance 0)
		)
		(min_thickness 0.0254)
		(filled_areas_thickness no)
		(fill yes
			(thermal_gap 0.5)
			(thermal_bridge_width 0.5)
			(island_removal_mode 1)
			(island_area_min 10)
		)
		(polygon
			(pts
				(xy 211.925 162.2) (xy 211.928333 162.214486) (xy 211.93119 162.24461) (xy 211.919036 162.255651)
				(xy 211.89 162.26) (xy 212.025 163.136) (xy 212.16 162.26) (xy 212.130666 162.255525) (xy 212.118642 162.244199)
				(xy 212.121667 162.214486) (xy 212.125 162.2)
			)
		)
	)
	(zone
		(net 1)
		(net_name "GND")
		(layer "F.Cu")
		(name "$teardrop_padvia$")
		(hatch none 0.1)
		(priority 30562)
		(attr
			(teardrop
				(type padvia)
			)
		)
		(connect_pads yes
			(clearance 0)
		)
		(min_thickness 0.0254)
		(filled_areas_thickness no)
		(fill yes
			(thermal_gap 0.5)
			(thermal_bridge_width 0.5)
			(island_removal_mode 1)
			(island_area_min 10)
		)
		(polygon
			(pts
				(xy 210.425 167.75) (xy 210.428333 167.764486) (xy 210.43119 167.79461) (xy 210.419036 167.805651)
				(xy 210.39 167.81) (xy 210.525 168.686) (xy 210.66 167.81) (xy 210.630666 167.805525) (xy 210.618642 167.794199)
				(xy 210.621667 167.764486) (xy 210.625 167.75)
			)
		)
	)
	(zone
		(net 50)
		(net_name "Net-(C12-Pad2)")
		(layer "F.Cu")
		(name "$teardrop_padvia$")
		(hatch none 0.1)
		(priority 31461)
		(attr
			(teardrop
				(type padvia)
			)
		)
		(connect_pads yes
			(clearance 0)
		)
		(min_thickness 0.0254)
		(filled_areas_thickness no)
		(fill yes
			(thermal_gap 0.5)
			(thermal_bridge_width 0.5)
			(island_removal_mode 1)
			(island_area_min 10)
		)
		(polygon
			(pts
				(xy 137.426705 113.21) (xy 137.549553 113.207162) (xy 137.645625 113.206054) (xy 137.756105 113.220677)
				(xy 137.801 113) (xy 137.656519 112.831396) (xy 137.59723 112.900198) (xy 137.588745 112.912689)
				(xy 137.56203 112.950009) (xy 137.53056 112.981002) (xy 137.487673 113.002167) (xy 137.426705 113.01)
			)
		)
	)
	(zone
		(net 23)
		(net_name "/M.2 key E/~{PERST_D}")
		(layer "F.Cu")
		(name "$teardrop_padvia$")
		(hatch none 0.1)
		(priority 31000)
		(attr
			(teardrop
				(type padvia)
			)
		)
		(connect_pads yes
			(clearance 0)
		)
		(min_thickness 0.0254)
		(filled_areas_thickness no)
		(fill yes
			(thermal_gap 0.5)
			(thermal_bridge_width 0.5)
			(island_removal_mode 1)
			(island_area_min 10)
		)
		(polygon
			(pts
				(xy 143.8675 84.622) (xy 143.847531 84.684866) (xy 143.821079 84.716844) (xy 143.783668 84.745358)
				(xy 143.736473 84.767882) (xy 143.678833 84.783093) (xy 143.678202 84.783202) (xy 143.93 85.061)
				(xy 144.181798 84.783202) (xy 144.126365 84.768905) (xy 144.08048 84.747825) (xy 144.042799 84.72046)
				(xy 144.015566 84.689552) (xy 143.998528 84.656265) (xy 143.992511 84.623434) (xy 143.9925 84.622)
			)
		)
	)
	(zone
		(net 1)
		(net_name "GND")
		(layer "F.Cu")
		(name "$teardrop_padvia$")
		(hatch none 0.1)
		(priority 30896)
		(attr
			(teardrop
				(type padvia)
			)
		)
		(connect_pads yes
			(clearance 0)
		)
		(min_thickness 0.0254)
		(filled_areas_thickness no)
		(fill yes
			(thermal_gap 0.5)
			(thermal_bridge_width 0.5)
			(island_removal_mode 1)
			(island_area_min 10)
		)
		(polygon
			(pts
				(xy 124.883 148.456781) (xy 124.887603 148.520102) (xy 124.899828 148.572232) (xy 124.947937 148.672131)
				(xy 124.980259 148.732742) (xy 124.999323 148.803697) (xy 125.22 148.781) (xy 125.345003 148.592919)
				(xy 125.282486 148.565236) (xy 125.213799 148.532132) (xy 125.191441 148.502428) (xy 125.183 148.456781)
			)
		)
	)
	(zone
		(net 9)
		(net_name "/Com Express 7 Interfaces/PCIe_{B1x2}.TX0+")
		(layer "F.Cu")
		(name "$teardrop_padvia$")
		(hatch none 0.1)
		(priority 30258)
		(attr
			(teardrop
				(type padvia)
			)
		)
		(connect_pads yes
			(clearance 0)
		)
		(min_thickness 0.0254)
		(filled_areas_thickness no)
		(fill yes
			(thermal_gap 0.5)
			(thermal_bridge_width 0.5)
			(island_removal_mode 1)
			(island_area_min 10)
		)
		(polygon
			(pts
				(xy 202.9795 167.75) (xy 202.98258 167.764227) (xy 202.984749 167.794527) (xy 202.971877 167.805628)
				(xy 202.941705 167.81) (xy 203.025 168.686) (xy 203.175 168.437021) (xy 203.155644 168.195818) (xy 203.170401 167.923112)
				(xy 203.1815 167.75)
			)
		)
	)
	(zone
		(net 1)
		(net_name "GND")
		(layer "F.Cu")
		(name "$teardrop_padvia$")
		(hatch none 0.1)
		(priority 30578)
		(attr
			(teardrop
				(type padvia)
			)
		)
		(connect_pads yes
			(clearance 0)
		)
		(min_thickness 0.0254)
		(filled_areas_thickness no)
		(fill yes
			(thermal_gap 0.5)
			(thermal_bridge_width 0.5)
			(island_removal_mode 1)
			(island_area_min 10)
		)
		(polygon
			(pts
				(xy 179.625 157.62) (xy 179.621667 157.605514) (xy 179.61881 157.57539) (xy 179.630964 157.564349)
				(xy 179.66 157.56) (xy 179.525 156.684) (xy 179.39 157.56) (xy 179.419334 157.564475) (xy 179.431358 157.575801)
				(xy 179.428333 157.605514) (xy 179.425 157.62)
			)
		)
	)
	(zone
		(net 373)
		(net_name "Net-(J12D-~{THRM})")
		(layer "F.Cu")
		(name "$teardrop_padvia$")
		(hatch none 0.1)
		(priority 30654)
		(attr
			(teardrop
				(type padvia)
			)
		)
		(connect_pads yes
			(clearance 0)
		)
		(min_thickness 0.0254)
		(filled_areas_thickness no)
		(fill yes
			(thermal_gap 0.5)
			(thermal_bridge_width 0.5)
			(island_removal_mode 1)
			(island_area_min 10)
		)
		(polygon
			(pts
				(xy 193.0875 164.07) (xy 193.098438 164.031177) (xy 193.120195 164.016067) (xy 193.16 164.01) (xy 193.025 163.134)
				(xy 192.89 164.01) (xy 192.925281 164.014517) (xy 192.946797 164.026138) (xy 192.961995 164.058961)
				(xy 192.9625 164.07)
			)
		)
	)
	(zone
		(net 1)
		(net_name "GND")
		(layer "F.Cu")
		(name "$teardrop_padvia$")
		(hatch none 0.1)
		(priority 31282)
		(attr
			(teardrop
				(type padvia)
			)
		)
		(connect_pads yes
			(clearance 0)
		)
		(min_thickness 0.0254)
		(filled_areas_thickness no)
		(fill yes
			(thermal_gap 0.5)
			(thermal_bridge_width 0.5)
			(island_removal_mode 1)
			(island_area_min 10)
		)
		(polygon
			(pts
				(xy 208.925 151.874323) (xy 208.920287 151.952234) (xy 208.9073 152.011018) (xy 208.865199 152.102048)
				(xy 208.8225 152.187221) (xy 209.025 152.276) (xy 209.2275 152.187221) (xy 209.184801 152.10205)
				(xy 209.142133 152.009217) (xy 209.129556 151.951078) (xy 209.125 151.874323)
			)
		)
	)
	(zone
		(net 353)
		(net_name "Net-(J12D-~{LPC_DRQ0}{slash}~{ESPI_ALERT0})")
		(layer "F.Cu")
		(name "$teardrop_padvia$")
		(hatch none 0.1)
		(priority 30668)
		(attr
			(teardrop
				(type padvia)
			)
		)
		(connect_pads yes
			(clearance 0)
		)
		(min_thickness 0.0254)
		(filled_areas_thickness no)
		(fill yes
			(thermal_gap 0.5)
			(thermal_bridge_width 0.5)
			(island_removal_mode 1)
			(island_area_min 10)
		)
		(polygon
			(pts
				(xy 179.5875 164.07) (xy 179.598438 164.031177) (xy 179.620195 164.016067) (xy 179.66 164.01) (xy 179.525 163.134)
				(xy 179.39 164.01) (xy 179.425281 164.014517) (xy 179.446797 164.026138) (xy 179.461995 164.058961)
				(xy 179.4625 164.07)
			)
		)
	)
	(zone
		(net 51)
		(net_name "Net-(C13-Pad1)")
		(layer "F.Cu")
		(name "$teardrop_padvia$")
		(hatch none 0.1)
		(priority 30144)
		(attr
			(teardrop
				(type padvia)
			)
		)
		(connect_pads yes
			(clearance 0)
		)
		(min_thickness 0.0254)
		(filled_areas_thickness no)
		(fill yes
			(thermal_gap 0.5)
			(thermal_bridge_width 0.5)
			(island_removal_mode 1)
			(island_area_min 10)
		)
		(polygon
			(pts
				(xy 130.066964 111.039095) (xy 130.122924 111.051039) (xy 130.185844 111.07655) (xy 130.236481 111.109075)
				(xy 130.280113 111.152912) (xy 130.305358 111.194461) (xy 130.321088 111.243508) (xy 130.325207 111.284182)
				(xy 130.770707 110.950707) (xy 130.325861 110.612533) (xy 130.325165 110.687411) (xy 130.318981 110.800239)
				(xy 130.305389 110.822778) (xy 130.279095 110.826964)
			)
		)
	)
	(zone
		(net 217)
		(net_name "/Com Express 7 Interfaces/PCIe_{B1x4}.RX1-")
		(layer "F.Cu")
		(name "$teardrop_padvia$")
		(hatch none 0.1)
		(priority 31555)
		(attr
			(teardrop
				(type padvia)
			)
		)
		(connect_pads yes
			(clearance 0)
		)
		(min_thickness 0.0254)
		(filled_areas_thickness no)
		(fill yes
			(thermal_gap 0.5)
			(thermal_bridge_width 0.5)
			(island_removal_mode 1)
			(island_area_min 10)
		)
		(polygon
			(pts
				(xy 208.041269 161.695933) (xy 208.025206 161.673162) (xy 208.026868 161.656145) (xy 208.059503 161.636548)
				(xy 208.113463 161.622566) (xy 208.170306 161.608159) (xy 208.218503 161.587081) (xy 208.092793 161.399293)
				(xy 207.872823 161.443895) (xy 207.874 161.533751) (xy 207.855641 161.609671) (xy 207.841185 161.665663)
				(xy 207.837116 161.721042) (xy 207.853007 161.77801) (xy 207.898434 161.838768)
			)
		)
	)
	(zone
		(net 356)
		(net_name "/Com Express 7 MGMT/~{CW_PWRBTN}")
		(layer "F.Cu")
		(name "$teardrop_padvia$")
		(hatch none 0.1)
		(priority 31775)
		(attr
			(teardrop
				(type padvia)
			)
		)
		(connect_pads yes
			(clearance 0)
		)
		(min_thickness 0.0254)
		(filled_areas_thickness no)
		(fill yes
			(thermal_gap 0.5)
			(thermal_bridge_width 0.5)
			(island_removal_mode 1)
			(island_area_min 10)
		)
		(polygon
			(pts
				(xy 184.4625 158.900677) (xy 184.467318 158.831236) (xy 184.48104 158.779912) (xy 184.527755 158.70437)
				(xy 184.537299 158.692229) (xy 184.587081 158.625003) (xy 184.4 158.499) (xy 184.212919 158.625003)
				(xy 184.262701 158.692231) (xy 184.317106 158.775397) (xy 184.33219 158.828251) (xy 184.3375 158.900677)
			)
		)
	)
	(zone
		(net 596)
		(net_name "/Misc/PWM2")
		(layer "F.Cu")
		(name "$teardrop_padvia$")
		(hatch none 0.1)
		(priority 30741)
		(attr
			(teardrop
				(type padvia)
			)
		)
		(connect_pads yes
			(clearance 0)
		)
		(min_thickness 0.0254)
		(filled_areas_thickness no)
		(fill yes
			(thermal_gap 0.5)
			(thermal_bridge_width 0.5)
			(island_removal_mode 1)
			(island_area_min 10)
		)
		(polygon
			(pts
				(xy 241.930708 79.0225) (xy 241.874257 79.002455) (xy 241.847447 78.976276) (xy 241.824656 78.939267)
				(xy 241.798773 78.8375) (xy 241.419708 79.085) (xy 241.798773 79.3325) (xy 241.808582 79.275174)
				(xy 241.825736 79.228495) (xy 241.848882 79.191945) (xy 241.875973 79.166305) (xy 241.930708 79.1475)
			)
		)
	)
	(zone
		(net 531)
		(net_name "/Com Express 7 Interfaces/SD_CD")
		(layer "F.Cu")
		(name "$teardrop_padvia$")
		(hatch none 0.1)
		(priority 31072)
		(attr
			(teardrop
				(type padvia)
			)
		)
		(connect_pads yes
			(clearance 0)
		)
		(min_thickness 0.0254)
		(filled_areas_thickness no)
		(fill yes
			(thermal_gap 0.5)
			(thermal_bridge_width 0.5)
			(island_removal_mode 1)
			(island_area_min 10)
		)
		(polygon
			(pts
				(xy 112.993 139.8975) (xy 112.933588 139.877727) (xy 112.877503 139.814453) (xy 112.855801 139.765828)
				(xy 112.841127 139.706468) (xy 112.839347 139.6945) (xy 112.579 139.96) (xy 112.839347 140.2255)
				(xy 112.852197 140.165361) (xy 112.872131 140.115477) (xy 112.898056 140.075358) (xy 112.927876 140.046345)
				(xy 112.959294 140.028854) (xy 112.991105 140.022521) (xy 112.993 140.0225)
			)
		)
	)
	(zone
		(net 207)
		(net_name "/Backplane/UART.TX")
		(layer "F.Cu")
		(name "$teardrop_padvia$")
		(hatch none 0.1)
		(priority 30641)
		(attr
			(teardrop
				(type padvia)
			)
		)
		(connect_pads yes
			(clearance 0)
		)
		(min_thickness 0.0254)
		(filled_areas_thickness no)
		(fill yes
			(thermal_gap 0.5)
			(thermal_bridge_width 0.5)
			(island_removal_mode 1)
			(island_area_min 10)
		)
		(polygon
			(pts
				(xy 226.0875 169.62) (xy 226.098438 169.581177) (xy 226.120195 169.566067) (xy 226.16 169.56) (xy 226.025 168.684)
				(xy 225.89 169.56) (xy 225.925281 169.564517) (xy 225.946797 169.576138) (xy 225.961995 169.608961)
				(xy 225.9625 169.62)
			)
		)
	)
	(zone
		(net 561)
		(net_name "Net-(U5-A1)")
		(layer "F.Cu")
		(name "$teardrop_padvia$")
		(hatch none 0.1)
		(priority 31054)
		(attr
			(teardrop
				(type padvia)
			)
		)
		(connect_pads yes
			(clearance 0)
		)
		(min_thickness 0.0254)
		(filled_areas_thickness no)
		(fill yes
			(thermal_gap 0.5)
			(thermal_bridge_width 0.5)
			(island_removal_mode 1)
			(island_area_min 10)
		)
		(polygon
			(pts
				(xy 158.6125 157.703) (xy 158.632273 157.643588) (xy 158.695547 157.587503) (xy 158.744172 157.565801)
				(xy 158.803532 157.551127) (xy 158.8155 157.549347) (xy 158.55 157.289) (xy 158.2845 157.549347)
				(xy 158.344639 157.562197) (xy 158.394523 157.582131) (xy 158.434642 157.608056) (xy 158.463655 157.637876)
				(xy 158.481146 157.669294) (xy 158.487479 157.701105) (xy 158.4875 157.703)
			)
		)
	)
	(zone
		(net 374)
		(net_name "/2xUSB3.0+RJ45/USB_2.D-")
		(layer "F.Cu")
		(name "$teardrop_padvia$")
		(hatch none 0.1)
		(priority 31504)
		(attr
			(teardrop
				(type padvia)
			)
		)
		(connect_pads yes
			(clearance 0)
		)
		(min_thickness 0.0254)
		(filled_areas_thickness no)
		(fill yes
			(thermal_gap 0.5)
			(thermal_bridge_width 0.5)
			(island_removal_mode 1)
			(island_area_min 10)
		)
		(polygon
			(pts
				(xy 132.476793 115.685321) (xy 132.590111 115.566085) (xy 132.719205 115.436794) (xy 132.572665 115.271251)
				(xy 132.351281 115.267509) (xy 132.364466 115.349818) (xy 132.373636 115.377903) (xy 132.386992 115.421487)
				(xy 132.391836 115.464102) (xy 132.380666 115.507768) (xy 132.345978 115.554506)
			)
		)
	)
	(zone
		(net 249)
		(net_name "/Com Express 7 Interfaces/PCIe_{B2Bx4}.TX2+")
		(layer "F.Cu")
		(name "$teardrop_padvia$")
		(hatch none 0.1)
		(priority 30244)
		(attr
			(teardrop
				(type padvia)
			)
		)
		(connect_pads yes
			(clearance 0)
		)
		(min_thickness 0.0254)
		(filled_areas_thickness no)
		(fill yes
			(thermal_gap 0.5)
			(thermal_bridge_width 0.5)
			(island_removal_mode 1)
			(island_area_min 10)
		)
		(polygon
			(pts
				(xy 187.9795 167.75) (xy 187.98258 167.764227) (xy 187.984749 167.794527) (xy 187.971877 167.805628)
				(xy 187.941705 167.81) (xy 188.025 168.686) (xy 188.175 168.437021) (xy 188.155644 168.195818) (xy 188.170401 167.923112)
				(xy 188.1815 167.75)
			)
		)
	)
	(zone
		(net 1)
		(net_name "GND")
		(layer "F.Cu")
		(name "$teardrop_padvia$")
		(hatch none 0.1)
		(priority 31323)
		(attr
			(teardrop
				(type padvia)
			)
		)
		(connect_pads yes
			(clearance 0)
		)
		(min_thickness 0.0254)
		(filled_areas_thickness no)
		(fill yes
			(thermal_gap 0.5)
			(thermal_bridge_width 0.5)
			(island_removal_mode 1)
			(island_area_min 10)
		)
		(polygon
			(pts
				(xy 176.125 150.312793) (xy 176.131205 150.151365) (xy 176.154641 150.027721) (xy 176.164815 149.986192)
				(xy 176.166731 149.978421) (xy 175.95 149.924) (xy 175.769305 150.056389) (xy 175.838296 150.13039)
				(xy 175.899512 150.199698) (xy 175.918152 150.247293) (xy 175.925 150.312793)
			)
		)
	)
	(zone
		(net 1)
		(net_name "GND")
		(layer "F.Cu")
		(name "$teardrop_padvia$")
		(hatch none 0.1)
		(priority 31290)
		(attr
			(teardrop
				(type padvia)
			)
		)
		(connect_pads yes
			(clearance 0)
		)
		(min_thickness 0.0254)
		(filled_areas_thickness no)
		(fill yes
			(thermal_gap 0.5)
			(thermal_bridge_width 0.5)
			(island_removal_mode 1)
			(island_area_min 10)
		)
		(polygon
			(pts
				(xy 110.6 152.899323) (xy 110.595287 152.977234) (xy 110.5823 153.036018) (xy 110.540199 153.127048)
				(xy 110.4975 153.212221) (xy 110.7 153.301) (xy 110.9025 153.212221) (xy 110.859801 153.12705) (xy 110.817133 153.034217)
				(xy 110.804556 152.976078) (xy 110.8 152.899323)
			)
		)
	)
	(zone
		(net 345)
		(net_name "/Com Express 7 MGMT/SER0.RX")
		(layer "F.Cu")
		(name "$teardrop_padvia$")
		(hatch none 0.1)
		(priority 30671)
		(attr
			(teardrop
				(type padvia)
			)
		)
		(connect_pads yes
			(clearance 0)
		)
		(min_thickness 0.0254)
		(filled_areas_thickness no)
		(fill yes
			(thermal_gap 0.5)
			(thermal_bridge_width 0.5)
			(island_removal_mode 1)
			(island_area_min 10)
		)
		(polygon
			(pts
				(xy 225.0875 169.62) (xy 225.098438 169.581177) (xy 225.120195 169.566067) (xy 225.16 169.56) (xy 225.025 168.684)
				(xy 224.89 169.56) (xy 224.925281 169.564517) (xy 224.946797 169.576138) (xy 224.961995 169.608961)
				(xy 224.9625 169.62)
			)
		)
	)
	(zone
		(net 297)
		(net_name "Net-(J12D-~{SUS_S3})")
		(layer "F.Cu")
		(name "$teardrop_padvia$")
		(hatch none 0.1)
		(priority 30647)
		(attr
			(teardrop
				(type padvia)
			)
		)
		(connect_pads yes
			(clearance 0)
		)
		(min_thickness 0.0254)
		(filled_areas_thickness no)
		(fill yes
			(thermal_gap 0.5)
			(thermal_bridge_width 0.5)
			(island_removal_mode 1)
			(island_area_min 10)
		)
		(polygon
			(pts
				(xy 183.0875 169.62) (xy 183.098438 169.581177) (xy 183.120195 169.566067) (xy 183.16 169.56) (xy 183.025 168.684)
				(xy 182.89 169.56) (xy 182.925281 169.564517) (xy 182.946797 169.576138) (xy 182.961995 169.608961)
				(xy 182.9625 169.62)
			)
		)
	)
	(zone
		(net 24)
		(net_name "/M.2 key E/~{CLKREQ}")
		(layer "F.Cu")
		(name "$teardrop_padvia$")
		(hatch none 0.1)
		(priority 31760)
		(attr
			(teardrop
				(type padvia)
			)
		)
		(connect_pads yes
			(clearance 0)
		)
		(min_thickness 0.0254)
		(filled_areas_thickness no)
		(fill yes
			(thermal_gap 0.5)
			(thermal_bridge_width 0.5)
			(island_removal_mode 1)
			(island_area_min 10)
		)
		(polygon
			(pts
				(xy 154.329323 84.122) (xy 154.398764 84.126818) (xy 154.450088 84.14054) (xy 154.525629 84.187255)
				(xy 154.537769 84.196799) (xy 154.604997 84.246581) (xy 154.731 84.0595) (xy 154.604997 83.872419)
				(xy 154.537768 83.922202) (xy 154.454602 83.976606) (xy 154.401748 83.99169) (xy 154.329323 83.997)
			)
		)
	)
	(zone
		(net 340)
		(net_name "/Com Express 7 MGMT/SPI.CLK")
		(layer "F.Cu")
		(name "$teardrop_padvia$")
		(hatch none 0.1)
		(priority 30701)
		(attr
			(teardrop
				(type padvia)
			)
		)
		(connect_pads yes
			(clearance 0)
		)
		(min_thickness 0.0254)
		(filled_areas_thickness no)
		(fill yes
			(thermal_gap 0.5)
			(thermal_bridge_width 0.5)
			(island_removal_mode 1)
			(island_area_min 10)
		)
		(polygon
			(pts
				(xy 222.4625 167.75) (xy 222.451563 167.788823) (xy 222.429805 167.803933) (xy 222.39 167.81) (xy 222.525 168.686)
				(xy 222.66 167.81) (xy 222.624719 167.805483) (xy 222.603203 167.793862) (xy 222.588005 167.761039)
				(xy 222.5875 167.75)
			)
		)
	)
	(zone
		(net 1)
		(net_name "GND")
		(layer "F.Cu")
		(name "$teardrop_padvia$")
		(hatch none 0.1)
		(priority 30570)
		(attr
			(teardrop
				(type padvia)
			)
		)
		(connect_pads yes
			(clearance 0)
		)
		(min_thickness 0.0254)
		(filled_areas_thickness no)
		(fill yes
			(thermal_gap 0.5)
			(thermal_bridge_width 0.5)
			(island_removal_mode 1)
			(island_area_min 10)
		)
		(polygon
			(pts
				(xy 196.125 169.62) (xy 196.121667 169.605514) (xy 196.11881 169.57539) (xy 196.130964 169.564349)
				(xy 196.16 169.56) (xy 196.025 168.684) (xy 195.89 169.56) (xy 195.919334 169.564475) (xy 195.931358 169.575801)
				(xy 195.928333 169.605514) (xy 195.925 169.62)
			)
		)
	)
	(zone
		(net 1)
		(net_name "GND")
		(layer "F.Cu")
		(name "$teardrop_padvia$")
		(hatch none 0.1)
		(priority 30558)
		(attr
			(teardrop
				(type padvia)
			)
		)
		(connect_pads yes
			(clearance 0)
		)
		(min_thickness 0.0254)
		(filled_areas_thickness no)
		(fill yes
			(thermal_gap 0.5)
			(thermal_bridge_width 0.5)
			(island_removal_mode 1)
			(island_area_min 10)
		)
		(polygon
			(pts
				(xy 210.425 162.2) (xy 210.428333 162.214486) (xy 210.43119 162.24461) (xy 210.419036 162.255651)
				(xy 210.39 162.26) (xy 210.525 163.136) (xy 210.66 162.26) (xy 210.630666 162.255525) (xy 210.618642 162.244199)
				(xy 210.621667 162.214486) (xy 210.625 162.2)
			)
		)
	)
	(zone
		(net 1)
		(net_name "GND")
		(layer "F.Cu")
		(name "$teardrop_padvia$")
		(hatch none 0.1)
		(priority 31035)
		(attr
			(teardrop
				(type padvia)
			)
		)
		(connect_pads yes
			(clearance 0)
		)
		(min_thickness 0.0254)
		(filled_areas_thickness no)
		(fill yes
			(thermal_gap 0.5)
			(thermal_bridge_width 0.5)
			(island_removal_mode 1)
			(island_area_min 10)
		)
		(polygon
			(pts
				(xy 190.040414 138.167183) (xy 190.070746 138.225756) (xy 190.074654 138.267072) (xy 190.068363 138.313688)
				(xy 190.050917 138.362986) (xy 190.020915 138.414499) (xy 190.020545 138.415024) (xy 190.395026 138.433409)
				(xy 190.376641 138.058928) (xy 190.327336 138.088016) (xy 190.279985 138.105555) (xy 190.23399 138.11285)
				(xy 190.192879 138.110251) (xy 190.157294 138.098761) (xy 190.129825 138.079802) (xy 190.128802 138.078795)
			)
		)
	)
	(zone
		(net 633)
		(net_name "Net-(U41-A0)")
		(layer "F.Cu")
		(name "$teardrop_padvia$")
		(hatch none 0.1)
		(priority 30966)
		(attr
			(teardrop
				(type padvia)
			)
		)
		(connect_pads yes
			(clearance 0)
		)
		(min_thickness 0.0254)
		(filled_areas_thickness no)
		(fill yes
			(thermal_gap 0.5)
			(thermal_bridge_width 0.5)
			(island_removal_mode 1)
			(island_area_min 10)
		)
		(polygon
			(pts
				(xy 133.8825 83.872001) (xy 133.862531 83.934867) (xy 133.836079 83.966845) (xy 133.798668 83.995359)
				(xy 133.751473 84.017883) (xy 133.693833 84.033094) (xy 133.693202 84.033203) (xy 133.945 84.311001)
				(xy 134.196798 84.033203) (xy 134.141365 84.018906) (xy 134.09548 83.997826) (xy 134.057799 83.970461)
				(xy 134.030566 83.939553) (xy 134.013528 83.906266) (xy 134.007511 83.873435) (xy 134.0075 83.872001)
			)
		)
	)
	(zone
		(net 62)
		(net_name "+12V_AON")
		(layer "F.Cu")
		(name "$teardrop_padvia$")
		(hatch none 0.1)
		(priority 30072)
		(attr
			(teardrop
				(type padvia)
			)
		)
		(connect_pads yes
			(clearance 0)
		)
		(min_thickness 0.0254)
		(filled_areas_thickness no)
		(fill yes
			(thermal_gap 0.5)
			(thermal_bridge_width 0.5)
			(island_removal_mode 1)
			(island_area_min 10)
		)
		(polygon
			(pts
				(xy 200.36861 74.002163) (xy 200.331448 73.997088) (xy 200.29357 73.981561) (xy 200.257048 73.955293)
				(xy 200.223556 73.917786) (xy 200.195948 73.870716) (xy 200.174522 73.812452) (xy 200.161747 73.749026)
				(xy 199.70761 74.102163) (xy 200.161747 74.4553) (xy 200.175342 74.388965) (xy 200.196094 74.3333)
				(xy 200.223203 74.287029) (xy 200.254696 74.251184) (xy 200.290337 74.224605) (xy 200.327253 74.208435)
				(xy 200.36861 74.202163)
			)
		)
	)
	(zone
		(net 228)
		(net_name "/M.2 key M #1/~{PERST_D}")
		(layer "F.Cu")
		(name "$teardrop_padvia$")
		(hatch none 0.1)
		(priority 31824)
		(attr
			(teardrop
				(type padvia)
			)
		)
		(connect_pads yes
			(clearance 0)
		)
		(min_thickness 0.0254)
		(filled_areas_thickness no)
		(fill yes
			(thermal_gap 0.5)
			(thermal_bridge_width 0.5)
			(island_removal_mode 1)
			(island_area_min 10)
		)
		(polygon
			(pts
				(xy 178.130407 104.801577) (xy 178.060966 104.796759) (xy 178.009643 104.783037) (xy 177.934101 104.736323)
				(xy 177.921961 104.726778) (xy 177.854733 104.676996) (xy 177.72873 104.864077) (xy 177.854733 105.051158)
				(xy 177.921959 105.001376) (xy 178.005126 104.946971) (xy 178.057981 104.931887) (xy 178.130407 104.926577)
			)
		)
	)
	(zone
		(net 1)
		(net_name "GND")
		(layer "F.Cu")
		(name "$teardrop_padvia$")
		(hatch none 0.1)
		(priority 31523)
		(attr
			(teardrop
				(type padvia)
			)
		)
		(connect_pads yes
			(clearance 0)
		)
		(min_thickness 0.0254)
		(filled_areas_thickness no)
		(fill yes
			(thermal_gap 0.5)
			(thermal_bridge_width 0.5)
			(island_removal_mode 1)
			(island_area_min 10)
		)
		(polygon
			(pts
				(xy 114.984999 74.405) (xy 114.97675 74.382923) (xy 114.966016 74.344428) (xy 114.978981 74.330475)
				(xy 115.014999 74.325) (xy 114.834999 73.924) (xy 114.654999 74.325) (xy 114.688734 74.32954) (xy 114.702927 74.341323)
				(xy 114.699445 74.369817) (xy 114.693248 74.382923) (xy 114.684999 74.405)
			)
		)
	)
	(zone
		(net 533)
		(net_name "/Com Express 7 MGMT/PSON")
		(layer "F.Cu")
		(name "$teardrop_padvia$")
		(hatch none 0.1)
		(priority 30840)
		(attr
			(teardrop
				(type padvia)
			)
		)
		(connect_pads yes
			(clearance 0)
		)
		(min_thickness 0.0254)
		(filled_areas_thickness no)
		(fill yes
			(thermal_gap 0.5)
			(thermal_bridge_width 0.5)
			(island_removal_mode 1)
			(island_area_min 10)
		)
		(polygon
			(pts
				(xy 303.013 137.705) (xy 302.966789 137.69879) (xy 302.91839 137.675323) (xy 302.890034 137.647416)
				(xy 302.866988 137.60719) (xy 302.851798 137.553202) (xy 302.574 137.805) (xy 302.851798 138.056798)
				(xy 302.864931 138.007946) (xy 302.884335 137.970436) (xy 302.936945 137.923013) (xy 303.003446 137.905257)
				(xy 303.013 137.905)
			)
		)
	)
	(zone
		(net 670)
		(net_name "/2xSFP+/KR to SFI #2/MDIO")
		(layer "F.Cu")
		(name "$teardrop_padvia$")
		(hatch none 0.1)
		(priority 31457)
		(attr
			(teardrop
				(type padvia)
			)
		)
		(connect_pads yes
			(clearance 0)
		)
		(min_thickness 0.0254)
		(filled_areas_thickness no)
		(fill yes
			(thermal_gap 0.5)
			(thermal_bridge_width 0.5)
			(island_removal_mode 1)
			(island_area_min 10)
		)
		(polygon
			(pts
				(xy 125.043283 143.96833) (xy 125.022421 143.970711) (xy 125.004159 143.96195) (xy 124.973725 143.911885)
				(xy 124.941798 143.773202) (xy 124.689293 144.050707) (xy 124.965776 144.290912) (xy 124.991115 144.196044)
				(xy 125.049248 144.112738) (xy 125.127758 144.058211) (xy 125.13167 144.056717)
			)
		)
	)
	(zone
		(net 50)
		(net_name "Net-(C12-Pad2)")
		(layer "F.Cu")
		(name "$teardrop_padvia$")
		(hatch none 0.1)
		(priority 31243)
		(attr
			(teardrop
				(type padvia)
			)
		)
		(connect_pads yes
			(clearance 0)
		)
		(min_thickness 0.0254)
		(filled_areas_thickness no)
		(fill yes
			(thermal_gap 0.5)
			(thermal_bridge_width 0.5)
			(island_removal_mode 1)
			(island_area_min 10)
		)
		(polygon
			(pts
				(xy 137.399323 109.32) (xy 137.487165 109.324727) (xy 137.552296 109.337816) (xy 137.640112 109.372211)
				(xy 137.722288 109.406669) (xy 137.801 109.2) (xy 137.700779 109.002239) (xy 137.616578 109.05232)
				(xy 137.52919 109.100428) (xy 137.47342 109.114776) (xy 137.399323 109.12)
			)
		)
	)
	(zone
		(net 343)
		(net_name "Net-(J12D-~{TYPE10})")
		(layer "F.Cu")
		(name "$teardrop_padvia$")
		(hatch none 0.1)
		(priority 31874)
		(attr
			(teardrop
				(type padvia)
			)
		)
		(connect_pads yes
			(clearance 0)
		)
		(min_thickness 0.0254)
		(filled_areas_thickness no)
		(fill yes
			(thermal_gap 0.5)
			(thermal_bridge_width 0.5)
			(island_removal_mode 1)
			(island_area_min 10)
		)
		(polygon
			(pts
				(xy 224.160873 165.577515) (xy 224.213382 165.531819) (xy 224.259376 165.505231) (xy 224.345824 165.484847)
				(xy 224.36116 165.483011) (xy 224.443895 165.470677) (xy 224.400707 165.249293) (xy 224.179323 165.206105)
				(xy 224.166988 165.288841) (xy 224.146651 165.386119) (xy 224.119943 165.434159) (xy 224.072485 165.489127)
			)
		)
	)
	(zone
		(net 604)
		(net_name "Net-(U37-~{OE2})")
		(layer "F.Cu")
		(name "$teardrop_padvia$")
		(hatch none 0.1)
		(priority 30941)
		(attr
			(teardrop
				(type padvia)
			)
		)
		(connect_pads yes
			(clearance 0)
		)
		(min_thickness 0.0254)
		(filled_areas_thickness no)
		(fill yes
			(thermal_gap 0.5)
			(thermal_bridge_width 0.5)
			(island_removal_mode 1)
			(island_area_min 10)
		)
		(polygon
			(pts
				(xy 216.497 136.5225) (xy 216.559866 136.542469) (xy 216.591844 136.568921) (xy 216.620358 136.606332)
				(xy 216.642882 136.653527) (xy 216.658093 136.711167) (xy 216.658202 136.711798) (xy 216.936 136.46)
				(xy 216.658202 136.208202) (xy 216.643905 136.263635) (xy 216.622825 136.30952) (xy 216.59546 136.347201)
				(xy 216.564552 136.374434) (xy 216.531265 136.391472) (xy 216.498434 136.397489) (xy 216.497 136.3975)
			)
		)
	)
	(zone
		(net 973)
		(net_name "/PCIe redriver/RX_SW")
		(layer "F.Cu")
		(name "$teardrop_padvia$")
		(hatch none 0.1)
		(priority 31023)
		(attr
			(teardrop
				(type padvia)
			)
		)
		(connect_pads yes
			(clearance 0)
		)
		(min_thickness 0.0254)
		(filled_areas_thickness no)
		(fill yes
			(thermal_gap 0.5)
			(thermal_bridge_width 0.5)
			(island_removal_mode 1)
			(island_area_min 10)
		)
		(polygon
			(pts
				(xy 191.649576 129.566786) (xy 191.679908 129.625359) (xy 191.683815 129.666675) (xy 191.677524 129.713291)
				(xy 191.660079 129.76259) (xy 191.630077 129.814103) (xy 191.629708 129.814626) (xy 192.004189 129.833011)
				(xy 191.985804 129.45853) (xy 191.936498 129.487618) (xy 191.889147 129.505157) (xy 191.843152 129.512452)
				(xy 191.80204 129.509853) (xy 191.766455 129.498364) (xy 191.738986 129.479404) (xy 191.737964 129.478398)
			)
		)
	)
	(zone
		(net 78)
		(net_name "+1V8")
		(layer "F.Cu")
		(name "$teardrop_padvia$")
		(hatch none 0.1)
		(priority 30900)
		(attr
			(teardrop
				(type padvia)
			)
		)
		(connect_pads yes
			(clearance 0)
		)
		(min_thickness 0.0254)
		(filled_areas_thickness no)
		(fill yes
			(thermal_gap 0.5)
			(thermal_bridge_width 0.5)
			(island_removal_mode 1)
			(island_area_min 10)
		)
		(polygon
			(pts
				(xy 142.389 148.444426) (xy 142.384303 148.483683) (xy 142.371427 148.513461) (xy 142.326401 148.554726)
				(xy 142.293016 148.572756) (xy 142.234708 148.608207) (xy 142.377 148.779) (xy 142.597677 148.787906)
				(xy 142.617763 148.69858) (xy 142.637511 148.654042) (xy 142.672492 148.566739) (xy 142.689 148.444426)
			)
		)
	)
	(zone
		(net 594)
		(net_name "Net-(U24-GPIO4)")
		(layer "F.Cu")
		(name "$teardrop_padvia$")
		(hatch none 0.1)
		(priority 30829)
		(attr
			(teardrop
				(type padvia)
			)
		)
		(connect_pads yes
			(clearance 0)
		)
		(min_thickness 0.0254)
		(filled_areas_thickness no)
		(fill yes
			(thermal_gap 0.5)
			(thermal_bridge_width 0.5)
			(island_removal_mode 1)
			(island_area_min 10)
		)
		(polygon
			(pts
				(xy 254.015907 86.404293) (xy 254.081263 86.433157) (xy 254.110759 86.462689) (xy 254.13199 86.502102)
				(xy 254.14 86.550448) (xy 254.700707 86.370707) (xy 254.14 86.172397) (xy 254.140001 86.179942)
				(xy 254.135561 86.284745) (xy 254.124956 86.309715) (xy 254.104294 86.315906)
			)
		)
	)
	(zone
		(net 1)
		(net_name "GND")
		(layer "F.Cu")
		(name "$teardrop_padvia$")
		(hatch none 0.1)
		(priority 31194)
		(attr
			(teardrop
				(type padvia)
			)
		)
		(connect_pads yes
			(clearance 0)
		)
		(min_thickness 0.0254)
		(filled_areas_thickness no)
		(fill yes
			(thermal_gap 0.5)
			(thermal_bridge_width 0.5)
			(island_removal_mode 1)
			(island_area_min 10)
		)
		(polygon
			(pts
				(xy 194.625 162.321677) (xy 194.62972 162.252353) (xy 194.642756 162.199449) (xy 194.694658 162.10686)
				(xy 194.746458 162.023363) (xy 194.55 161.92) (xy 194.342355 161.996358) (xy 194.374583 162.076861)
				(xy 194.410965 162.178318) (xy 194.425 162.321677)
			)
		)
	)
	(zone
		(net 150)
		(net_name "/2xUSB3.0+RJ45/DC-")
		(layer "F.Cu")
		(name "$teardrop_padvia$")
		(hatch none 0.1)
		(priority 30027)
		(attr
			(teardrop
				(type padvia)
			)
		)
		(connect_pads yes
			(clearance 0)
		)
		(min_thickness 0.0254)
		(filled_areas_thickness no)
		(fill yes
			(thermal_gap 0.5)
			(thermal_bridge_width 0.5)
			(island_removal_mode 1)
			(island_area_min 10)
		)
		(polygon
			(pts
				(xy 117.278034 104.928032) (xy 117.321409 104.891528) (xy 117.360623 104.872127) (xy 117.39156 104.867671)
				(xy 117.420381 104.873255) (xy 117.476611 104.912906) (xy 117.548067 105.008998) (xy 117.573452 105.049255)
				(xy 117.662311 105.181264) (xy 117.714802 105.241372) (xy 117.77499 105.291242) (xy 118.150707 104.729293)
				(xy 117.588758 104.35499) (xy 117.488638 104.495569) (xy 117.403472 104.594205) (xy 117.301447 104.695169)
				(xy 117.171968 104.821966)
			)
		)
	)
	(zone
		(net 651)
		(net_name "/2xSFP+/KR to SFI #1/MDC")
		(layer "F.Cu")
		(name "$teardrop_padvia$")
		(hatch none 0.1)
		(priority 31066)
		(attr
			(teardrop
				(type padvia)
			)
		)
		(connect_pads yes
			(clearance 0)
		)
		(min_thickness 0.0254)
		(filled_areas_thickness no)
		(fill yes
			(thermal_gap 0.5)
			(thermal_bridge_width 0.5)
			(island_removal_mode 1)
			(island_area_min 10)
		)
		(polygon
			(pts
				(xy 143.263 144.9875) (xy 143.203588 144.967727) (xy 143.147503 144.904453) (xy 143.125801 144.855828)
				(xy 143.111127 144.796468) (xy 143.109347 144.7845) (xy 142.849 145.05) (xy 143.109347 145.3155)
				(xy 143.122197 145.255361) (xy 143.142131 145.205477) (xy 143.168056 145.165358) (xy 143.197876 145.136345)
				(xy 143.229294 145.118854) (xy 143.261105 145.112521) (xy 143.263 145.1125)
			)
		)
	)
	(zone
		(net 554)
		(net_name "/2xUSB3.0+RJ45/FLG_2B")
		(layer "F.Cu")
		(name "$teardrop_padvia$")
		(hatch none 0.1)
		(priority 30994)
		(attr
			(teardrop
				(type padvia)
			)
		)
		(connect_pads yes
			(clearance 0)
		)
		(min_thickness 0.0254)
		(filled_areas_thickness no)
		(fill yes
			(thermal_gap 0.5)
			(thermal_bridge_width 0.5)
			(island_removal_mode 1)
			(island_area_min 10)
		)
		(polygon
			(pts
				(xy 121.6325 92.398) (xy 121.652469 92.335134) (xy 121.678921 92.303156) (xy 121.716332 92.274642)
				(xy 121.763527 92.252118) (xy 121.821167 92.236907) (xy 121.821798 92.236798) (xy 121.57 91.959)
				(xy 121.318202 92.236798) (xy 121.373635 92.251095) (xy 121.41952 92.272175) (xy 121.457201 92.29954)
				(xy 121.484434 92.330448) (xy 121.501472 92.363735) (xy 121.507489 92.396566) (xy 121.5075 92.398)
			)
		)
	)
	(zone
		(net 1)
		(net_name "GND")
		(layer "F.Cu")
		(name "$teardrop_padvia$")
		(hatch none 0.1)
		(priority 31235)
		(attr
			(teardrop
				(type padvia)
			)
		)
		(connect_pads yes
			(clearance 0)
		)
		(min_thickness 0.0254)
		(filled_areas_thickness no)
		(fill yes
			(thermal_gap 0.5)
			(thermal_bridge_width 0.5)
			(island_removal_mode 1)
			(island_area_min 10)
		)
		(polygon
			(pts
				(xy 212.125 155.900677) (xy 212.129737 155.809676) (xy 212.142896 155.742587) (xy 212.175418 155.655855)
				(xy 212.207644 155.575358) (xy 212 155.499) (xy 211.803541 155.602363) (xy 211.855343 155.685863)
				(xy 211.904833 155.771955) (xy 211.919614 155.82716) (xy 211.925 155.900677)
			)
		)
	)
	(zone
		(net 528)
		(net_name "/Backplane/~{PERST}")
		(layer "F.Cu")
		(name "$teardrop_padvia$")
		(hatch none 0.1)
		(priority 31089)
		(attr
			(teardrop
				(type padvia)
			)
		)
		(connect_pads yes
			(clearance 0)
		)
		(min_thickness 0.0254)
		(filled_areas_thickness no)
		(fill yes
			(thermal_gap 0.5)
			(thermal_bridge_width 0.5)
			(island_removal_mode 1)
			(island_area_min 10)
		)
		(polygon
			(pts
				(xy 290.743 102.7975) (xy 290.683588 102.777727) (xy 290.627503 102.714453) (xy 290.605801 102.665828)
				(xy 290.591127 102.606468) (xy 290.589347 102.5945) (xy 290.329 102.86) (xy 290.589347 103.1255)
				(xy 290.602197 103.065361) (xy 290.622131 103.015477) (xy 290.648056 102.975358) (xy 290.677876 102.946345)
				(xy 290.709294 102.928854) (xy 290.741105 102.922521) (xy 290.743 102.9225)
			)
		)
	)
	(zone
		(net 254)
		(net_name "/Com Express 7 Interfaces/PCIe_{B2Bx4}.RX1+")
		(layer "F.Cu")
		(name "$teardrop_padvia$")
		(hatch none 0.1)
		(priority 31418)
		(attr
			(teardrop
				(type padvia)
			)
		)
		(connect_pads yes
			(clearance 0)
		)
		(min_thickness 0.0254)
		(filled_areas_thickness no)
		(fill yes
			(thermal_gap 0.5)
			(thermal_bridge_width 0.5)
			(island_removal_mode 1)
			(island_area_min 10)
		)
		(polygon
			(pts
				(xy 194.274027 160.093744) (xy 194.384432 159.975708) (xy 194.441608 159.91351) (xy 194.516785 159.84487)
				(xy 194.375493 159.674079) (xy 194.154109 159.664618) (xy 194.164381 159.751455) (xy 194.169023 159.770088)
				(xy 194.179045 159.814757) (xy 194.18096 159.8584) (xy 194.167448 159.903092) (xy 194.131191 159.950908)
			)
		)
	)
	(zone
		(net 252)
		(net_name "/Com Express 7 Interfaces/PCIe_{B2Bx4}.RX1-")
		(layer "F.Cu")
		(name "$teardrop_padvia$")
		(hatch none 0.1)
		(priority 30275)
		(attr
			(teardrop
				(type padvia)
			)
		)
		(connect_pads yes
			(clearance 0)
		)
		(min_thickness 0.0254)
		(filled_areas_thickness no)
		(fill yes
			(thermal_gap 0.5)
			(thermal_bridge_width 0.5)
			(island_removal_mode 1)
			(island_area_min 10)
		)
		(polygon
			(pts
				(xy 193.8685 162.2) (xy 193.879599 162.373112) (xy 193.894216 162.60051) (xy 193.891181 162.735138)
				(xy 193.875 162.887021) (xy 194.025 163.136) (xy 194.108295 162.26) (xy 194.077864 162.255523) (xy 194.065097 162.244185)
				(xy 194.06742 162.214227) (xy 194.0705 162.2)
			)
		)
	)
	(zone
		(net 695)
		(net_name "/2xUSB3.0+RJ45/DD_FL+")
		(layer "F.Cu")
		(name "$teardrop_padvia$")
		(hatch none 0.1)
		(priority 31979)
		(attr
			(teardrop
				(type padvia)
			)
		)
		(connect_pads yes
			(clearance 0)
		)
		(min_thickness 0.0254)
		(filled_areas_thickness no)
		(fill yes
			(thermal_gap 0.5)
			(thermal_bridge_width 0.5)
			(island_removal_mode 1)
			(island_area_min 10)
		)
		(polygon
			(pts
				(xy 130.285858 101.841923) (xy 130.299094 101.851437) (xy 130.324793 101.873581) (xy 130.32868 101.889941)
				(xy 130.32 101.911498) (xy 130.800707 101.960707) (xy 130.784389 101.825) (xy 130.627296 101.820002)
				(xy 130.508147 101.800026) (xy 130.452418 101.778863) (xy 130.40698 101.749564) (xy 130.391923 101.735858)
			)
		)
	)
	(zone
		(net 292)
		(net_name "/2xUSB3.0+RJ45/GbE.MDI1-")
		(layer "F.Cu")
		(name "$teardrop_padvia$")
		(hatch none 0.1)
		(priority 31652)
		(attr
			(teardrop
				(type padvia)
			)
		)
		(connect_pads yes
			(clearance 0)
		)
		(min_thickness 0.0254)
		(filled_areas_thickness no)
		(fill yes
			(thermal_gap 0.5)
			(thermal_bridge_width 0.5)
			(island_removal_mode 1)
			(island_area_min 10)
		)
		(polygon
			(pts
				(xy 170.7 163.657916) (xy 170.702203 163.8633) (xy 170.704323 164.001757) (xy 170.925 164.001) (xy 171.050003 163.812919)
				(xy 170.973862 163.779004) (xy 170.957261 163.773949) (xy 170.915719 163.760156) (xy 170.881601 163.740737)
				(xy 170.858499 163.708917) (xy 170.85 163.657916)
			)
		)
	)
	(zone
		(net 1)
		(net_name "GND")
		(layer "F.Cu")
		(name "$teardrop_padvia$")
		(hatch none 0.1)
		(priority 32145)
		(attr
			(teardrop
				(type padvia)
			)
		)
		(connect_pads yes
			(clearance 0)
		)
		(min_thickness 0.0254)
		(filled_areas_thickness no)
		(fill yes
			(thermal_gap 0.5)
			(thermal_bridge_width 0.5)
			(island_removal_mode 1)
			(island_area_min 10)
		)
		(polygon
			(pts
				(xy 304.237677 75.19) (xy 304.244605 75.194406) (xy 304.23567 75.205249) (xy 304.216577 75.22086)
				(xy 304.198365 75.235989) (xy 304.198 75.2425) (xy 304.198 75.04) (xy 304.198 75.2425) (xy 304.243082 75.224111)
				(xy 304.291672 75.161929) (xy 304.328624 75.053272) (xy 304.332435 74.998476) (xy 304.3239 74.94999)
				(xy 304.307936 74.920537) (xy 304.282812 74.899922) (xy 304.237677 74.89)
			)
		)
	)
	(zone
		(net 138)
		(net_name "Net-(U33-1A)")
		(layer "F.Cu")
		(name "$teardrop_padvia$")
		(hatch none 0.1)
		(priority 31095)
		(attr
			(teardrop
				(type padvia)
			)
		)
		(connect_pads yes
			(clearance 0)
		)
		(min_thickness 0.0254)
		(filled_areas_thickness no)
		(fill yes
			(thermal_gap 0.5)
			(thermal_bridge_width 0.5)
			(island_removal_mode 1)
			(island_area_min 10)
		)
		(polygon
			(pts
				(xy 251.5625 129.517) (xy 251.542727 129.576412) (xy 251.479453 129.632496) (xy 251.430828 129.654198)
				(xy 251.371469 129.668872) (xy 251.3595 129.670652) (xy 251.625 129.931) (xy 251.8905 129.670652)
				(xy 251.830362 129.657803) (xy 251.780478 129.637869) (xy 251.740358 129.611944) (xy 251.711345 129.582124)
				(xy 251.693854 129.550706) (xy 251.687521 129.518895) (xy 251.6875 129.517)
			)
		)
	)
	(zone
		(net 426)
		(net_name "Net-(J12K-10G_SDP0)")
		(layer "F.Cu")
		(name "$teardrop_padvia$")
		(hatch none 0.1)
		(priority 30652)
		(attr
			(teardrop
				(type padvia)
			)
		)
		(connect_pads yes
			(clearance 0)
		)
		(min_thickness 0.0254)
		(filled_areas_thickness no)
		(fill yes
			(thermal_gap 0.5)
			(thermal_bridge_width 0.5)
			(island_removal_mode 1)
			(island_area_min 10)
		)
		(polygon
			(pts
				(xy 195.5875 157.62) (xy 195.598438 157.581177) (xy 195.620195 157.566067) (xy 195.66 157.56) (xy 195.525 156.684)
				(xy 195.39 157.56) (xy 195.425281 157.564517) (xy 195.446797 157.576138) (xy 195.461995 157.608961)
				(xy 195.4625 157.62)
			)
		)
	)
	(zone
		(net 193)
		(net_name "/OCuLink/PCIe_{REF0}.CK-")
		(layer "F.Cu")
		(name "$teardrop_padvia$")
		(hatch none 0.1)
		(priority 31349)
		(attr
			(teardrop
				(type padvia)
			)
		)
		(connect_pads yes
			(clearance 0)
		)
		(min_thickness 0.0254)
		(filled_areas_thickness no)
		(fill yes
			(thermal_gap 0.5)
			(thermal_bridge_width 0.5)
			(island_removal_mode 1)
			(island_area_min 10)
		)
		(polygon
			(pts
				(xy 207.737496 129.6295) (xy 207.69071 129.624765) (xy 207.655258 129.611621) (xy 207.60706 129.566613)
				(xy 207.582884 129.528392) (xy 207.555514 129.485225) (xy 207.518852 129.443268) (xy 207.369 129.6065)
				(xy 207.38986 129.827177) (xy 207.490531 129.822548) (xy 207.573897 129.82598) (xy 207.575964 129.826105)
				(xy 207.737496 129.8315)
			)
		)
	)
	(zone
		(net 1)
		(net_name "GND")
		(layer "F.Cu")
		(hatch edge 0.5)
		(priority 1)
		(connect_pads
			(clearance 0.15)
		)
		(min_thickness 0.25)
		(filled_areas_thickness no)
		(fill yes
			(thermal_gap 0.15)
			(thermal_bridge_width 0.3)
		)
		(polygon
			(pts
				(xy 114.08 146.486) (xy 114.08 148.236) (xy 120.72 148.236) (xy 120.72 146.486)
			)
		)
	)
	(zone
		(net 633)
		(net_name "Net-(U41-A0)")
		(layer "F.Cu")
		(name "$teardrop_padvia$")
		(hatch none 0.1)
		(priority 32025)
		(attr
			(teardrop
				(type padvia)
			)
		)
		(connect_pads yes
			(clearance 0)
		)
		(min_thickness 0.0254)
		(filled_areas_thickness no)
		(fill yes
			(thermal_gap 0.5)
			(thermal_bridge_width 0.5)
			(island_removal_mode 1)
			(island_area_min 10)
		)
		(polygon
			(pts
				(xy 133.0495 84.2475) (xy 133.043178 84.247596) (xy 133.003675 84.242011) (xy 132.985453 84.227078)
				(xy 132.972505 84.1975) (xy 132.586 84.31) (xy 132.972505 84.4225) (xy 132.983621 84.395506) (xy 132.999148 84.380405)
				(xy 133.043178 84.372404) (xy 133.0495 84.3725)
			)
		)
	)
	(zone
		(net 142)
		(net_name "/2xSFP+/PHY0_{RESET}")
		(layer "F.Cu")
		(name "$teardrop_padvia$")
		(hatch none 0.1)
		(priority 31823)
		(attr
			(teardrop
				(type padvia)
			)
		)
		(connect_pads yes
			(clearance 0)
		)
		(min_thickness 0.0254)
		(filled_areas_thickness no)
		(fill yes
			(thermal_gap 0.5)
			(thermal_bridge_width 0.5)
			(island_removal_mode 1)
			(island_area_min 10)
		)
		(polygon
			(pts
				(xy 176.550677 154.5375) (xy 176.481236 154.532682) (xy 176.429913 154.51896) (xy 176.354371 154.472246)
				(xy 176.342231 154.462701) (xy 176.275003 154.412919) (xy 176.149 154.6) (xy 176.275003 154.787081)
				(xy 176.342229 154.737299) (xy 176.425396 154.682894) (xy 176.478251 154.66781) (xy 176.550677 154.6625)
			)
		)
	)
	(zone
		(net 2)
		(net_name "+3V3")
		(layer "F.Cu")
		(name "$teardrop_padvia$")
		(hatch none 0.1)
		(priority 31977)
		(attr
			(teardrop
				(type padvia)
			)
		)
		(connect_pads yes
			(clearance 0)
		)
		(min_thickness 0.0254)
		(filled_areas_thickness no)
		(fill yes
			(thermal_gap 0.5)
			(thermal_bridge_width 0.5)
			(island_removal_mode 1)
			(island_area_min 10)
		)
		(polygon
			(pts
				(xy 218.45329 130.193709) (xy 218.481561 130.228566) (xy 218.495177 130.259998) (xy 218.500633 130.310281)
				(xy 218.506323 130.369895) (xy 218.727707 130.326707) (xy 218.770895 130.105323) (xy 218.711283 130.099634)
				(xy 218.654968 130.092392) (xy 218.594712 130.052291)
			)
		)
	)
	(zone
		(net 312)
		(net_name "/2xUSB3.0+RJ45/USB_1.D-")
		(layer "F.Cu")
		(name "$teardrop_padvia$")
		(hatch none 0.1)
		(priority 31487)
		(attr
			(teardrop
				(type padvia)
			)
		)
		(connect_pads yes
			(clearance 0)
		)
		(min_thickness 0.0254)
		(filled_areas_thickness no)
		(fill yes
			(thermal_gap 0.5)
			(thermal_bridge_width 0.5)
			(island_removal_mode 1)
			(island_area_min 10)
		)
		(polygon
			(pts
				(xy 134.495494 116.504022) (xy 134.530391 116.475828) (xy 134.563324 116.461532) (xy 134.625816 116.462371)
				(xy 134.672097 116.476363) (xy 134.72407 116.49205) (xy 134.782492 116.498719) (xy 134.778749 116.277335)
				(xy 134.613204 116.130795) (xy 134.483917 116.259885) (xy 134.364679 116.373207)
			)
		)
	)
	(zone
		(net 1)
		(net_name "GND")
		(layer "F.Cu")
		(name "$teardrop_padvia$")
		(hatch none 0.1)
		(priority 30590)
		(attr
			(teardrop
				(type padvia)
			)
		)
		(connect_pads yes
			(clearance 0)
		)
		(min_thickness 0.0254)
		(filled_areas_thickness no)
		(fill yes
			(thermal_gap 0.5)
			(thermal_bridge_width 0.5)
			(island_removal_mode 1)
			(island_area_min 10)
		)
		(polygon
			(pts
				(xy 217.125 164.07) (xy 217.121667 164.055514) (xy 217.11881 164.02539) (xy 217.130964 164.014349)
				(xy 217.16 164.01) (xy 217.025 163.134) (xy 216.89 164.01) (xy 216.919334 164.014475) (xy 216.931358 164.025801)
				(xy 216.928333 164.055514) (xy 216.925 164.07)
			)
		)
	)
	(zone
		(net 634)
		(net_name "Net-(U41-SDA)")
		(layer "F.Cu")
		(name "$teardrop_padvia$")
		(hatch none 0.1)
		(priority 32008)
		(attr
			(teardrop
				(type padvia)
			)
		)
		(connect_pads yes
			(clearance 0)
		)
		(min_thickness 0.0254)
		(filled_areas_thickness no)
		(fill yes
			(thermal_gap 0.5)
			(thermal_bridge_width 0.5)
			(island_removal_mode 1)
			(island_area_min 10)
		)
		(polygon
			(pts
				(xy 131.3355 83.1595) (xy 131.335596 83.165822) (xy 131.330011 83.205325) (xy 131.315078 83.223547)
				(xy 131.2855 83.236495) (xy 131.398 83.623) (xy 131.5105 83.236495) (xy 131.483507 83.225379) (xy 131.468405 83.209852)
				(xy 131.460404 83.165822) (xy 131.4605 83.1595)
			)
		)
	)
	(zone
		(net 551)
		(net_name "Net-(R16-Pad2)")
		(layer "F.Cu")
		(name "$teardrop_padvia$")
		(hatch none 0.1)
		(priority 30332)
		(attr
			(teardrop
				(type padvia)
			)
		)
		(connect_pads yes
			(clearance 0)
		)
		(min_thickness 0.0254)
		(filled_areas_thickness no)
		(fill yes
			(thermal_gap 0.5)
			(thermal_bridge_width 0.5)
			(island_removal_mode 1)
			(island_area_min 10)
		)
		(polygon
			(pts
				(xy 135.845461 109.635961) (xy 135.89417 109.595415) (xy 135.957976 109.560465) (xy 136.016861 109.541669)
				(xy 136.084441 109.53303) (xy 136.175474 109.54) (xy 136.120707 109.219293) (xy 135.825 109.139526)
				(xy 135.819956 109.272711) (xy 135.781148 109.38805) (xy 135.714323 109.483873) (xy 135.704039 109.494539)
			)
		)
	)
	(zone
		(net 602)
		(net_name "Net-(U37-~{OE0})")
		(layer "F.Cu")
		(name "$teardrop_padvia$")
		(hatch none 0.1)
		(priority 31012)
		(attr
			(teardrop
				(type padvia)
			)
		)
		(connect_pads yes
			(clearance 0)
		)
		(min_thickness 0.0254)
		(filled_areas_thickness no)
		(fill yes
			(thermal_gap 0.5)
			(thermal_bridge_width 0.5)
			(island_removal_mode 1)
			(island_area_min 10)
		)
		(polygon
			(pts
				(xy 211.6975 126.652) (xy 211.677531 126.714866) (xy 211.651079 126.746844) (xy 211.613668 126.775358)
				(xy 211.566473 126.797882) (xy 211.508833 126.813093) (xy 211.508202 126.813202) (xy 211.76 127.091)
				(xy 212.011798 126.813202) (xy 211.956365 126.798905) (xy 211.91048 126.777825) (xy 211.872799 126.75046)
				(xy 211.845566 126.719552) (xy 211.828528 126.686265) (xy 211.822511 126.653434) (xy 211.8225 126.652)
			)
		)
	)
	(zone
		(net 2)
		(net_name "+3V3")
		(layer "F.Cu")
		(name "$teardrop_padvia$")
		(hatch none 0.1)
		(priority 30391)
		(attr
			(teardrop
				(type padvia)
			)
		)
		(connect_pads yes
			(clearance 0)
		)
		(min_thickness 0.0254)
		(filled_areas_thickness no)
		(fill yes
			(thermal_gap 0.5)
			(thermal_bridge_width 0.5)
			(island_removal_mode 1)
			(island_area_min 10)
		)
		(polygon
			(pts
				(xy 194.155421 132.618162) (xy 194.201252 132.635253) (xy 194.238212 132.645664) (xy 194.267151 132.662557)
				(xy 194.275966 132.691419) (xy 194.25255 132.737737) (xy 194.624233 132.734835) (xy 194.628618 132.362857)
				(xy 194.594776 132.382734) (xy 194.569924 132.385751) (xy 194.543521 132.363523) (xy 194.526167 132.310771)
				(xy 194.508974 132.264609)
			)
		)
	)
	(zone
		(net 286)
		(net_name "/2xUSB3.0+RJ45/GbE.MDI3+")
		(layer "F.Cu")
		(name "$teardrop_padvia$")
		(hatch none 0.1)
		(priority 31645)
		(attr
			(teardrop
				(type padvia)
			)
		)
		(connect_pads yes
			(clearance 0)
		)
		(min_thickness 0.0254)
		(filled_areas_thickness no)
		(fill yes
			(thermal_gap 0.5)
			(thermal_bridge_width 0.5)
			(island_removal_mode 1)
			(island_area_min 10)
		)
		(polygon
			(pts
				(xy 172.15 160.857916) (xy 172.145244 160.897838) (xy 172.13195 160.926255) (xy 172.087871 160.958671)
				(xy 172.042738 160.973949) (xy 171.996459 160.989244) (xy 171.949997 161.012919) (xy 172.075 161.201)
				(xy 172.295677 161.201757) (xy 172.297797 161.063281) (xy 172.3 160.857916)
			)
		)
	)
	(zone
		(net 429)
		(net_name "/2xSFP+/MDIO1.MDC")
		(layer "F.Cu")
		(name "$teardrop_padvia$")
		(hatch none 0.1)
		(priority 30387)
		(attr
			(teardrop
				(type padvia)
			)
		)
		(connect_pads yes
			(clearance 0)
		)
		(min_thickness 0.0254)
		(filled_areas_thickness no)
		(fill yes
			(thermal_gap 0.5)
			(thermal_bridge_width 0.5)
			(island_removal_mode 1)
			(island_area_min 10)
		)
		(polygon
			(pts
				(xy 125.6375 146.297) (xy 125.632026 146.32731) (xy 125.61371 146.357642) (xy 125.586883 146.379543)
				(xy 125.547759 146.395912) (xy 125.517639 146.402046) (xy 125.682 147.113) (xy 125.852711 146.406289)
				(xy 125.818406 146.395022) (xy 125.793835 146.377863) (xy 125.766677 146.330288) (xy 125.7625 146.297)
			)
		)
	)
	(zone
		(net 328)
		(net_name "/Com Express 7 Interfaces/PCIe_{B2Ax4}.TX2+")
		(layer "F.Cu")
		(name "$teardrop_padvia$")
		(hatch none 0.1)
		(priority 31598)
		(attr
			(teardrop
				(type padvia)
			)
		)
		(connect_pads yes
			(clearance 0)
		)
		(min_thickness 0.0254)
		(filled_areas_thickness no)
		(fill yes
			(thermal_gap 0.5)
			(thermal_bridge_width 0.5)
			(island_removal_mode 1)
			(island_area_min 10)
		)
		(polygon
			(pts
				(xy 214.116211 167.424123) (xy 214.152728 167.380889) (xy 214.174756 167.340129) (xy 214.187384 167.262836)
				(xy 214.179773 167.195028) (xy 214.171481 167.124235) (xy 214.176995 167.044332) (xy 213.957207 166.999293)
				(xy 213.831497 167.187081) (xy 213.913542 167.216935) (xy 213.9778 167.239792) (xy 213.987777 167.256866)
				(xy 213.973376 167.281288)
			)
		)
	)
	(zone
		(net 356)
		(net_name "/Com Express 7 MGMT/~{CW_PWRBTN}")
		(layer "F.Cu")
		(name "$teardrop_padvia$")
		(hatch none 0.1)
		(priority 31891)
		(attr
			(teardrop
				(type padvia)
			)
		)
		(connect_pads yes
			(clearance 0)
		)
		(min_thickness 0.0254)
		(filled_areas_thickness no)
		(fill yes
			(thermal_gap 0.5)
			(thermal_bridge_width 0.5)
			(island_removal_mode 1)
			(island_area_min 10)
		)
		(polygon
			(pts
				(xy 222.227515 143.039127) (xy 222.181819 142.986618) (xy 222.155231 142.940623) (xy 222.134847 142.854175)
				(xy 222.133011 142.83884) (xy 222.120677 142.756105) (xy 221.899293 142.799293) (xy 221.856105 143.020677)
				(xy 221.93884 143.033011) (xy 222.036119 143.053349) (xy 222.084159 143.080057) (xy 222.139127 143.127515)
			)
		)
	)
	(zone
		(net 207)
		(net_name "/Backplane/UART.TX")
		(layer "F.Cu")
		(name "$teardrop_padvia$")
		(hatch none 0.1)
		(priority 32126)
		(attr
			(teardrop
				(type padvia)
			)
		)
		(connect_pads yes
			(clearance 0)
		)
		(min_thickness 0.0254)
		(filled_areas_thickness no)
		(fill yes
			(thermal_gap 0.5)
			(thermal_bridge_width 0.5)
			(island_removal_mode 1)
			(island_area_min 10)
		)
		(polygon
			(pts
				(xy 314.086294 168.062093) (xy 314.09675 168.064149) (xy 314.102269 168.089964) (xy 314.106306 168.114694)
				(xy 314.363707 168.007293) (xy 314.104997 167.903264) (xy 314.081748 167.942237) (xy 314.029762 167.966386)
				(xy 314.003205 167.972582) (xy 313.997907 167.973706)
			)
		)
	)
	(zone
		(net 385)
		(net_name "/Com Express 7 Interfaces/SDIO.CMD")
		(layer "F.Cu")
		(name "$teardrop_padvia$")
		(hatch none 0.1)
		(priority 30047)
		(attr
			(teardrop
				(type padvia)
			)
		)
		(connect_pads yes
			(clearance 0)
		)
		(min_thickness 0.0254)
		(filled_areas_thickness no)
		(fill yes
			(thermal_gap 0.5)
			(thermal_bridge_width 0.5)
			(island_removal_mode 1)
			(island_area_min 10)
		)
		(polygon
			(pts
				(xy 110.595 136.719) (xy 110.563366 136.713903) (xy 110.532489 136.698222) (xy 110.505162 136.672417)
				(xy 110.482138 136.635622) (xy 110.465474 136.588468) (xy 110.456279 136.529788) (xy 110.455 136.495)
				(xy 109.504 136.81) (xy 110.455 137.125) (xy 110.459723 137.060141) (xy 110.472784 137.007088) (xy 110.492459 136.965444)
				(xy 110.517125 136.934553) (xy 110.545573 136.913687) (xy 110.575742 136.902878) (xy 110.595 136.901)
			)
		)
	)
	(zone
		(net 747)
		(net_name "Net-(U45C-PRBS_{PASS})")
		(layer "F.Cu")
		(name "$teardrop_padvia$")
		(hatch none 0.1)
		(priority 31714)
		(attr
			(teardrop
				(type padvia)
			)
		)
		(connect_pads yes
			(clearance 0)
		)
		(min_thickness 0.0254)
		(filled_areas_thickness no)
		(fill yes
			(thermal_gap 0.5)
			(thermal_bridge_width 0.5)
			(island_removal_mode 1)
			(island_area_min 10)
		)
		(polygon
			(pts
				(xy 130.9775 129.739323) (xy 130.972682 129.808763) (xy 130.95896 129.860087) (xy 130.912245 129.935628)
				(xy 130.902702 129.947768) (xy 130.852919 130.014997) (xy 131.04 130.141) (xy 131.227081 130.014997)
				(xy 131.177299 129.947769) (xy 131.122894 129.864603) (xy 131.10781 129.811748) (xy 131.1025 129.739323)
			)
		)
	)
	(zone
		(net 940)
		(net_name "Net-(D8-C)")
		(layer "F.Cu")
		(name "$teardrop_padvia$")
		(hatch none 0.1)
		(priority 31118)
		(attr
			(teardrop
				(type padvia)
			)
		)
		(connect_pads yes
			(clearance 0)
		)
		(min_thickness 0.0254)
		(filled_areas_thickness no)
		(fill yes
			(thermal_gap 0.5)
			(thermal_bridge_width 0.5)
			(island_removal_mode 1)
			(island_area_min 10)
		)
		(polygon
			(pts
				(xy 154.406 166.4225) (xy 154.465412 166.442273) (xy 154.521497 166.505547) (xy 154.543199 166.554172)
				(xy 154.557873 166.613531) (xy 154.559653 166.6255) (xy 154.82 166.36) (xy 154.559653 166.0945)
				(xy 154.546804 166.154638) (xy 154.52687 166.204522) (xy 154.500945 166.244641) (xy 154.471125 166.273654)
				(xy 154.439707 166.291146) (xy 154.407896 166.297479) (xy 154.406 166.2975)
			)
		)
	)
	(zone
		(net 313)
		(net_name "/2xUSB3.0+RJ45/USB_1.D+")
		(layer "F.Cu")
		(name "$teardrop_padvia$")
		(hatch none 0.1)
		(priority 31491)
		(attr
			(teardrop
				(type padvia)
			)
		)
		(connect_pads yes
			(clearance 0)
		)
		(min_thickness 0.0254)
		(filled_areas_thickness no)
		(fill yes
			(thermal_gap 0.5)
			(thermal_bridge_width 0.5)
			(island_removal_mode 1)
			(island_area_min 10)
		)
		(polygon
			(pts
				(xy 147.954022 115.504506) (xy 147.925828 115.469609) (xy 147.911532 115.436676) (xy 147.912371 115.374183)
				(xy 147.926363 115.327902) (xy 147.94205 115.275929) (xy 147.948719 115.217508) (xy 147.727335 115.221251)
				(xy 147.580795 115.386795) (xy 147.709886 115.516083) (xy 147.823207 115.635321)
			)
		)
	)
	(zone
		(net 1)
		(net_name "GND")
		(layer "F.Cu")
		(name "$teardrop_padvia$")
		(hatch none 0.1)
		(priority 31559)
		(attr
			(teardrop
				(type padvia)
			)
		)
		(connect_pads yes
			(clearance 0)
		)
		(min_thickness 0.0254)
		(filled_areas_thickness no)
		(fill yes
			(thermal_gap 0.5)
			(thermal_bridge_width 0.5)
			(island_removal_mode 1)
			(island_area_min 10)
		)
		(polygon
			(pts
				(xy 307.668 80.993) (xy 307.659751 80.970923) (xy 307.649017 80.932428) (xy 307.661982 80.918475)
				(xy 307.698 80.913) (xy 307.518 80.537) (xy 307.338 80.913) (xy 307.371735 80.91754) (xy 307.385928 80.929323)
				(xy 307.382446 80.957817) (xy 307.376249 80.970923) (xy 307.368 80.993)
			)
		)
	)
	(zone
		(net 48)
		(net_name "Net-(U34-ONT)")
		(layer "F.Cu")
		(name "$teardrop_padvia$")
		(hatch none 0.1)
		(priority 31003)
		(attr
			(teardrop
				(type padvia)
			)
		)
		(connect_pads yes
			(clearance 0)
		)
		(min_thickness 0.0254)
		(filled_areas_thickness no)
		(fill yes
			(thermal_gap 0.5)
			(thermal_bridge_width 0.5)
			(island_removal_mode 1)
			(island_area_min 10)
		)
		(polygon
			(pts
				(xy 242.188 128.7275) (xy 242.125134 128.707531) (xy 242.093156 128.681079) (xy 242.064642 128.643668)
				(xy 242.042118 128.596473) (xy 242.026907 128.538833) (xy 242.026798 128.538202) (xy 241.749 128.79)
				(xy 242.026798 129.041798) (xy 242.041095 128.986365) (xy 242.062175 128.94048) (xy 242.08954 128.902799)
				(xy 242.120448 128.875566) (xy 242.153735 128.858528) (xy 242.186566 128.852511) (xy 242.188 128.8525)
			)
		)
	)
	(zone
		(net 583)
		(net_name "Net-(U22-EN)")
		(layer "F.Cu")
		(name "$teardrop_padvia$")
		(hatch none 0.1)
		(priority 30481)
		(attr
			(teardrop
				(type padvia)
			)
		)
		(connect_pads yes
			(clearance 0)
		)
		(min_thickness 0.0254)
		(filled_areas_thickness no)
		(fill yes
			(thermal_gap 0.5)
			(thermal_bridge_width 0.5)
			(island_removal_mode 1)
			(island_area_min 10)
		)
		(polygon
			(pts
				(xy 312.376555 135.590556) (xy 312.293212 135.645935) (xy 312.163223 135.682154) (xy 312.082633 135.688517)
				(xy 311.995025 135.685) (xy 312.074792 135.980707) (xy 312.395499 136.035474) (xy 312.386481 135.884316)
				(xy 312.396325 135.816785) (xy 312.41459 135.757974) (xy 312.464943 135.678944)
			)
		)
	)
	(zone
		(net 2)
		(net_name "+3V3")
		(layer "F.Cu")
		(name "$teardrop_padvia$")
		(hatch none 0.1)
		(priority 31248)
		(attr
			(teardrop
				(type padvia)
			)
		)
		(connect_pads yes
			(clearance 0)
		)
		(min_thickness 0.0254)
		(filled_areas_thickness no)
		(fill yes
			(thermal_gap 0.5)
			(thermal_bridge_width 0.5)
			(island_removal_mode 1)
			(island_area_min 10)
		)
		(polygon
			(pts
				(xy 218.359323 127.424) (xy 218.437235 127.428713) (xy 218.49602 127.4417) (xy 218.587051 127.483802)
				(xy 218.672222 127.5265) (xy 218.761 127.324) (xy 218.672222 127.1215) (xy 218.58705 127.164199)
				(xy 218.494217 127.206867) (xy 218.436078 127.219444) (xy 218.359323 127.224)
			)
		)
	)
	(zone
		(net 941)
		(net_name "/2xUSB3.0+RJ45/EN_1")
		(layer "F.Cu")
		(name "$teardrop_padvia$")
		(hatch none 0.1)
		(priority 31047)
		(attr
			(teardrop
				(type padvia)
			)
		)
		(connect_pads yes
			(clearance 0)
		)
		(min_thickness 0.0254)
		(filled_areas_thickness no)
		(fill yes
			(thermal_gap 0.5)
			(thermal_bridge_width 0.5)
			(island_removal_mode 1)
			(island_area_min 10)
		)
		(polygon
			(pts
				(xy 122.942999 84.9975) (xy 122.883587 84.977727) (xy 122.827502 84.914453) (xy 122.8058 84.865828)
				(xy 122.791126 84.806468) (xy 122.789346 84.7945) (xy 122.528999 85.06) (xy 122.789346 85.3255)
				(xy 122.802196 85.265361) (xy 122.82213 85.215477) (xy 122.848055 85.175358) (xy 122.877875 85.146345)
				(xy 122.909293 85.128854) (xy 122.941104 85.122521) (xy 122.942999 85.1225)
			)
		)
	)
	(zone
		(net 74)
		(net_name "+1V0")
		(layer "F.Cu")
		(hatch edge 0.5)
		(priority 24)
		(connect_pads yes
			(clearance 0.15)
		)
		(min_thickness 0.25)
		(filled_areas_thickness no)
		(fill yes
			(thermal_gap 0.2)
			(thermal_bridge_width 0.5)
			(smoothing fillet)
			(radius 0.2)
		)
		(polygon
			(pts
				(xy 303.738 118.18) (xy 303.738 114.709) (xy 299.688 114.709) (xy 299.688 118.18)
			)
		)
	)
	(zone
		(net 430)
		(net_name "/2xSFP+/MDIO0.MDC")
		(layer "F.Cu")
		(name "$teardrop_padvia$")
		(hatch none 0.1)
		(priority 30679)
		(attr
			(teardrop
				(type padvia)
			)
		)
		(connect_pads yes
			(clearance 0)
		)
		(min_thickness 0.0254)
		(filled_areas_thickness no)
		(fill yes
			(thermal_gap 0.5)
			(thermal_bridge_width 0.5)
			(island_removal_mode 1)
			(island_area_min 10)
		)
		(polygon
			(pts
				(xy 198.4625 155.75) (xy 198.451563 155.788823) (xy 198.429805 155.803933) (xy 198.39 155.81) (xy 198.525 156.686)
				(xy 198.66 155.81) (xy 198.624719 155.805483) (xy 198.603203 155.793862) (xy 198.588005 155.761039)
				(xy 198.5875 155.75)
			)
		)
	)
	(zone
		(net 711)
		(net_name "Net-(U37-SADR_{TRI})")
		(layer "F.Cu")
		(name "$teardrop_padvia$")
		(hatch none 0.1)
		(priority 31622)
		(attr
			(teardrop
				(type padvia)
			)
		)
		(connect_pads yes
			(clearance 0)
		)
		(min_thickness 0.0254)
		(filled_areas_thickness no)
		(fill yes
			(thermal_gap 0.5)
			(thermal_bridge_width 0.5)
			(island_removal_mode 1)
			(island_area_min 10)
		)
		(polygon
			(pts
				(xy 217.5415 125.977023) (xy 217.546246 125.929099) (xy 217.559468 125.892978) (xy 217.604259 125.845265)
				(xy 217.647853 125.819233) (xy 217.700839 125.787229) (xy 217.751875 125.740208) (xy 217.58 125.599)
				(xy 217.359323 125.643895) (xy 217.386369 125.754725) (xy 217.407862 125.846488) (xy 217.4165 125.977023)
			)
		)
	)
	(zone
		(net 244)
		(net_name "/Com Express 7 Interfaces/PCIe_{B2Bx4}.RX2+")
		(layer "F.Cu")
		(name "$teardrop_padvia$")
		(hatch none 0.1)
		(priority 31410)
		(attr
			(teardrop
				(type padvia)
			)
		)
		(connect_pads yes
			(clearance 0)
		)
		(min_thickness 0.0254)
		(filled_areas_thickness no)
		(fill yes
			(thermal_gap 0.5)
			(thermal_bridge_width 0.5)
			(island_removal_mode 1)
			(island_area_min 10)
		)
		(polygon
			(pts
				(xy 173.232504 97.0165) (xy 173.394035 97.011105) (xy 173.478445 97.007554) (xy 173.58014 97.012177)
				(xy 173.601 96.7915) (xy 173.451147 96.628268) (xy 173.397007 96.696935) (xy 173.387115 96.713393)
				(xy 173.362615 96.752065) (xy 173.333109 96.784279) (xy 173.291953 96.806327) (xy 173.232504 96.8145)
			)
		)
	)
	(zone
		(net 567)
		(net_name "/2xSFP+/~{LED1_2}")
		(layer "F.Cu")
		(name "$teardrop_padvia$")
		(hatch none 0.1)
		(priority 31051)
		(attr
			(teardrop
				(type padvia)
			)
		)
		(connect_pads yes
			(clearance 0)
		)
		(min_thickness 0.0254)
		(filled_areas_thickness no)
		(fill yes
			(thermal_gap 0.5)
			(thermal_bridge_width 0.5)
			(island_removal_mode 1)
			(island_area_min 10)
		)
		(polygon
			(pts
				(xy 156.192 163.0475) (xy 156.132588 163.027727) (xy 156.076503 162.964453) (xy 156.054801 162.915828)
				(xy 156.040127 162.856468) (xy 156.038347 162.8445) (xy 155.778 163.11) (xy 156.038347 163.3755)
				(xy 156.051197 163.315361) (xy 156.071131 163.265477) (xy 156.097056 163.225358) (xy 156.126876 163.196345)
				(xy 156.158294 163.178854) (xy 156.190105 163.172521) (xy 156.192 163.1725)
			)
		)
	)
	(zone
		(net 2)
		(net_name "+3V3")
		(layer "F.Cu")
		(name "$teardrop_padvia$")
		(hatch none 0.1)
		(priority 30292)
		(attr
			(teardrop
				(type padvia)
			)
		)
		(connect_pads yes
			(clearance 0)
		)
		(min_thickness 0.0254)
		(filled_areas_thickness no)
		(fill yes
			(thermal_gap 0.5)
			(thermal_bridge_width 0.5)
			(island_removal_mode 1)
			(island_area_min 10)
		)
		(polygon
			(pts
				(xy 237.936707 78.323) (xy 237.926592 78.323153) (xy 237.895876 78.32254) (xy 237.863387 78.314218)
				(xy 237.834233 78.290325) (xy 237.813516 78.243) (xy 237.120707 78.423) (xy 237.813516 78.603) (xy 237.826875 78.567099)
				(xy 237.845106 78.543801) (xy 237.890432 78.524101) (xy 237.926592 78.522847) (xy 237.936707 78.523)
			)
		)
	)
	(zone
		(net 1)
		(net_name "GND")
		(layer "F.Cu")
		(name "$teardrop_padvia$")
		(hatch none 0.1)
		(priority 30557)
		(attr
			(teardrop
				(type padvia)
			)
		)
		(connect_pads yes
			(clearance 0)
		)
		(min_thickness 0.0254)
		(filled_areas_thickness no)
		(fill yes
			(thermal_gap 0.5)
			(thermal_bridge_width 0.5)
			(island_removal_mode 1)
			(island_area_min 10)
		)
		(polygon
			(pts
				(xy 201.125 169.62) (xy 201.121667 169.605514) (xy 201.11881 169.57539) (xy 201.130964 169.564349)
				(xy 201.16 169.56) (xy 201.025 168.684) (xy 200.89 169.56) (xy 200.919334 169.564475) (xy 200.931358 169.575801)
				(xy 200.928333 169.605514) (xy 200.925 169.62)
			)
		)
	)
	(zone
		(net 73)
		(net_name "+3V3_AON")
		(layer "F.Cu")
		(name "$teardrop_padvia$")
		(hatch none 0.1)
		(priority 30836)
		(attr
			(teardrop
				(type padvia)
			)
		)
		(connect_pads yes
			(clearance 0)
		)
		(min_thickness 0.0254)
		(filled_areas_thickness no)
		(fill yes
			(thermal_gap 0.5)
			(thermal_bridge_width 0.5)
			(island_removal_mode 1)
			(island_area_min 10)
		)
		(polygon
			(pts
				(xy 237.137999 153.862) (xy 237.081456 153.854426) (xy 237.022961 153.821409) (xy 236.999107 153.791031)
				(xy 236.98156 153.748854) (xy 236.976798 153.728202) (xy 236.699001 153.98) (xy 236.976798 154.231798)
				(xy 236.990204 154.17777) (xy 237.009943 154.135854) (xy 237.06284 154.082528) (xy 237.128086 154.062331)
				(xy 237.138 154.061999)
			)
		)
	)
	(zone
		(net 1)
		(net_name "GND")
		(layer "F.Cu")
		(hatch edge 0.5)
		(priority 19)
		(connect_pads yes
			(clearance 0.15)
		)
		(min_thickness 0.25)
		(filled_areas_thickness no)
		(fill yes
			(thermal_gap 0.2)
			(thermal_bridge_width 0.5)
			(smoothing fillet)
			(radius 0.2)
		)
		(polygon
			(pts
				(xy 297.15 98.31) (xy 296.35 98.31) (xy 296.35 101.51) (xy 299.45 101.51) (xy 299.45 100.66) (xy 297.2 100.66)
				(xy 297.15 100.61)
			)
		)
	)
	(zone
		(net 739)
		(net_name "Net-(U43B-LS_OK_{OUT_B})")
		(layer "F.Cu")
		(name "$teardrop_padvia$")
		(hatch none 0.1)
		(priority 30125)
		(attr
			(teardrop
				(type padvia)
			)
		)
		(connect_pads yes
			(clearance 0)
		)
		(min_thickness 0.0254)
		(filled_areas_thickness no)
		(fill yes
			(thermal_gap 0.5)
			(thermal_bridge_width 0.5)
			(island_removal_mode 1)
			(island_area_min 10)
		)
		(polygon
			(pts
				(xy 147.3125 130.227794) (xy 147.317315 130.145733) (xy 147.331019 130.080388) (xy 147.377576 129.98712)
				(xy 147.445787 129.908657) (xy 147.501942 129.847158) (xy 147.561801 129.768339) (xy 147.25 129.559)
				(xy 146.938199 129.768339) (xy 147.035219 129.888517) (xy 147.054214 129.908658) (xy 147.107366 129.967541)
				(xy 147.149591 130.031624) (xy 147.177449 130.114008) (xy 147.1875 130.227794)
			)
		)
	)
	(zone
		(net 471)
		(net_name "Net-(J12K-10G_SDP3)")
		(layer "F.Cu")
		(name "$teardrop_padvia$")
		(hatch none 0.1)
		(priority 30704)
		(attr
			(teardrop
				(type padvia)
			)
		)
		(connect_pads yes
			(clearance 0)
		)
		(min_thickness 0.0254)
		(filled_areas_thickness no)
		(fill yes
			(thermal_gap 0.5)
			(thermal_bridge_width 0.5)
			(island_removal_mode 1)
			(island_area_min 10)
		)
		(polygon
			(pts
				(xy 183.9625 150.2) (xy 183.951563 150.238823) (xy 183.929805 150.253933) (xy 183.89 150.26) (xy 184.025 151.136)
				(xy 184.16 150.26) (xy 184.124719 150.255483) (xy 184.103203 150.243862) (xy 184.088005 150.211039)
				(xy 184.0875 150.2)
			)
		)
	)
	(zone
		(net 2)
		(net_name "+3V3")
		(layer "F.Cu")
		(name "$teardrop_padvia$")
		(hatch none 0.1)
		(priority 31008)
		(attr
			(teardrop
				(type padvia)
			)
		)
		(connect_pads yes
			(clearance 0)
		)
		(min_thickness 0.0254)
		(filled_areas_thickness no)
		(fill yes
			(thermal_gap 0.5)
			(thermal_bridge_width 0.5)
			(island_removal_mode 1)
			(island_area_min 10)
		)
		(polygon
			(pts
				(xy 178.788 103.3275) (xy 178.725134 103.307531) (xy 178.693156 103.281079) (xy 178.664642 103.243668)
				(xy 178.642118 103.196473) (xy 178.626907 103.138833) (xy 178.626798 103.138202) (xy 178.349 103.39)
				(xy 178.626798 103.641798) (xy 178.641095 103.586365) (xy 178.662175 103.54048) (xy 178.68954 103.502799)
				(xy 178.720448 103.475566) (xy 178.753735 103.458528) (xy 178.786566 103.452511) (xy 178.788 103.4525)
			)
		)
	)
	(zone
		(net 1)
		(net_name "GND")
		(layer "F.Cu")
		(name "$teardrop_padvia$")
		(hatch none 0.1)
		(priority 30589)
		(attr
			(teardrop
				(type padvia)
			)
		)
		(connect_pads yes
			(clearance 0)
		)
		(min_thickness 0.0254)
		(filled_areas_thickness no)
		(fill yes
			(thermal_gap 0.5)
			(thermal_bridge_width 0.5)
			(island_removal_mode 1)
			(island_area_min 10)
		)
		(polygon
			(pts
				(xy 182.625 157.62) (xy 182.621667 157.605514) (xy 182.61881 157.57539) (xy 182.630964 157.564349)
				(xy 182.66 157.56) (xy 182.525 156.684) (xy 182.39 157.56) (xy 182.419334 157.564475) (xy 182.431358 157.575801)
				(xy 182.428333 157.605514) (xy 182.425 157.62)
			)
		)
	)
	(zone
		(net 358)
		(net_name "/Com Express 7 MGMT/SMBus.SDA")
		(layer "F.Cu")
		(name "$teardrop_padvia$")
		(hatch none 0.1)
		(priority 31827)
		(attr
			(teardrop
				(type padvia)
			)
		)
		(connect_pads yes
			(clearance 0)
		)
		(min_thickness 0.0254)
		(filled_areas_thickness no)
		(fill yes
			(thermal_gap 0.5)
			(thermal_bridge_width 0.5)
			(island_removal_mode 1)
			(island_area_min 10)
		)
		(polygon
			(pts
				(xy 121.025677 152.1625) (xy 120.956236 152.157682) (xy 120.904913 152.14396) (xy 120.829371 152.097246)
				(xy 120.817231 152.087701) (xy 120.750003 152.037919) (xy 120.624 152.225) (xy 120.750003 152.412081)
				(xy 120.817229 152.362299) (xy 120.900396 152.307894) (xy 120.953251 152.29281) (xy 121.025677 152.2875)
			)
		)
	)
	(zone
		(net 2)
		(net_name "+3V3")
		(layer "F.Cu")
		(name "$teardrop_padvia$")
		(hatch none 0.1)
		(priority 30747)
		(attr
			(teardrop
				(type padvia)
			)
		)
		(connect_pads yes
			(clearance 0)
		)
		(min_thickness 0.0254)
		(filled_areas_thickness no)
		(fill yes
			(thermal_gap 0.5)
			(thermal_bridge_width 0.5)
			(island_removal_mode 1)
			(island_area_min 10)
		)
		(polygon
			(pts
				(xy 310.324999 83.693) (xy 310.324662 83.67791) (xy 310.325239 83.637674) (xy 310.337053 83.59613)
				(xy 310.371632 83.560835) (xy 310.440499 83.539347) (xy 310.175 83.279) (xy 309.909499 83.539346)
				(xy 309.955937 83.55029) (xy 309.988134 83.56739) (xy 310.019577 83.611855) (xy 310.025336 83.67791)
				(xy 310.024999 83.693)
			)
		)
	)
	(zone
		(net 303)
		(net_name "/Com Express 7 MGMT/~{SUS_S5}")
		(layer "F.Cu")
		(name "$teardrop_padvia$")
		(hatch none 0.1)
		(priority 31716)
		(attr
			(teardrop
				(type padvia)
			)
		)
		(connect_pads yes
			(clearance 0)
		)
		(min_thickness 0.0254)
		(filled_areas_thickness no)
		(fill yes
			(thermal_gap 0.5)
			(thermal_bridge_width 0.5)
			(island_removal_mode 1)
			(island_area_min 10)
		)
		(polygon
			(pts
				(xy 221.9375 145.499323) (xy 221.932682 145.568763) (xy 221.91896 145.620087) (xy 221.872245 145.695628)
				(xy 221.862702 145.707768) (xy 221.812919 145.774997) (xy 222 145.901) (xy 222.187081 145.774997)
				(xy 222.137299 145.707769) (xy 222.082894 145.624603) (xy 222.06781 145.571748) (xy 222.0625 145.499323)
			)
		)
	)
	(zone
		(net 640)
		(net_name "Net-(U41-IO0_1)")
		(layer "F.Cu")
		(name "$teardrop_padvia$")
		(hatch none 0.1)
		(priority 31083)
		(attr
			(teardrop
				(type padvia)
			)
		)
		(connect_pads yes
			(clearance 0)
		)
		(min_thickness 0.0254)
		(filled_areas_thickness no)
		(fill yes
			(thermal_gap 0.5)
			(thermal_bridge_width 0.5)
			(island_removal_mode 1)
			(island_area_min 10)
		)
		(polygon
			(pts
				(xy 127.318 83.997501) (xy 127.258588 83.977728) (xy 127.202503 83.914454) (xy 127.180801 83.865829)
				(xy 127.166127 83.806469) (xy 127.164347 83.794501) (xy 126.904 84.060001) (xy 127.164347 84.325501)
				(xy 127.177197 84.265362) (xy 127.197131 84.215478) (xy 127.223056 84.175359) (xy 127.252876 84.146346)
				(xy 127.284294 84.128855) (xy 127.316105 84.122522) (xy 127.318 84.122501)
			)
		)
	)
	(zone
		(net 1)
		(net_name "GND")
		(layer "F.Cu")
		(name "$teardrop_padvia$")
		(hatch none 0.1)
		(priority 30861)
		(attr
			(teardrop
				(type padvia)
			)
		)
		(connect_pads yes
			(clearance 0)
		)
		(min_thickness 0.0254)
		(filled_areas_thickness no)
		(fill yes
			(thermal_gap 0.5)
			(thermal_bridge_width 0.5)
			(island_removal_mode 1)
			(island_area_min 10)
		)
		(polygon
			(pts
				(xy 231.625791 77.622) (xy 231.579776 77.617303) (xy 231.543881 77.604427) (xy 231.490529 77.559093)
				(xy 231.467806 77.52927) (xy 231.425922 77.478131) (xy 231.269707 77.635) (xy 231.279341 77.855677)
				(xy 231.374917 77.868109) (xy 231.421924 77.883602) (xy 231.508017 77.90961) (xy 231.625791 77.922)
			)
		)
	)
	(zone
		(net 1)
		(net_name "GND")
		(layer "F.Cu")
		(name "$teardrop_padvia$")
		(hatch none 0.1)
		(priority 31599)
		(attr
			(teardrop
				(type padvia)
			)
		)
		(connect_pads yes
			(clearance 0)
		)
		(min_thickness 0.0254)
		(filled_areas_thickness no)
		(fill yes
			(thermal_gap 0.5)
			(thermal_bridge_width 0.5)
			(island_removal_mode 1)
			(island_area_min 10)
		)
		(polygon
			(pts
				(xy 225.4625 169.349323) (xy 225.457831 169.419201) (xy 225.445144 169.472579) (xy 225.400666 169.559579)
				(xy 225.342355 169.674641) (xy 225.55 169.751) (xy 225.737081 169.624997) (xy 225.66863 169.542342)
				(xy 225.610755 169.467857) (xy 225.593685 169.417955) (xy 225.5875 169.349323)
			)
		)
	)
	(zone
		(net 874)
		(net_name "/2xSFP+/SDA1")
		(layer "F.Cu")
		(name "$teardrop_padvia$")
		(hatch none 0.1)
		(priority 31135)
		(attr
			(teardrop
				(type padvia)
			)
		)
		(connect_pads yes
			(clearance 0)
		)
		(min_thickness 0.0254)
		(filled_areas_thickness no)
		(fill yes
			(thermal_gap 0.5)
			(thermal_bridge_width 0.5)
			(island_removal_mode 1)
			(island_area_min 10)
		)
		(polygon
			(pts
				(xy 177.507 144.0625) (xy 177.566412 144.082273) (xy 177.622497 144.145547) (xy 177.644199 144.194172)
				(xy 177.658873 144.253531) (xy 177.660653 144.2655) (xy 177.921 144) (xy 177.660653 143.7345) (xy 177.647804 143.794638)
				(xy 177.62787 143.844522) (xy 177.601945 143.884641) (xy 177.572125 143.913654) (xy 177.540707 143.931146)
				(xy 177.508896 143.937479) (xy 177.507 143.9375)
			)
		)
	)
	(zone
		(net 2)
		(net_name "+3V3")
		(layer "F.Cu")
		(name "$teardrop_padvia$")
		(hatch none 0.1)
		(priority 30934)
		(attr
			(teardrop
				(type padvia)
			)
		)
		(connect_pads yes
			(clearance 0)
		)
		(min_thickness 0.0254)
		(filled_areas_thickness no)
		(fill yes
			(thermal_gap 0.5)
			(thermal_bridge_width 0.5)
			(island_removal_mode 1)
			(island_area_min 10)
		)
		(polygon
			(pts
				(xy 220.1475 124.462) (xy 220.127531 124.524866) (xy 220.101079 124.556844) (xy 220.063668 124.585358)
				(xy 220.016473 124.607882) (xy 219.958833 124.623093) (xy 219.958202 124.623202) (xy 220.21 124.901)
				(xy 220.461798 124.623202) (xy 220.406365 124.608905) (xy 220.36048 124.587825) (xy 220.322799 124.56046)
				(xy 220.295566 124.529552) (xy 220.278528 124.496265) (xy 220.272511 124.463434) (xy 220.2725 124.462)
			)
		)
	)
	(zone
		(net 239)
		(net_name "/Com Express 7 Interfaces/PCIe_{B2Bx4}.RX3+")
		(layer "F.Cu")
		(name "$teardrop_padvia$")
		(hatch none 0.1)
		(priority 31416)
		(attr
			(teardrop
				(type padvia)
			)
		)
		(connect_pads yes
			(clearance 0)
		)
		(min_thickness 0.0254)
		(filled_areas_thickness no)
		(fill yes
			(thermal_gap 0.5)
			(thermal_bridge_width 0.5)
			(island_removal_mode 1)
			(island_area_min 10)
		)
		(polygon
			(pts
				(xy 173.232504 94.0165) (xy 173.394035 94.011105) (xy 173.478445 94.007554) (xy 173.58014 94.012177)
				(xy 173.601 93.7915) (xy 173.451147 93.628268) (xy 173.397007 93.696935) (xy 173.387115 93.713393)
				(xy 173.362615 93.752065) (xy 173.333109 93.784279) (xy 173.291953 93.806327) (xy 173.232504 93.8145)
			)
		)
	)
	(zone
		(net 706)
		(net_name "Net-(U24-GPIO0)")
		(layer "F.Cu")
		(name "$teardrop_padvia$")
		(hatch none 0.1)
		(priority 30811)
		(attr
			(teardrop
				(type padvia)
			)
		)
		(connect_pads yes
			(clearance 0)
		)
		(min_thickness 0.0254)
		(filled_areas_thickness no)
		(fill yes
			(thermal_gap 0.5)
			(thermal_bridge_width 0.5)
			(island_removal_mode 1)
			(island_area_min 10)
		)
		(polygon
			(pts
				(xy 260.624 86.937499) (xy 260.597391 86.932136) (xy 260.572117 86.914599) (xy 260.554478 86.888305)
				(xy 260.54305 86.850159) (xy 260.54 86.810999) (xy 259.979 87) (xy 260.54 87.188999) (xy 260.544627 87.141636)
				(xy 260.557018 87.106588) (xy 260.574877 87.08265) (xy 260.596015 87.068453) (xy 260.624 87.062499)
			)
		)
	)
	(zone
		(net 259)
		(net_name "/Com Express 7 Interfaces/PCIe_{B2Bx4}.TX1+")
		(layer "F.Cu")
		(name "$teardrop_padvia$")
		(hatch none 0.1)
		(priority 30246)
		(attr
			(teardrop
				(type padvia)
			)
		)
		(connect_pads yes
			(clearance 0)
		)
		(min_thickness 0.0254)
		(filled_areas_thickness no)
		(fill yes
			(thermal_gap 0.5)
			(thermal_bridge_width 0.5)
			(island_removal_mode 1)
			(island_area_min 10)
		)
		(polygon
			(pts
				(xy 193.4795 167.75) (xy 193.48258 167.764227) (xy 193.484749 167.794527) (xy 193.471877 167.805628)
				(xy 193.441705 167.81) (xy 193.525 168.686) (xy 193.675 168.437021) (xy 193.655644 168.195818) (xy 193.670401 167.923112)
				(xy 193.6815 167.75)
			)
		)
	)
	(zone
		(net 371)
		(net_name "/Com Express 7 MGMT/I2C.SCL")
		(layer "F.Cu")
		(name "$teardrop_padvia$")
		(hatch none 0.1)
		(priority 31829)
		(attr
			(teardrop
				(type padvia)
			)
		)
		(connect_pads yes
			(clearance 0)
		)
		(min_thickness 0.0254)
		(filled_areas_thickness no)
		(fill yes
			(thermal_gap 0.5)
			(thermal_bridge_width 0.5)
			(island_removal_mode 1)
			(island_area_min 10)
		)
		(polygon
			(pts
				(xy 259.540677 88.847499) (xy 259.471236 88.842681) (xy 259.419913 88.828959) (xy 259.344371 88.782245)
				(xy 259.332231 88.7727) (xy 259.265003 88.722918) (xy 259.139 88.909999) (xy 259.265003 89.09708)
				(xy 259.332229 89.047298) (xy 259.415396 88.992893) (xy 259.468251 88.977809) (xy 259.540677 88.972499)
			)
		)
	)
	(zone
		(net 424)
		(net_name "/2xSFP+/I2C_{SFP1}.SDA")
		(layer "F.Cu")
		(name "$teardrop_padvia$")
		(hatch none 0.1)
		(priority 31899)
		(attr
			(teardrop
				(type padvia)
			)
		)
		(connect_pads yes
			(clearance 0)
		)
		(min_thickness 0.0254)
		(filled_areas_thickness no)
		(fill yes
			(thermal_gap 0.5)
			(thermal_bridge_width 0.5)
			(island_removal_mode 1)
			(island_area_min 10)
		)
		(polygon
			(pts
				(xy 179.452877 144.0625) (xy 179.487615 144.067272) (xy 179.510167 144.08068) (xy 179.527895 144.12286)
				(xy 179.527226 144.192039) (xy 179.529323 144.293895) (xy 179.751 144.25) (xy 179.793895 144.029323)
				(xy 179.676809 143.99162) (xy 179.658131 143.983216) (xy 179.574939 143.951383) (xy 179.452877 143.9375)
			)
		)
	)
	(zone
		(net 699)
		(net_name "/USB-C console/FTDI_RX")
		(layer "F.Cu")
		(name "$teardrop_padvia$")
		(hatch none 0.1)
		(priority 30096)
		(attr
			(teardrop
				(type padvia)
			)
		)
		(connect_pads yes
			(clearance 0)
		)
		(min_thickness 0.0254)
		(filled_areas_thickness no)
		(fill yes
			(thermal_gap 0.5)
			(thermal_bridge_width 0.5)
			(island_removal_mode 1)
			(island_area_min 10)
		)
		(polygon
			(pts
				(xy 118.182206 72.8725) (xy 118.226747 72.877313) (xy 118.244721 72.891004) (xy 118.23541 72.920306)
				(xy 118.168976 72.985657) (xy 118.120406 73.025923) (xy 118.018805 73.112529) (xy 117.938199 73.201661)
				(xy 118.251 73.41) (xy 118.561801 73.201661) (xy 118.497492 73.077086) (xy 118.466281 72.991806)
				(xy 118.429941 72.896034) (xy 118.381226 72.818454) (xy 118.347191 72.788801) (xy 118.304019 72.766473)
				(xy 118.249696 72.752398) (xy 118.182206 72.7475)
			)
		)
	)
	(zone
		(net 744)
		(net_name "/2xSFP+/KR to SFI #2/TMS")
		(layer "F.Cu")
		(name "$teardrop_padvia$")
		(hatch none 0.1)
		(priority 30133)
		(attr
			(teardrop
				(type padvia)
			)
		)
		(connect_pads yes
			(clearance 0)
		)
		(min_thickness 0.0254)
		(filled_areas_thickness no)
		(fill yes
			(thermal_gap 0.5)
			(thermal_bridge_width 0.5)
			(island_removal_mode 1)
			(island_area_min 10)
		)
		(polygon
			(pts
				(xy 135.6525 130.227794) (xy 135.657315 130.145733) (xy 135.671019 130.080388) (xy 135.717576 129.98712)
				(xy 135.785787 129.908657) (xy 135.841942 129.847158) (xy 135.901801 129.768339) (xy 135.59 129.559)
				(xy 135.278199 129.768339) (xy 135.375219 129.888517) (xy 135.394214 129.908658) (xy 135.447366 129.967541)
				(xy 135.489591 130.031624) (xy 135.517449 130.114008) (xy 135.5275 130.227794)
			)
		)
	)
	(zone
		(net 2)
		(net_name "+3V3")
		(layer "F.Cu")
		(name "$teardrop_padvia$")
		(hatch none 0.1)
		(priority 30039)
		(attr
			(teardrop
				(type padvia)
			)
		)
		(connect_pads yes
			(clearance 0)
		)
		(min_thickness 0.0254)
		(filled_areas_thickness no)
		(fill yes
			(thermal_gap 0.5)
			(thermal_bridge_width 0.5)
			(island_removal_mode 1)
			(island_area_min 10)
		)
		(polygon
			(pts
				(xy 143.735913 138.235699) (xy 143.638968 138.305468) (xy 143.489412 138.363498) (xy 143.28074 138.401415)
				(xy 143.10567 138.41) (xy 143.189293 138.935707) (xy 143.65 139.042844) (xy 143.655326 138.863025)
				(xy 143.672612 138.697809) (xy 143.695507 138.582447) (xy 143.727693 138.480482) (xy 143.761338 138.408852)
				(xy 143.802219 138.348488) (xy 143.824301 138.324087)
			)
		)
	)
	(zone
		(net 158)
		(net_name "/2xUSB3.0+RJ45/USBSS_1.RX-")
		(layer "F.Cu")
		(name "$teardrop_padvia$")
		(hatch none 0.1)
		(priority 31484)
		(attr
			(teardrop
				(type padvia)
			)
		)
		(connect_pads yes
			(clearance 0)
		)
		(min_thickness 0.0254)
		(filled_areas_thickness no)
		(fill yes
			(thermal_gap 0.5)
			(thermal_bridge_width 0.5)
			(island_removal_mode 1)
			(island_area_min 10)
		)
		(polygon
			(pts
				(xy 179.9925 157.990416) (xy 179.98776 158.035027) (xy 179.974582 158.068424) (xy 179.929799 158.112019)
				(xy 179.88718 158.134851) (xy 179.839337 158.160508) (xy 179.793311 158.197104) (xy 179.9525 158.351)
				(xy 180.173177 158.337562) (xy 180.173316 158.154857) (xy 180.1775 157.990416)
			)
		)
	)
	(zone
		(net 158)
		(net_name "/2xUSB3.0+RJ45/USBSS_1.RX-")
		(layer "F.Cu")
		(name "$teardrop_padvia$")
		(hatch none 0.1)
		(priority 30294)
		(attr
			(teardrop
				(type padvia)
			)
		)
		(connect_pads yes
			(clearance 0)
		)
		(min_thickness 0.0254)
		(filled_areas_thickness no)
		(fill yes
			(thermal_gap 0.5)
			(thermal_bridge_width 0.5)
			(island_removal_mode 1)
			(island_area_min 10)
		)
		(polygon
			(pts
				(xy 180.1775 157.62) (xy 180.168097 157.446083) (xy 180.155714 157.211032) (xy 180.159219 157.071494)
				(xy 180.175 156.913685) (xy 180.025 156.684) (xy 179.945877 157.56) (xy 179.977617 157.564484) (xy 179.992473 157.575869)
				(xy 179.994085 157.607811) (xy 179.9925 157.62)
			)
		)
	)
	(zone
		(net 257)
		(net_name "/Com Express 7 Interfaces/PCIe_{B2Bx4}.TX1-")
		(layer "F.Cu")
		(name "$teardrop_padvia$")
		(hatch none 0.1)
		(priority 30272)
		(attr
			(teardrop
				(type padvia)
			)
		)
		(connect_pads yes
			(clearance 0)
		)
		(min_thickness 0.0254)
		(filled_areas_thickness no)
		(fill yes
			(thermal_gap 0.5)
			(thermal_bridge_width 0.5)
			(island_removal_mode 1)
			(island_area_min 10)
		)
		(polygon
			(pts
				(xy 193.8685 167.75) (xy 193.879599 167.923112) (xy 193.894216 168.15051) (xy 193.891181 168.285138)
				(xy 193.875 168.437021) (xy 194.025 168.686) (xy 194.108295 167.81) (xy 194.077864 167.805523) (xy 194.065097 167.794185)
				(xy 194.06742 167.764227) (xy 194.0705 167.75)
			)
		)
	)
	(zone
		(net 257)
		(net_name "/Com Express 7 Interfaces/PCIe_{B2Bx4}.TX1-")
		(layer "F.Cu")
		(name "$teardrop_padvia$")
		(hatch none 0.1)
		(priority 31356)
		(attr
			(teardrop
				(type padvia)
			)
		)
		(connect_pads yes
			(clearance 0)
		)
		(min_thickness 0.0254)
		(filled_areas_thickness no)
		(fill yes
			(thermal_gap 0.5)
			(thermal_bridge_width 0.5)
			(island_removal_mode 1)
			(island_area_min 10)
		)
		(polygon
			(pts
				(xy 190.367496 166.1045) (xy 190.32071 166.099765) (xy 190.285258 166.086621) (xy 190.23706 166.041613)
				(xy 190.212884 166.003392) (xy 190.185514 165.960225) (xy 190.148852 165.918268) (xy 189.999 166.0815)
				(xy 190.01986 166.302177) (xy 190.120531 166.297548) (xy 190.203897 166.30098) (xy 190.205964 166.301105)
				(xy 190.367496 166.3065)
			)
		)
	)
	(zone
		(net 611)
		(net_name "/PCIe misc/DIF0+")
		(layer "F.Cu")
		(name "$teardrop_padvia$")
		(hatch none 0.1)
		(priority 30420)
		(attr
			(teardrop
				(type padvia)
			)
		)
		(connect_pads yes
			(clearance 0)
		)
		(min_thickness 0.0254)
		(filled_areas_thickness no)
		(fill yes
			(thermal_gap 0.5)
			(thermal_bridge_width 0.5)
			(island_removal_mode 1)
			(island_area_min 10)
		)
		(polygon
			(pts
				(xy 210.225521 128.0245) (xy 210.197939 128.001242) (xy 210.177276 127.970004) (xy 210.154401 127.878085)
				(xy 210.155 127.721085) (xy 209.859 127.82) (xy 209.828246 128.14) (xy 209.943378 128.130561) (xy 210.071718 128.155334)
				(xy 210.203283 128.213209) (xy 210.225521 128.2265)
			)
		)
	)
	(zone
		(net 288)
		(net_name "/2xUSB3.0+RJ45/~{GBE0_LINK_1000}")
		(layer "F.Cu")
		(name "$teardrop_padvia$")
		(hatch none 0.1)
		(priority 31740)
		(attr
			(teardrop
				(type padvia)
			)
		)
		(connect_pads yes
			(clearance 0)
		)
		(min_thickness 0.0254)
		(filled_areas_thickness no)
		(fill yes
			(thermal_gap 0.5)
			(thermal_bridge_width 0.5)
			(island_removal_mode 1)
			(island_area_min 10)
		)
		(polygon
			(pts
				(xy 145.1375 151.899323) (xy 145.132682 151.968763) (xy 145.11896 152.020087) (xy 145.072245 152.095628)
				(xy 145.062702 152.107768) (xy 145.012919 152.174997) (xy 145.2 152.301) (xy 145.387081 152.174997)
				(xy 145.337299 152.107769) (xy 145.282894 152.024603) (xy 145.26781 151.971748) (xy 145.2625 151.899323)
			)
		)
	)
	(zone
		(net 382)
		(net_name "Net-(J12D-~{CB_RESET})")
		(layer "F.Cu")
		(name "$teardrop_padvia$")
		(hatch none 0.1)
		(priority 30991)
		(attr
			(teardrop
				(type padvia)
			)
		)
		(connect_pads yes
			(clearance 0)
		)
		(min_thickness 0.0254)
		(filled_areas_thickness no)
		(fill yes
			(thermal_gap 0.5)
			(thermal_bridge_width 0.5)
			(island_removal_mode 1)
			(island_area_min 10)
		)
		(polygon
			(pts
				(xy 307.088 156.1275) (xy 307.025134 156.107531) (xy 306.993156 156.081079) (xy 306.964642 156.043668)
				(xy 306.942118 155.996473) (xy 306.926907 155.938833) (xy 306.926798 155.938202) (xy 306.649 156.19)
				(xy 306.926798 156.441798) (xy 306.941095 156.386365) (xy 306.962175 156.34048) (xy 306.98954 156.302799)
				(xy 307.020448 156.275566) (xy 307.053735 156.258528) (xy 307.086566 156.252511) (xy 307.088 156.2525)
			)
		)
	)
	(zone
		(net 586)
		(net_name "Net-(U22-FB)")
		(layer "F.Cu")
		(name "$teardrop_padvia$")
		(hatch none 0.1)
		(priority 30623)
		(attr
			(teardrop
				(type padvia)
			)
		)
		(connect_pads yes
			(clearance 0)
		)
		(min_thickness 0.0254)
		(filled_areas_thickness no)
		(fill yes
			(thermal_gap 0.5)
			(thermal_bridge_width 0.5)
			(island_removal_mode 1)
			(island_area_min 10)
		)
		(polygon
			(pts
				(xy 313.446959 136.293072) (xy 313.401147 136.21949) (xy 313.378339 136.104135) (xy 313.379813 136.031573)
				(xy 313.391723 135.952941) (xy 313.395499 135.936314) (xy 313.074792 135.979293) (xy 312.985633 136.275)
				(xy 313.144818 136.283284) (xy 313.21649 136.3009) (xy 313.278657 136.325902) (xy 313.358571 136.38146)
			)
		)
	)
	(zone
		(net 1)
		(net_name "GND")
		(layer "F.Cu")
		(name "$teardrop_padvia$")
		(hatch none 0.1)
		(priority 30959)
		(attr
			(teardrop
				(type padvia)
			)
		)
		(connect_pads yes
			(clearance 0)
		)
		(min_thickness 0.0254)
		(filled_areas_thickness no)
		(fill yes
			(thermal_gap 0.5)
			(thermal_bridge_width 0.5)
			(island_removal_mode 1)
			(island_area_min 10)
		)
		(polygon
			(pts
				(xy 124.2975 133.442) (xy 124.277531 133.504866) (xy 124.251079 133.536844) (xy 124.213668 133.565358)
				(xy 124.166473 133.587882) (xy 124.108833 133.603093) (xy 124.108202 133.603202) (xy 124.36 133.881)
				(xy 124.611798 133.603202) (xy 124.556365 133.588905) (xy 124.51048 133.567825) (xy 124.472799 133.54046)
				(xy 124.445566 133.509552) (xy 124.428528 133.476265) (xy 124.422511 133.443434) (xy 124.4225 133.442)
			)
		)
	)
	(zone
		(net 47)
		(net_name "/2xUSB3.0+RJ45/USBSS_1.TX-")
		(layer "F.Cu")
		(name "$teardrop_padvia$")
		(hatch none 0.1)
		(priority 30289)
		(attr
			(teardrop
				(type padvia)
			)
		)
		(connect_pads yes
			(clearance 0)
		)
		(min_thickness 0.0254)
		(filled_areas_thickness no)
		(fill yes
			(thermal_gap 0.5)
			(thermal_bridge_width 0.5)
			(island_removal_mode 1)
			(island_area_min 10)
		)
		(polygon
			(pts
				(xy 179.9925 150.2) (xy 179.994085 150.212189) (xy 179.992704 150.243738) (xy 179.977931 150.255396)
				(xy 179.945877 150.26) (xy 180.025 151.136) (xy 180.175 150.906314) (xy 180.155715 150.6469) (xy 180.168097 150.373917)
				(xy 180.1775 150.2)
			)
		)
	)
	(zone
		(net 267)
		(net_name "/Com Express 7 Interfaces/PCIe_{B2Bx4}.TX0-")
		(layer "F.Cu")
		(name "$teardrop_padvia$")
		(hatch none 0.1)
		(priority 30266)
		(attr
			(teardrop
				(type padvia)
			)
		)
		(connect_pads yes
			(clearance 0)
		)
		(min_thickness 0.0254)
		(filled_areas_thickness no)
		(fill yes
			(thermal_gap 0.5)
			(thermal_bridge_width 0.5)
			(island_removal_mode 1)
			(island_area_min 10)
		)
		(polygon
			(pts
				(xy 195.3685 167.75) (xy 195.379599 167.923112) (xy 195.394216 168.15051) (xy 195.391181 168.285138)
				(xy 195.375 168.437021) (xy 195.525 168.686) (xy 195.608295 167.81) (xy 195.577864 167.805523) (xy 195.565097 167.794185)
				(xy 195.56742 167.764227) (xy 195.5705 167.75)
			)
		)
	)
	(zone
		(net 397)
		(net_name "/Com Express 7 MGMT/SPI.~{CS}")
		(layer "F.Cu")
		(name "$teardrop_padvia$")
		(hatch none 0.1)
		(priority 31600)
		(attr
			(teardrop
				(type padvia)
			)
		)
		(connect_pads yes
			(clearance 0)
		)
		(min_thickness 0.0254)
		(filled_areas_thickness no)
		(fill yes
			(thermal_gap 0.5)
			(thermal_bridge_width 0.5)
			(island_removal_mode 1)
			(island_area_min 10)
		)
		(polygon
			(pts
				(xy 223.9625 163.949323) (xy 223.957831 164.019201) (xy 223.945144 164.072579) (xy 223.900666 164.159579)
				(xy 223.842355 164.274641) (xy 224.05 164.351) (xy 224.237081 164.224997) (xy 224.16863 164.142342)
				(xy 224.110755 164.067857) (xy 224.093685 164.017955) (xy 224.0875 163.949323)
			)
		)
	)
	(zone
		(net 71)
		(net_name "Net-(U49-IN+)")
		(layer "F.Cu")
		(hatch edge 0.5)
		(priority 1)
		(connect_pads yes
			(clearance 0.15)
		)
		(min_thickness 0.25)
		(filled_areas_thickness no)
		(fill yes
			(thermal_gap 0.2)
			(thermal_bridge_width 0.5)
			(smoothing fillet)
			(radius 0.2)
		)
		(polygon
			(pts
				(xy 308.524999 99.55) (xy 308.524999 106.091) (xy 308.725962 106.3) (xy 309.724999 106.3) (xy 310.474999 107.05)
				(xy 310.474999 113.6) (xy 310.224999 113.85) (xy 307.874999 113.85) (xy 306.124999 112.1) (xy 304.75 110.725236)
				(xy 304.75 98.9) (xy 307.874999 98.9)
			)
		)
	)
	(zone
		(net 1)
		(net_name "GND")
		(layer "F.Cu")
		(name "$teardrop_padvia$")
		(hatch none 0.1)
		(priority 30530)
		(attr
			(teardrop
				(type padvia)
			)
		)
		(connect_pads yes
			(clearance 0)
		)
		(min_thickness 0.0254)
		(filled_areas_thickness no)
		(fill yes
			(thermal_gap 0.5)
			(thermal_bridge_width 0.5)
			(island_removal_mode 1)
			(island_area_min 10)
		)
		(polygon
			(pts
				(xy 197.425 155.75) (xy 197.428333 155.764486) (xy 197.43119 155.79461) (xy 197.419036 155.805651)
				(xy 197.39 155.81) (xy 197.525 156.686) (xy 197.66 155.81) (xy 197.630666 155.805525) (xy 197.618642 155.794199)
				(xy 197.621667 155.764486) (xy 197.625 155.75)
			)
		)
	)
	(zone
		(net 554)
		(net_name "/2xUSB3.0+RJ45/FLG_2B")
		(layer "F.Cu")
		(name "$teardrop_padvia$")
		(hatch none 0.1)
		(priority 31129)
		(attr
			(teardrop
				(type padvia)
			)
		)
		(connect_pads yes
			(clearance 0)
		)
		(min_thickness 0.0254)
		(filled_areas_thickness no)
		(fill yes
			(thermal_gap 0.5)
			(thermal_bridge_width 0.5)
			(island_removal_mode 1)
			(island_area_min 10)
		)
		(polygon
			(pts
				(xy 121.157 93.0225) (xy 121.216412 93.042273) (xy 121.272497 93.105547) (xy 121.294199 93.154172)
				(xy 121.308873 93.213531) (xy 121.310653 93.2255) (xy 121.571 92.96) (xy 121.310653 92.6945) (xy 121.297804 92.754638)
				(xy 121.27787 92.804522) (xy 121.251945 92.844641) (xy 121.222125 92.873654) (xy 121.190707 92.891146)
				(xy 121.158896 92.897479) (xy 121.157 92.8975)
			)
		)
	)
	(zone
		(net 533)
		(net_name "/Com Express 7 MGMT/PSON")
		(layer "F.Cu")
		(name "$teardrop_padvia$")
		(hatch none 0.1)
		(priority 31049)
		(attr
			(teardrop
				(type padvia)
			)
		)
		(connect_pads yes
			(clearance 0)
		)
		(min_thickness 0.0254)
		(filled_areas_thickness no)
		(fill yes
			(thermal_gap 0.5)
			(thermal_bridge_width 0.5)
			(island_removal_mode 1)
			(island_area_min 10)
		)
		(polygon
			(pts
				(xy 240.8625 133.253) (xy 240.882273 133.193588) (xy 240.945547 133.137503) (xy 240.994172 133.115801)
				(xy 241.053532 133.101127) (xy 241.0655 133.099347) (xy 240.8 132.839) (xy 240.5345 133.099347)
				(xy 240.594639 133.112197) (xy 240.644523 133.132131) (xy 240.684642 133.158056) (xy 240.713655 133.187876)
				(xy 240.731146 133.219294) (xy 240.737479 133.251105) (xy 240.7375 133.253)
			)
		)
	)
	(zone
		(net 531)
		(net_name "/Com Express 7 Interfaces/SD_CD")
		(layer "F.Cu")
		(name "$teardrop_padvia$")
		(hatch none 0.1)
		(priority 31704)
		(attr
			(teardrop
				(type padvia)
			)
		)
		(connect_pads yes
			(clearance 0)
		)
		(min_thickness 0.0254)
		(filled_areas_thickness no)
		(fill yes
			(thermal_gap 0.5)
			(thermal_bridge_width 0.5)
			(island_removal_mode 1)
			(island_area_min 10)
		)
		(polygon
			(pts
				(xy 206.9625 163.774323) (xy 206.957682 163.843763) (xy 206.94396 163.895087) (xy 206.897245 163.970628)
				(xy 206.887702 163.982768) (xy 206.837919 164.049997) (xy 207.025 164.176) (xy 207.212081 164.049997)
				(xy 207.162299 163.982769) (xy 207.107894 163.899603) (xy 207.09281 163.846748) (xy 207.0875 163.774323)
			)
		)
	)
	(zone
		(net 604)
		(net_name "Net-(U37-~{OE2})")
		(layer "F.Cu")
		(name "$teardrop_padvia$")
		(hatch none 0.1)
		(priority 31105)
		(attr
			(teardrop
				(type padvia)
			)
		)
		(connect_pads yes
			(clearance 0)
		)
		(min_thickness 0.0254)
		(filled_areas_thickness no)
		(fill yes
			(thermal_gap 0.5)
			(thermal_bridge_width 0.5)
			(island_removal_mode 1)
			(island_area_min 10)
		)
		(polygon
			(pts
				(xy 215.8625 136.057) (xy 215.842727 136.116412) (xy 215.779453 136.172496) (xy 215.730828 136.194198)
				(xy 215.671469 136.208872) (xy 215.6595 136.210652) (xy 215.925 136.471) (xy 216.1905 136.210652)
				(xy 216.130362 136.197803) (xy 216.080478 136.177869) (xy 216.040358 136.151944) (xy 216.011345 136.122124)
				(xy 215.993854 136.090706) (xy 215.987521 136.058895) (xy 215.9875 136.057)
			)
		)
	)
	(zone
		(net 1)
		(net_name "GND")
		(layer "F.Cu")
		(name "$teardrop_padvia$")
		(hatch none 0.1)
		(priority 31193)
		(attr
			(teardrop
				(type padvia)
			)
		)
		(connect_pads yes
			(clearance 0)
		)
		(min_thickness 0.0254)
		(filled_areas_thickness no)
		(fill yes
			(thermal_gap 0.5)
			(thermal_bridge_width 0.5)
			(island_removal_mode 1)
			(island_area_min 10)
		)
		(polygon
			(pts
				(xy 196.125 162.321677) (xy 196.12972 162.252353) (xy 196.142756 162.199449) (xy 196.194658 162.10686)
				(xy 196.246458 162.023363) (xy 196.05 161.92) (xy 195.842355 161.996358) (xy 195.874583 162.076861)
				(xy 195.910965 162.178318) (xy 195.925 162.321677)
			)
		)
	)
	(zone
		(net 189)
		(net_name "/OCuLink/PCIe_{x4}.RX1-")
		(layer "F.Cu")
		(name "$teardrop_padvia$")
		(hatch none 0.1)
		(priority 31376)
		(attr
			(teardrop
				(type padvia)
			)
		)
		(connect_pads yes
			(clearance 0)
		)
		(min_thickness 0.0254)
		(filled_areas_thickness no)
		(fill yes
			(thermal_gap 0.5)
			(thermal_bridge_width 0.5)
			(island_removal_mode 1)
			(island_area_min 10)
		)
		(polygon
			(pts
				(xy 99.232504 149.5955) (xy 99.27929 149.600235) (xy 99.314742 149.613379) (xy 99.362939 149.658387)
				(xy 99.387116 149.696608) (xy 99.414485 149.739773) (xy 99.451147 149.781731) (xy 99.601 149.6185)
				(xy 99.58014 149.397823) (xy 99.479466 149.402452) (xy 99.396096 149.399019) (xy 99.394035 149.398895)
				(xy 99.232504 149.3935)
			)
		)
	)
	(zone
		(net 67)
		(net_name "Net-(C47-Pad2)")
		(layer "F.Cu")
		(name "$teardrop_padvia$")
		(hatch none 0.1)
		(priority 32143)
		(attr
			(teardrop
				(type padvia)
			)
		)
		(connect_pads yes
			(clearance 0)
		)
		(min_thickness 0.0254)
		(filled_areas_thickness no)
		(fill yes
			(thermal_gap 0.5)
			(thermal_bridge_width 0.5)
			(island_removal_mode 1)
			(island_area_min 10)
		)
		(polygon
			(pts
				(xy 312.462499 121.659099) (xy 312.504616 121.730709) (xy 312.524851 121.847522) (xy 312.519999 121.942195)
				(xy 312.619999 121.959999) (xy 312.619953 121.66092) (xy 312.595879 121.667747) (xy 312.589958 121.663136)
				(xy 312.587499 121.659099)
			)
		)
	)
	(zone
		(net 527)
		(net_name "/Backplane/GPIO")
		(layer "F.Cu")
		(name "$teardrop_padvia$")
		(hatch none 0.1)
		(priority 32120)
		(attr
			(teardrop
				(type padvia)
			)
		)
		(connect_pads yes
			(clearance 0)
		)
		(min_thickness 0.0254)
		(filled_areas_thickness no)
		(fill yes
			(thermal_gap 0.5)
			(thermal_bridge_width 0.5)
			(island_removal_mode 1)
			(island_area_min 10)
		)
		(polygon
			(pts
				(xy 315.46 164.8955) (xy 315.453678 164.895596) (xy 315.414175 164.890011) (xy 315.395953 164.875078)
				(xy 315.383005 164.8455) (xy 315.134 164.958) (xy 315.383005 165.0705) (xy 315.394121 165.043506)
				(xy 315.409648 165.028405) (xy 315.453678 165.020404) (xy 315.46 165.0205)
			)
		)
	)
	(zone
		(net 759)
		(net_name "Net-(U45B-LS_OK_{OUT_B})")
		(layer "F.Cu")
		(name "$teardrop_padvia$")
		(hatch none 0.1)
		(priority 30122)
		(attr
			(teardrop
				(type padvia)
			)
		)
		(connect_pads yes
			(clearance 0)
		)
		(min_thickness 0.0254)
		(filled_areas_thickness no)
		(fill yes
			(thermal_gap 0.5)
			(thermal_bridge_width 0.5)
			(island_removal_mode 1)
			(island_area_min 10)
		)
		(polygon
			(pts
				(xy 129.1525 130.227794) (xy 129.157315 130.145733) (xy 129.171019 130.080388) (xy 129.217576 129.98712)
				(xy 129.285787 129.908657) (xy 129.341942 129.847158) (xy 129.401801 129.768339) (xy 129.09 129.559)
				(xy 128.778199 129.768339) (xy 128.875219 129.888517) (xy 128.894214 129.908658) (xy 128.947366 129.967541)
				(xy 128.989591 130.031624) (xy 129.017449 130.114008) (xy 129.0275 130.227794)
			)
		)
	)
	(zone
		(net 111)
		(net_name "/2xSFP+/10GKR_SFP0.TX+")
		(layer "F.Cu")
		(name "$teardrop_padvia$")
		(hatch none 0.1)
		(priority 31617)
		(attr
			(teardrop
				(type padvia)
			)
		)
		(connect_pads yes
			(clearance 0)
		)
		(min_thickness 0.0254)
		(filled_areas_thickness no)
		(fill yes
			(thermal_gap 0.5)
			(thermal_bridge_width 0.5)
			(island_removal_mode 1)
			(island_area_min 10)
		)
		(polygon
			(pts
				(xy 197.811344 153.778506) (xy 197.785868 153.746304) (xy 197.774527 153.716168) (xy 197.781386 153.660293)
				(xy 197.799935 153.618294) (xy 197.832558 153.531014) (xy 197.611174 153.486412) (xy 197.457354 153.644676)
				(xy 197.57323 153.763035) (xy 197.698207 153.891643)
			)
		)
	)
	(zone
		(net 624)
		(net_name "/PCIe redriver/TX_EQ1")
		(layer "F.Cu")
		(name "$teardrop_padvia$")
		(hatch none 0.1)
		(priority 31537)
		(attr
			(teardrop
				(type padvia)
			)
		)
		(connect_pads yes
			(clearance 0)
		)
		(min_thickness 0.0254)
		(filled_areas_thickness no)
		(fill yes
			(thermal_gap 0.5)
			(thermal_bridge_width 0.5)
			(island_removal_mode 1)
			(island_area_min 10)
		)
		(polygon
			(pts
				(xy 112.063788 146.934599) (xy 112.083475 146.934113) (xy 112.100352 146.944778) (xy 112.125225 147.000199)
				(xy 112.136228 147.088946) (xy 112.420707 146.859293) (xy 112.147498 146.614187) (xy 112.120924 146.70976)
				(xy 112.061994 146.791998) (xy 112.022894 146.823621) (xy 111.983747 146.843509) (xy 111.975401 146.846212)
			)
		)
	)
	(zone
		(net 701)
		(net_name "/USB-C console/FTDI_CBUS0")
		(layer "F.Cu")
		(name "$teardrop_padvia$")
		(hatch none 0.1)
		(priority 30098)
		(attr
			(teardrop
				(type padvia)
			)
		)
		(connect_pads yes
			(clearance 0)
		)
		(min_thickness 0.0254)
		(filled_areas_thickness no)
		(fill yes
			(thermal_gap 0.5)
			(thermal_bridge_width 0.5)
			(island_removal_mode 1)
			(island_area_min 10)
		)
		(polygon
			(pts
				(xy 116.072499 78.232206) (xy 116.067684 78.314266) (xy 116.05398 78.379611) (xy 116.007423 78.472879)
				(xy 115.939213 78.551341) (xy 115.883057 78.612841) (xy 115.823198 78.691661) (xy 116.134999 78.901)
				(xy 116.4468 78.691661) (xy 116.34978 78.571482) (xy 116.330785 78.551341) (xy 116.277633 78.492458)
				(xy 116.235407 78.428375) (xy 116.207549 78.345992) (xy 116.197499 78.232206)
			)
		)
	)
	(zone
		(net 616)
		(net_name "/PCIe misc/DIF2-")
		(layer "F.Cu")
		(name "$teardrop_padvia$")
		(hatch none 0.1)
		(priority 30438)
		(attr
			(teardrop
				(type padvia)
			)
		)
		(connect_pads yes
			(clearance 0)
		)
		(min_thickness 0.0254)
		(filled_areas_thickness no)
		(fill yes
			(thermal_gap 0.5)
			(thermal_bridge_width 0.5)
			(island_removal_mode 1)
			(island_area_min 10)
		)
		(polygon
			(pts
				(xy 214.5735 134.154479) (xy 214.615458 134.232727) (xy 214.651472 134.331282) (xy 214.66683 134.408157)
				(xy 214.669442 134.488423) (xy 214.66 134.551754) (xy 214.98 134.521) (xy 215.078914 134.225) (xy 214.954533 134.227815)
				(xy 214.863647 134.215293) (xy 214.821613 134.198304) (xy 214.789966 134.173452) (xy 214.7755 134.154479)
			)
		)
	)
	(zone
		(net 1)
		(net_name "GND")
		(layer "F.Cu")
		(name "$teardrop_padvia$")
		(hatch none 0.1)
		(priority 31293)
		(attr
			(teardrop
				(type padvia)
			)
		)
		(connect_pads yes
			(clearance 0)
		)
		(min_thickness 0.0254)
		(filled_areas_thickness no)
		(fill yes
			(thermal_gap 0.5)
			(thermal_bridge_width 0.5)
			(island_removal_mode 1)
			(island_area_min 10)
		)
		(polygon
			(pts
				(xy 187.86261 157.595969) (xy 187.804186 157.647728) (xy 187.753436 157.68011) (xy 187.659299 157.714708)
				(xy 187.56888 157.744741) (xy 187.649293 157.950707) (xy 187.855257 158.031121) (xy 187.88529 157.940703)
				(xy 187.920762 157.844889) (xy 187.952979 157.794885) (xy 188.004031 157.73739)
			)
		)
	)
	(zone
		(net 785)
		(net_name "Net-(U33-1Y)")
		(layer "F.Cu")
		(name "$teardrop_padvia$")
		(hatch none 0.1)
		(priority 31679)
		(attr
			(teardrop
				(type padvia)
			)
		)
		(connect_pads yes
			(clearance 0)
		)
		(min_thickness 0.0254)
		(filled_areas_thickness no)
		(fill yes
			(thermal_gap 0.5)
			(thermal_bridge_width 0.5)
			(island_removal_mode 1)
			(island_area_min 10)
		)
		(polygon
			(pts
				(xy 248.9055 132.432) (xy 248.899978 132.459072) (xy 248.881322 132.484611) (xy 248.854703 132.50078)
				(xy 248.815962 132.510399) (xy 248.788 132.512) (xy 248.968 132.888) (xy 249.148 132.512) (xy 249.1025 132.507387)
				(xy 249.069532 132.4951) (xy 249.035156 132.456945) (xy 249.0305 132.432)
			)
		)
	)
	(zone
		(net 409)
		(net_name "Net-(J12K-10G_SDP2)")
		(layer "F.Cu")
		(name "$teardrop_padvia$")
		(hatch none 0.1)
		(priority 31819)
		(attr
			(teardrop
				(type padvia)
			)
		)
		(connect_pads yes
			(clearance 0)
		)
		(min_thickness 0.0254)
		(filled_areas_thickness no)
		(fill yes
			(thermal_gap 0.5)
			(thermal_bridge_width 0.5)
			(island_removal_mode 1)
			(island_area_min 10)
		)
		(polygon
			(pts
				(xy 181.200677 159.0875) (xy 181.131236 159.082682) (xy 181.079913 159.06896) (xy 181.004371 159.022246)
				(xy 180.992231 159.012701) (xy 180.925003 158.962919) (xy 180.799 159.15) (xy 180.925003 159.337081)
				(xy 180.992229 159.287299) (xy 181.075396 159.232894) (xy 181.128251 159.21781) (xy 181.200677 159.2125)
			)
		)
	)
	(zone
		(net 1)
		(net_name "GND")
		(layer "F.Cu")
		(name "$teardrop_padvia$")
		(hatch none 0.1)
		(priority 30897)
		(attr
			(teardrop
				(type padvia)
			)
		)
		(connect_pads yes
			(clearance 0)
		)
		(min_thickness 0.0254)
		(filled_areas_thickness no)
		(fill yes
			(thermal_gap 0.5)
			(thermal_bridge_width 0.5)
			(island_removal_mode 1)
			(island_area_min 10)
		)
		(polygon
			(pts
				(xy 261.205598 88.419999) (xy 261.245174 88.424695) (xy 261.275254 88.437567) (xy 261.317173 88.482611)
				(xy 261.33541 88.515582) (xy 261.371346 88.573429) (xy 261.540999 88.429999) (xy 261.548721 88.209322)
				(xy 261.458991 88.189709) (xy 261.414611 88.170415) (xy 261.327468 88.13617) (xy 261.205597 88.12)
			)
		)
	)
	(zone
		(net 532)
		(net_name "/Backplane/PCIe_{x2}.RX0+")
		(layer "F.Cu")
		(name "$teardrop_padvia$")
		(hatch none 0.1)
		(priority 32035)
		(attr
			(teardrop
				(type padvia)
			)
		)
		(connect_pads yes
			(clearance 0)
		)
		(min_thickness 0.0254)
		(filled_areas_thickness no)
		(fill yes
			(thermal_gap 0.5)
			(thermal_bridge_width 0.5)
			(island_removal_mode 1)
			(island_area_min 10)
		)
		(polygon
			(pts
				(xy 314.038 160.0665) (xy 314.117272 160.048854) (xy 314.202896 160.027263) (xy 314.250145 160.025372)
				(xy 314.300083 160.035) (xy 314.364 159.91) (xy 314.088953 159.842707) (xy 314.08432 159.86951)
				(xy 314.073289 159.877052) (xy 314.051941 159.869832) (xy 314.038 159.8645)
			)
		)
	)
	(zone
		(net 1)
		(net_name "GND")
		(layer "F.Cu")
		(name "$teardrop_padvia$")
		(hatch none 0.1)
		(priority 31253)
		(attr
			(teardrop
				(type padvia)
			)
		)
		(connect_pads yes
			(clearance 0)
		)
		(min_thickness 0.0254)
		(filled_areas_thickness no)
		(fill yes
			(thermal_gap 0.5)
			(thermal_bridge_width 0.5)
			(island_removal_mode 1)
			(island_area_min 10)
		)
		(polygon
			(pts
				(xy 184.307933 72.902163) (xy 184.385845 72.906876) (xy 184.44463 72.919863) (xy 184.535661 72.961965)
				(xy 184.620832 73.004663) (xy 184.70961 72.802163) (xy 184.620832 72.599663) (xy 184.53566 72.642362)
				(xy 184.442827 72.68503) (xy 184.384688 72.697607) (xy 184.307933 72.702163)
			)
		)
	)
	(zone
		(net 1)
		(net_name "GND")
		(layer "F.Cu")
		(name "$teardrop_padvia$")
		(hatch none 0.1)
		(priority 30711)
		(attr
			(teardrop
				(type padvia)
			)
		)
		(connect_pads yes
			(clearance 0)
		)
		(min_thickness 0.0254)
		(filled_areas_thickness no)
		(fill yes
			(thermal_gap 0.5)
			(thermal_bridge_width 0.5)
			(island_removal_mode 1)
			(island_area_min 10)
		)
		(polygon
			(pts
				(xy 225.6 164.07) (xy 225.596865 164.055714) (xy 225.594488 164.025461) (xy 225.607042 164.014369)
				(xy 225.636651 164.01) (xy 225.525 163.134) (xy 225.375 164.01) (xy 225.40119 164.01447) (xy 225.410657 164.025762)
				(xy 225.40468 164.054279) (xy 225.4 164.07)
			)
		)
	)
	(zone
		(net 204)
		(net_name "/Backplane/USB.D-")
		(layer "F.Cu")
		(name "$teardrop_padvia$")
		(hatch none 0.1)
		(priority 30621)
		(attr
			(teardrop
				(type padvia)
			)
		)
		(connect_pads yes
			(clearance 0)
		)
		(min_thickness 0.0254)
		(filled_areas_thickness no)
		(fill yes
			(thermal_gap 0.5)
			(thermal_bridge_width 0.5)
			(island_removal_mode 1)
			(island_area_min 10)
		)
		(polygon
			(pts
				(xy 198.1175 169.62) (xy 198.115543 169.607187) (xy 198.115762 169.576049) (xy 198.12949 169.564544)
				(xy 198.16 169.56) (xy 198.025 168.684) (xy 197.89 169.56) (xy 197.920352 169.56448) (xy 197.934128 169.575842)
				(xy 197.934457 169.607187) (xy 197.9325 169.62)
			)
		)
	)
	(zone
		(net 1)
		(net_name "GND")
		(layer "F.Cu")
		(name "$teardrop_padvia$")
		(hatch none 0.1)
		(priority 31189)
		(attr
			(teardrop
				(type padvia)
			)
		)
		(connect_pads yes
			(clearance 0)
		)
		(min_thickness 0.0254)
		(filled_areas_thickness no)
		(fill yes
			(thermal_gap 0.5)
			(thermal_bridge_width 0.5)
			(island_removal_mode 1)
			(island_area_min 10)
		)
		(polygon
			(pts
				(xy 197.625 150.500677) (xy 197.62972 150.431353) (xy 197.642756 150.378449) (xy 197.694658 150.28586)
				(xy 197.746458 150.202363) (xy 197.55 150.099) (xy 197.342355 150.175358) (xy 197.374583 150.255861)
				(xy 197.410965 150.357318) (xy 197.425 150.500677)
			)
		)
	)
	(zone
		(net 115)
		(net_name "/2xSFP+/KR to SFI #2/CLK+")
		(layer "F.Cu")
		(name "$teardrop_padvia$")
		(hatch none 0.1)
		(priority 30631)
		(attr
			(teardrop
				(type padvia)
			)
		)
		(connect_pads yes
			(clearance 0)
		)
		(min_thickness 0.0254)
		(filled_areas_thickness no)
		(fill yes
			(thermal_gap 0.5)
			(thermal_bridge_width 0.5)
			(island_removal_mode 1)
			(island_area_min 10)
		)
		(polygon
			(pts
				(xy 123.996343 141.63) (xy 124.04195 141.685193) (xy 124.065457 141.779328) (xy 124.065 141.956839)
				(xy 124.361 141.86) (xy 124.394492 141.54) (xy 124.266107 141.552255) (xy 124.128236 141.529889)
				(xy 124.005029 141.475763) (xy 123.996343 141.47)
			)
		)
	)
	(zone
		(net 358)
		(net_name "/Com Express 7 MGMT/SMBus.SDA")
		(layer "F.Cu")
		(name "$teardrop_padvia$")
		(hatch none 0.1)
		(priority 31787)
		(attr
			(teardrop
				(type padvia)
			)
		)
		(connect_pads yes
			(clearance 0)
		)
		(min_thickness 0.0254)
		(filled_areas_thickness no)
		(fill yes
			(thermal_gap 0.5)
			(thermal_bridge_width 0.5)
			(island_removal_mode 1)
			(island_area_min 10)
		)
		(polygon
			(pts
				(xy 127.1625 149.050677) (xy 127.167318 148.981236) (xy 127.18104 148.929912) (xy 127.227755 148.85437)
				(xy 127.237299 148.842229) (xy 127.287081 148.775003) (xy 127.1 148.649) (xy 126.912919 148.775003)
				(xy 126.962701 148.842231) (xy 127.017106 148.925397) (xy 127.03219 148.978251) (xy 127.0375 149.050677)
			)
		)
	)
	(zone
		(net 186)
		(net_name "/OCuLink/PCIe_{x4}.RX0+")
		(layer "F.Cu")
		(name "$teardrop_padvia$")
		(hatch none 0.1)
		(priority 32068)
		(attr
			(teardrop
				(type padvia)
			)
		)
		(connect_pads yes
			(clearance 0)
		)
		(min_thickness 0.0254)
		(filled_areas_thickness no)
		(fill yes
			(thermal_gap 0.5)
			(thermal_bridge_width 0.5)
			(island_removal_mode 1)
			(island_area_min 10)
		)
		(polygon
			(pts
				(xy 96.603 151.797) (xy 96.595802 151.776352) (xy 96.586208 151.744016) (xy 96.593035 151.729993)
				(xy 96.6145 151.720004) (xy 96.502 151.471) (xy 96.3895 151.720004) (xy 96.410676 151.729729) (xy 96.417731 151.743357)
				(xy 96.408198 151.776352) (xy 96.401 151.797)
			)
		)
	)
	(zone
		(net 315)
		(net_name "Net-(J12H-VCC_RTC)")
		(layer "F.Cu")
		(name "$teardrop_padvia$")
		(hatch none 0.1)
		(priority 31869)
		(attr
			(teardrop
				(type padvia)
			)
		)
		(connect_pads yes
			(clearance 0)
		)
		(min_thickness 0.0254)
		(filled_areas_thickness no)
		(fill yes
			(thermal_gap 0.5)
			(thermal_bridge_width 0.5)
			(island_removal_mode 1)
			(island_area_min 10)
		)
		(polygon
			(pts
				(xy 199.360873 167.177515) (xy 199.413382 167.131819) (xy 199.459376 167.105231) (xy 199.545824 167.084847)
				(xy 199.56116 167.083011) (xy 199.643895 167.070677) (xy 199.600707 166.849293) (xy 199.379323 166.806105)
				(xy 199.366988 166.888841) (xy 199.346651 166.986119) (xy 199.319943 167.034159) (xy 199.272485 167.089127)
			)
		)
	)
	(zone
		(net 577)
		(net_name "Net-(U18-EN)")
		(layer "F.Cu")
		(name "$teardrop_padvia$")
		(hatch none 0.1)
		(priority 31822)
		(attr
			(teardrop
				(type padvia)
			)
		)
		(connect_pads yes
			(clearance 0)
		)
		(min_thickness 0.0254)
		(filled_areas_thickness no)
		(fill yes
			(thermal_gap 0.5)
			(thermal_bridge_width 0.5)
			(island_removal_mode 1)
			(island_area_min 10)
		)
		(polygon
			(pts
				(xy 310.225676 120.046499) (xy 310.156235 120.041681) (xy 310.104912 120.027959) (xy 310.02937 119.981245)
				(xy 310.01723 119.9717) (xy 309.950002 119.921918) (xy 309.823999 120.108999) (xy 309.950002 120.29608)
				(xy 310.017228 120.246298) (xy 310.100395 120.191893) (xy 310.15325 120.176809) (xy 310.225676 120.171499)
			)
		)
	)
	(zone
		(net 293)
		(net_name "/2xUSB3.0+RJ45/GbE.MDI1+")
		(layer "F.Cu")
		(name "$teardrop_padvia$")
		(hatch none 0.1)
		(priority 31643)
		(attr
			(teardrop
				(type padvia)
			)
		)
		(connect_pads yes
			(clearance 0)
		)
		(min_thickness 0.0254)
		(filled_areas_thickness no)
		(fill yes
			(thermal_gap 0.5)
			(thermal_bridge_width 0.5)
			(island_removal_mode 1)
			(island_area_min 10)
		)
		(polygon
			(pts
				(xy 170.35 163.657916) (xy 170.345244 163.697838) (xy 170.33195 163.726255) (xy 170.287871 163.758671)
				(xy 170.242738 163.773949) (xy 170.196459 163.789244) (xy 170.149997 163.812919) (xy 170.275 164.001)
				(xy 170.495677 164.001757) (xy 170.497797 163.863281) (xy 170.5 163.657916)
			)
		)
	)
	(zone
		(net 73)
		(net_name "+3V3_AON")
		(layer "F.Cu")
		(name "$teardrop_padvia$")
		(hatch none 0.1)
		(priority 30963)
		(attr
			(teardrop
				(type padvia)
			)
		)
		(connect_pads yes
			(clearance 0)
		)
		(min_thickness 0.0254)
		(filled_areas_thickness no)
		(fill yes
			(thermal_gap 0.5)
			(thermal_bridge_width 0.5)
			(island_removal_mode 1)
			(island_area_min 10)
		)
		(polygon
			(pts
				(xy 245.912 127.8925) (xy 245.974866 127.912469) (xy 246.006844 127.938921) (xy 246.035358 127.976332)
				(xy 246.057882 128.023527) (xy 246.073093 128.081167) (xy 246.073202 128.081798) (xy 246.351 127.83)
				(xy 246.073202 127.578202) (xy 246.058905 127.633635) (xy 246.037825 127.67952) (xy 246.01046 127.717201)
				(xy 245.979552 127.744434) (xy 245.946265 127.761472) (xy 245.913434 127.767489) (xy 245.912 127.7675)
			)
		)
	)
	(zone
		(net 542)
		(net_name "Net-(Q9-E)")
		(layer "F.Cu")
		(name "$teardrop_padvia$")
		(hatch none 0.1)
		(priority 30823)
		(attr
			(teardrop
				(type padvia)
			)
		)
		(connect_pads yes
			(clearance 0)
		)
		(min_thickness 0.0254)
		(filled_areas_thickness no)
		(fill yes
			(thermal_gap 0.5)
			(thermal_bridge_width 0.5)
			(island_removal_mode 1)
			(island_area_min 10)
		)
		(polygon
			(pts
				(xy 255.344 83.767499) (xy 255.317391 83.762136) (xy 255.292117 83.744599) (xy 255.274478 83.718305)
				(xy 255.26305 83.680159) (xy 255.26 83.640999) (xy 254.699 83.83) (xy 255.26 84.018999) (xy 255.264627 83.971636)
				(xy 255.277018 83.936588) (xy 255.294877 83.91265) (xy 255.316015 83.898453) (xy 255.344 83.892499)
			)
		)
	)
	(zone
		(net 752)
		(net_name "Net-(U45C-CLKOUTB+)")
		(layer "F.Cu")
		(name "$teardrop_padvia$")
		(hatch none 0.1)
		(priority 30140)
		(attr
			(teardrop
				(type padvia)
			)
		)
		(connect_pads yes
			(clearance 0)
		)
		(min_thickness 0.0254)
		(filled_areas_thickness no)
		(fill yes
			(thermal_gap 0.5)
			(thermal_bridge_width 0.5)
			(island_removal_mode 1)
			(island_area_min 10)
		)
		(polygon
			(pts
				(xy 138.716396 129.988007) (xy 138.661775 129.926577) (xy 138.625259 129.87068) (xy 138.592229 129.771809)
				(xy 138.58498 129.668095) (xy 138.581201 129.5849) (xy 138.567794 129.486841) (xy 138.199293 129.559293)
				(xy 138.126841 129.927794) (xy 138.280423 129.944169) (xy 138.308095 129.94498) (xy 138.387316 129.949032)
				(xy 138.462488 129.964488) (xy 138.540441 130.003043) (xy 138.628007 130.076396)
			)
		)
	)
	(zone
		(net 214)
		(net_name "/Com Express 7 Interfaces/PCIe_{B1x4}.RX2+")
		(layer "F.Cu")
		(name "$teardrop_padvia$")
		(hatch none 0.1)
		(priority 31553)
		(attr
			(teardrop
				(type padvia)
			)
		)
		(connect_pads yes
			(clearance 0)
		)
		(min_thickness 0.0254)
		(filled_areas_thickness no)
		(fill yes
			(thermal_gap 0.5)
			(thermal_bridge_width 0.5)
			(island_removal_mode 1)
			(island_area_min 10)
		)
		(polygon
			(pts
				(xy 206.151566 161.838768) (xy 206.185081 161.798525) (xy 206.204567 161.760225) (xy 206.212239 161.687898)
				(xy 206.194359 161.609672) (xy 206.175685 161.531677) (xy 206.177177 161.443895) (xy 205.957207 161.399293)
				(xy 205.831497 161.587081) (xy 205.89823 161.613397) (xy 205.936537 161.622567) (xy 206.014091 161.64737)
				(xy 206.026027 161.666984) (xy 206.008731 161.695933)
			)
		)
	)
	(zone
		(net 270)
		(net_name "/M.2 key M #2/~{PERST_D}")
		(layer "F.Cu")
		(name "$teardrop_padvia$")
		(hatch none 0.1)
		(priority 31309)
		(attr
			(teardrop
				(type padvia)
			)
		)
		(connect_pads yes
			(clearance 0)
		)
		(min_thickness 0.0254)
		(filled_areas_thickness no)
		(fill yes
			(thermal_gap 0.5)
			(thermal_bridge_width 0.5)
			(island_removal_mode 1)
			(island_area_min 10)
		)
		(polygon
			(pts
				(xy 298.3865 83.141628) (xy 298.381596 83.167608) (xy 298.36727 83.189191) (xy 298.309931 83.220804)
				(xy 298.191995 83.237479) (xy 298.074143 83.235) (xy 298.2 83.531) (xy 298.52 83.3825) (xy 298.50284 83.319009)
				(xy 298.507298 83.201639) (xy 298.5115 83.141628)
			)
		)
	)
	(zone
		(net 41)
		(net_name "Net-(BT1-+)")
		(layer "F.Cu")
		(name "$teardrop_padvia$")
		(hatch none 0.1)
		(priority 30179)
		(attr
			(teardrop
				(type padvia)
			)
		)
		(connect_pads yes
			(clearance 0)
		)
		(min_thickness 0.0254)
		(filled_areas_thickness no)
		(fill yes
			(thermal_gap 0.5)
			(thermal_bridge_width 0.5)
			(island_removal_mode 1)
			(island_area_min 10)
		)
		(polygon
			(pts
				(xy 310.3 74.085) (xy 310.308478 74.026502) (xy 310.322989 73.997223) (xy 310.347827 73.971102)
				(xy 310.381272 73.952219) (xy 310.427168 73.939602) (xy 310.4875 73.935) (xy 310.15 73.559) (xy 309.8125 73.935)
				(xy 309.873398 73.939698) (xy 309.919609 73.952581) (xy 309.952128 73.971067) (xy 309.974612 73.993854)
				(xy 309.997553 74.051242) (xy 310 74.085)
			)
		)
	)
	(zone
		(net 1)
		(net_name "GND")
		(layer "F.Cu")
		(name "$teardrop_padvia$")
		(hatch none 0.1)
		(priority 30449)
		(attr
			(teardrop
				(type padvia)
			)
		)
		(connect_pads yes
			(clearance 0)
		)
		(min_thickness 0.0254)
		(filled_areas_thickness no)
		(fill yes
			(thermal_gap 0.5)
			(thermal_bridge_width 0.5)
			(island_removal_mode 1)
			(island_area_min 10)
		)
		(polygon
			(pts
				(xy 231.708707 77.622) (xy 231.672477 77.61921) (xy 231.636631 77.604678) (xy 231.60659 77.569163)
				(xy 231.587777 77.503424) (xy 231.584248 77.455031) (xy 231.269707 77.635) (xy 231.443207 77.93)
				(xy 231.497694 77.897419) (xy 231.569799 77.895055) (xy 231.638397 77.909387) (xy 231.708707 77.922)
			)
		)
	)
	(zone
		(net 1)
		(net_name "GND")
		(layer "F.Cu")
		(name "$teardrop_padvia$")
		(hatch none 0.1)
		(priority 30944)
		(attr
			(teardrop
				(type padvia)
			)
		)
		(connect_pads yes
			(clearance 0)
		)
		(min_thickness 0.0254)
		(filled_areas_thickness no)
		(fill yes
			(thermal_gap 0.5)
			(thermal_bridge_width 0.5)
			(island_removal_mode 1)
			(island_area_min 10)
		)
		(polygon
			(pts
				(xy 142.4575 133.442) (xy 142.437531 133.504866) (xy 142.411079 133.536844) (xy 142.373668 133.565358)
				(xy 142.326473 133.587882) (xy 142.268833 133.603093) (xy 142.268202 133.603202) (xy 142.52 133.881)
				(xy 142.771798 133.603202) (xy 142.716365 133.588905) (xy 142.67048 133.567825) (xy 142.632799 133.54046)
				(xy 142.605566 133.509552) (xy 142.588528 133.476265) (xy 142.582511 133.443434) (xy 142.5825 133.442)
			)
		)
	)
	(zone
		(net 65)
		(net_name "+12V")
		(layer "F.Cu")
		(name "$teardrop_padvia$")
		(hatch none 0.1)
		(priority 30084)
		(attr
			(teardrop
				(type padvia)
			)
		)
		(connect_pads yes
			(clearance 0)
		)
		(min_thickness 0.0254)
		(filled_areas_thickness no)
		(fill yes
			(thermal_gap 0.5)
			(thermal_bridge_width 0.5)
			(island_removal_mode 1)
			(island_area_min 10)
		)
		(polygon
			(pts
				(xy 193.80861 73.469957) (xy 193.813461 73.37858) (xy 193.827419 73.306651) (xy 193.87436 73.2051)
				(xy 193.93378 73.126257) (xy 194.020411 73.010502) (xy 193.70861 72.801163) (xy 193.396809 73.010502)
				(xy 193.48344 73.126258) (xy 193.53478 73.19314) (xy 193.574276 73.262875) (xy 193.599646 73.350226)
				(xy 193.60861 73.469957)
			)
		)
	)
	(zone
		(net 290)
		(net_name "/2xUSB3.0+RJ45/GbE.MDI2+")
		(layer "F.Cu")
		(name "$teardrop_padvia$")
		(hatch none 0.1)
		(priority 31664)
		(attr
			(teardrop
				(type padvia)
			)
		)
		(connect_pads yes
			(clearance 0)
		)
		(min_thickness 0.0254)
		(filled_areas_thickness no)
		(fill yes
			(thermal_gap 0.5)
			(thermal_bridge_width 0.5)
			(island_removal_mode 1)
			(island_area_min 10)
		)
		(polygon
			(pts
				(xy 135.363288 107.3525) (xy 135.260773 107.408442) (xy 135.105831 107.445859) (xy 134.903512 107.455)
				(xy 134.894 107.625) (xy 135.32 107.611714) (xy 135.322021 107.565866) (xy 135.332225 107.535644)
				(xy 135.363288 107.5025)
			)
		)
	)
	(zone
		(net 14)
		(net_name "/Com Express 7 Interfaces/PCIe_{B1x2}.RX0+")
		(layer "F.Cu")
		(name "$teardrop_padvia$")
		(hatch none 0.1)
		(priority 30383)
		(attr
			(teardrop
				(type padvia)
			)
		)
		(connect_pads yes
			(clearance 0)
		)
		(min_thickness 0.0254)
		(filled_areas_thickness no)
		(fill yes
			(thermal_gap 0.5)
			(thermal_bridge_width 0.5)
			(island_removal_mode 1)
			(island_area_min 10)
		)
		(polygon
			(pts
				(xy 154.4085 81.403) (xy 154.252972 81.414103) (xy 154.048818 81.428717) (xy 153.928693 81.42568)
				(xy 153.793966 81.4095) (xy 153.5725 81.5595) (xy 154.3485 81.643279) (xy 154.352977 81.61269) (xy 154.364318 81.599799)
				(xy 154.394331 81.601976) (xy 154.4085 81.605)
			)
		)
	)
	(zone
		(net 1)
		(net_name "GND")
		(layer "F.Cu")
		(name "$teardrop_padvia$")
		(hatch none 0.1)
		(priority 30616)
		(attr
			(teardrop
				(type padvia)
			)
		)
		(connect_pads yes
			(clearance 0)
		)
		(min_thickness 0.0254)
		(filled_areas_thickness no)
		(fill yes
			(thermal_gap 0.5)
			(thermal_bridge_width 0.5)
			(island_removal_mode 1)
			(island_area_min 10)
		)
		(polygon
			(pts
				(xy 179.425 150.2) (xy 179.428333 150.214486) (xy 179.43119 150.24461) (xy 179.419036 150.255651)
				(xy 179.39 150.26) (xy 179.525 151.136) (xy 179.66 150.26) (xy 179.630666 150.255525) (xy 179.618642 150.244199)
				(xy 179.621667 150.214486) (xy 179.625 150.2)
			)
		)
	)
	(zone
		(net 931)
		(net_name "/2xSFP+/SFP0_LEDG")
		(layer "F.Cu")
		(name "$teardrop_padvia$")
		(hatch none 0.1)
		(priority 30949)
		(attr
			(teardrop
				(type padvia)
			)
		)
		(connect_pads yes
			(clearance 0)
		)
		(min_thickness 0.0254)
		(filled_areas_thickness no)
		(fill yes
			(thermal_gap 0.5)
			(thermal_bridge_width 0.5)
			(island_removal_mode 1)
			(island_area_min 10)
		)
		(polygon
			(pts
				(xy 154.7565 159.672) (xy 154.736531 159.734866) (xy 154.710079 159.766844) (xy 154.672668 159.795358)
				(xy 154.625473 159.817882) (xy 154.567833 159.833093) (xy 154.567202 159.833202) (xy 154.819 160.111)
				(xy 155.070798 159.833202) (xy 155.015365 159.818905) (xy 154.96948 159.797825) (xy 154.931799 159.77046)
				(xy 154.904566 159.739552) (xy 154.887528 159.706265) (xy 154.881511 159.673434) (xy 154.8815 159.672)
			)
		)
	)
	(zone
		(net 2)
		(net_name "+3V3")
		(layer "F.Cu")
		(name "$teardrop_padvia$")
		(hatch none 0.1)
		(priority 30397)
		(attr
			(teardrop
				(type padvia)
			)
		)
		(connect_pads yes
			(clearance 0)
		)
		(min_thickness 0.0254)
		(filled_areas_thickness no)
		(fill yes
			(thermal_gap 0.5)
			(thermal_bridge_width 0.5)
			(island_removal_mode 1)
			(island_area_min 10)
		)
		(polygon
			(pts
				(xy 194.088245 138.209256) (xy 194.042249 138.192114) (xy 194.005222 138.181699) (xy 193.976204 138.164806)
				(xy 193.967286 138.135949) (xy 193.990556 138.089645) (xy 193.618726 138.09329) (xy 193.615082 138.465119)
				(xy 193.648961 138.445127) (xy 193.673832 138.442046) (xy 193.700221 138.4642) (xy 193.71755 138.516812)
				(xy 193.734692 138.562808)
			)
		)
	)
	(zone
		(net 1)
		(net_name "GND")
		(layer "F.Cu")
		(name "$teardrop_padvia$")
		(hatch none 0.1)
		(priority 30600)
		(attr
			(teardrop
				(type padvia)
			)
		)
		(connect_pads yes
			(clearance 0)
		)
		(min_thickness 0.0254)
		(filled_areas_thickness no)
		(fill yes
			(thermal_gap 0.5)
			(thermal_bridge_width 0.5)
			(island_removal_mode 1)
			(island_area_min 10)
		)
		(polygon
			(pts
				(xy 191.125 152.07) (xy 191.121667 152.055514) (xy 191.11881 152.02539) (xy 191.130964 152.014349)
				(xy 191.16 152.01) (xy 191.025 151.134) (xy 190.89 152.01) (xy 190.919334 152.014475) (xy 190.931358 152.025801)
				(xy 190.928333 152.055514) (xy 190.925 152.07)
			)
		)
	)
	(zone
		(net 2)
		(net_name "+3V3")
		(layer "F.Cu")
		(name "$teardrop_padvia$")
		(hatch none 0.1)
		(priority 31045)
		(attr
			(teardrop
				(type padvia)
			)
		)
		(connect_pads yes
			(clearance 0)
		)
		(min_thickness 0.0254)
		(filled_areas_thickness no)
		(fill yes
			(thermal_gap 0.5)
			(thermal_bridge_width 0.5)
			(island_removal_mode 1)
			(island_area_min 10)
		)
		(polygon
			(pts
				(xy 192.264264 139.479572) (xy 192.31897 139.452603) (xy 192.401556 139.458786) (xy 192.452635 139.47855)
				(xy 192.506892 139.510729) (xy 192.527146 139.525656) (xy 192.55948 139.15395) (xy 192.184999 139.172335)
				(xy 192.216444 139.251671) (xy 192.211268 139.329054) (xy 192.175876 139.391184)
			)
		)
	)
	(zone
		(net 528)
		(net_name "/Backplane/~{PERST}")
		(layer "F.Cu")
		(name "$teardrop_padvia$")
		(hatch none 0.1)
		(priority 32115)
		(attr
			(teardrop
				(type padvia)
			)
		)
		(connect_pads yes
			(clearance 0)
		)
		(min_thickness 0.0254)
		(filled_areas_thickness no)
		(fill yes
			(thermal_gap 0.5)
			(thermal_bridge_width 0.5)
			(island_removal_mode 1)
			(island_area_min 10)
		)
		(polygon
			(pts
				(xy 314.038 163.5225) (xy 314.044322 163.522404) (xy 314.083825 163.527989) (xy 314.102047 163.542922)
				(xy 314.114995 163.5725) (xy 314.364 163.46) (xy 314.114995 163.3475) (xy 314.103879 163.374493)
				(xy 314.088352 163.389595) (xy 314.044322 163.397596) (xy 314.038 163.3975)
			)
		)
	)
	(zone
		(net 969)
		(net_name "/M.2 key M #1/M2_3V3")
		(layer "F.Cu")
		(hatch edge 0.5)
		(priority 26)
		(connect_pads yes
			(clearance 0.15)
		)
		(min_thickness 0.25)
		(filled_areas_thickness no)
		(fill yes
			(thermal_gap 0.2)
			(thermal_bridge_width 0.5)
			(smoothing fillet)
			(radius 0.2)
		)
		(polygon
			(pts
				(xy 178.75 94.61) (xy 177.599999 94.61) (xy 177.6 98.11) (xy 178.75 98.11)
			)
		)
	)
	(zone
		(net 1)
		(net_name "GND")
		(layer "F.Cu")
		(name "$teardrop_padvia$")
		(hatch none 0.1)
		(priority 30789)
		(attr
			(teardrop
				(type padvia)
			)
		)
		(connect_pads yes
			(clearance 0)
		)
		(min_thickness 0.0254)
		(filled_areas_thickness no)
		(fill yes
			(thermal_gap 0.5)
			(thermal_bridge_width 0.5)
			(island_removal_mode 1)
			(island_area_min 10)
		)
		(polygon
			(pts
				(xy 152.969177 84.9095) (xy 152.811606 84.902569) (xy 152.698078 84.874049) (xy 152.656278 84.857)
				(xy 152.5675 85.0595) (xy 152.656278 85.262) (xy 152.752317 85.227618) (xy 152.854189 85.2124) (xy 152.969177 85.2095)
			)
		)
	)
	(zone
		(net 741)
		(net_name "Net-(U45C-REFCLK1-)")
		(layer "F.Cu")
		(name "$teardrop_padvia$")
		(hatch none 0.1)
		(priority 30091)
		(attr
			(teardrop
				(type padvia)
			)
		)
		(connect_pads yes
			(clearance 0)
		)
		(min_thickness 0.0254)
		(filled_areas_thickness no)
		(fill yes
			(thermal_gap 0.5)
			(thermal_bridge_width 0.5)
			(island_removal_mode 1)
			(island_area_min 10)
		)
		(polygon
			(pts
				(xy 126.415546 130.222842) (xy 126.617689 130.009688) (xy 126.770523 129.808065) (xy 126.781153 129.793311)
				(xy 126.792301 129.777838) (xy 126.490707 129.559293) (xy 126.12941 129.650553) (xy 126.169913 129.740989)
				(xy 126.248653 129.835509) (xy 126.276915 129.863876) (xy 126.337501 129.927577) (xy 126.376565 129.990556)
				(xy 126.383106 130.023345) (xy 126.378364 130.057839) (xy 126.360371 130.094666) (xy 126.327158 130.134454)
			)
		)
	)
	(zone
		(net 212)
		(net_name "/Com Express 7 Interfaces/PCIe_{B1x4}.TX3+")
		(layer "F.Cu")
		(name "$teardrop_padvia$")
		(hatch none 0.1)
		(priority 30255)
		(attr
			(teardrop
				(type padvia)
			)
		)
		(connect_pads yes
			(clearance 0)
		)
		(min_thickness 0.0254)
		(filled_areas_thickness no)
		(fill yes
			(thermal_gap 0.5)
			(thermal_bridge_width 0.5)
			(island_removal_mode 1)
			(island_area_min 10)
		)
		(polygon
			(pts
				(xy 204.4795 167.75) (xy 204.48258 167.764227) (xy 204.484749 167.794527) (xy 204.471877 167.805628)
				(xy 204.441705 167.81) (xy 204.525 168.686) (xy 204.675 168.437021) (xy 204.655644 168.195818) (xy 204.670401 167.923112)
				(xy 204.6815 167.75)
			)
		)
	)
	(zone
		(net 746)
		(net_name "/2xSFP+/KR to SFI #2/~{TRST}")
		(layer "F.Cu")
		(name "$teardrop_padvia$")
		(hatch none 0.1)
		(priority 31697)
		(attr
			(teardrop
				(type padvia)
			)
		)
		(connect_pads yes
			(clearance 0)
		)
		(min_thickness 0.0254)
		(filled_areas_thickness no)
		(fill yes
			(thermal_gap 0.5)
			(thermal_bridge_width 0.5)
			(island_removal_mode 1)
			(island_area_min 10)
		)
		(polygon
			(pts
				(xy 132.9275 130.109323) (xy 132.922682 130.178763) (xy 132.90896 130.230087) (xy 132.862245 130.305628)
				(xy 132.852702 130.317768) (xy 132.802919 130.384997) (xy 132.99 130.511) (xy 133.177081 130.384997)
				(xy 133.127299 130.317769) (xy 133.072894 130.234603) (xy 133.05781 130.181748) (xy 133.0525 130.109323)
			)
		)
	)
	(zone
		(net 430)
		(net_name "/2xSFP+/MDIO0.MDC")
		(layer "F.Cu")
		(name "$teardrop_padvia$")
		(hatch none 0.1)
		(priority 31992)
		(attr
			(teardrop
				(type padvia)
			)
		)
		(connect_pads yes
			(clearance 0)
		)
		(min_thickness 0.0254)
		(filled_areas_thickness no)
		(fill yes
			(thermal_gap 0.5)
			(thermal_bridge_width 0.5)
			(island_removal_mode 1)
			(island_area_min 10)
		)
		(polygon
			(pts
				(xy 144.119 147.2375) (xy 144.095833 147.232537) (xy 144.076857 147.217794) (xy 144.050169 147.157017)
				(xy 144.039 147.028621) (xy 143.838 147.11) (xy 144.018176 147.449113) (xy 144.027496 147.415584)
				(xy 144.043085 147.391828) (xy 144.087718 147.36626) (xy 144.119 147.3625)
			)
		)
	)
	(zone
		(net 339)
		(net_name "/Com Express 7 Interfaces/SDIO.CLK")
		(layer "F.Cu")
		(name "$teardrop_padvia$")
		(hatch none 0.1)
		(priority 30624)
		(attr
			(teardrop
				(type padvia)
			)
		)
		(connect_pads yes
			(clearance 0)
		)
		(min_thickness 0.0254)
		(filled_areas_thickness no)
		(fill yes
			(thermal_gap 0.5)
			(thermal_bridge_width 0.5)
			(island_removal_mode 1)
			(island_area_min 10)
		)
		(polygon
			(pts
				(xy 222.116 169.62) (xy 222.114282 169.607584) (xy 222.115106 169.576206) (xy 222.129162 169.56459)
				(xy 222.16 169.56) (xy 222.025 168.684) (xy 221.89 169.56) (xy 221.920565 169.564481) (xy 221.934698 169.575851)
				(xy 221.935718 169.607584) (xy 221.934 169.62)
			)
		)
	)
	(zone
		(net 1)
		(net_name "GND")
		(layer "F.Cu")
		(name "$teardrop_padvia$")
		(hatch none 0.1)
		(priority 30230)
		(attr
			(teardrop
				(type padvia)
			)
		)
		(connect_pads yes
			(clearance 0)
		)
		(min_thickness 0.0254)
		(filled_areas_thickness no)
		(fill yes
			(thermal_gap 0.5)
			(thermal_bridge_width 0.5)
			(island_removal_mode 1)
			(island_area_min 10)
		)
		(polygon
			(pts
				(xy 196.05 152.07) (xy 196.047272 152.056152) (xy 196.045933 152.025611) (xy 196.059368 152.014412)
				(xy 196.090241 152.01) (xy 196.025 151.134) (xy 195.875 151.315795) (xy 195.886563 151.578482) (xy 195.865463 151.86173)
				(xy 195.85 152.07)
			)
		)
	)
	(zone
		(net 556)
		(net_name "/2xUSB3.0+RJ45/EN_2B")
		(layer "F.Cu")
		(name "$teardrop_padvia$")
		(hatch none 0.1)
		(priority 30077)
		(attr
			(teardrop
				(type padvia)
			)
		)
		(connect_pads yes
			(clearance 0)
		)
		(min_thickness 0.0254)
		(filled_areas_thickness no)
		(fill yes
			(thermal_gap 0.5)
			(thermal_bridge_width 0.5)
			(island_removal_mode 1)
			(island_area_min 10)
		)
		(polygon
			(pts
				(xy 118.939 92.6515) (xy 118.883736 92.632104) (xy 118.834452 92.570761) (xy 118.802899 92.462049)
				(xy 118.799 92.399) (xy 118.198 92.714) (xy 118.799 93.029) (xy 118.803756 92.959663) (xy 118.817044 92.900293)
				(xy 118.837444 92.851557) (xy 118.863462 92.814336) (xy 118.891726 92.79052) (xy 118.922426 92.778176)
				(xy 118.939 92.7765)
			)
		)
	)
	(zone
		(net 400)
		(net_name "/Com Express 7 MGMT/FAN_PWM")
		(layer "F.Cu")
		(name "$teardrop_padvia$")
		(hatch none 0.1)
		(priority 31766)
		(attr
			(teardrop
				(type padvia)
			)
		)
		(connect_pads yes
			(clearance 0)
		)
		(min_thickness 0.0254)
		(filled_areas_thickness no)
		(fill yes
			(thermal_gap 0.5)
			(thermal_bridge_width 0.5)
			(island_removal_mode 1)
			(island_area_min 10)
		)
		(polygon
			(pts
				(xy 241.020031 77.2475) (xy 241.089472 77.252318) (xy 241.140796 77.26604) (xy 241.216337 77.312755)
				(xy 241.228477 77.322299) (xy 241.295705 77.372081) (xy 241.421708 77.185) (xy 241.295705 76.997919)
				(xy 241.228476 77.047702) (xy 241.14531 77.102106) (xy 241.092456 77.11719) (xy 241.020031 77.1225)
			)
		)
	)
	(zone
		(net 330)
		(net_name "/Com Express 7 Interfaces/PCIe_{B2Ax4}.TX3+")
		(layer "F.Cu")
		(name "$teardrop_padvia$")
		(hatch none 0.1)
		(priority 30368)
		(attr
			(teardrop
				(type padvia)
			)
		)
		(connect_pads yes
			(clearance 0)
		)
		(min_thickness 0.0254)
		(filled_areas_thickness no)
		(fill yes
			(thermal_gap 0.5)
			(thermal_bridge_width 0.5)
			(island_removal_mode 1)
			(island_area_min 10)
		)
		(polygon
			(pts
				(xy 288.6525 73.2) (xy 288.655524 73.214169) (xy 288.657552 73.244507) (xy 288.644562 73.255622)
				(xy 288.61422 73.26) (xy 288.698 74.036) (xy 288.848 73.814533) (xy 288.828652 73.60088) (xy 288.843397 73.355527)
				(xy 288.8545 73.2)
			)
		)
	)
	(zone
		(net 2)
		(net_name "+3V3")
		(layer "F.Cu")
		(name "$teardrop_padvia$")
		(hatch none 0.1)
		(priority 30805)
		(attr
			(teardrop
				(type padvia)
			)
		)
		(connect_pads yes
			(clearance 0)
		)
		(min_thickness 0.0254)
		(filled_areas_thickness no)
		(fill yes
			(thermal_gap 0.5)
			(thermal_bridge_width 0.5)
			(island_removal_mode 1)
			(island_area_min 10)
		)
		(polygon
			(pts
				(xy 310.324999 83.680677) (xy 310.33193 83.523106) (xy 310.360451 83.409578) (xy 310.3775 83.367778)
				(xy 310.175 83.279001) (xy 309.9725 83.367778) (xy 310.006883 83.463822) (xy 310.022101 83.565701)
				(xy 310.025 83.680676)
			)
		)
	)
	(zone
		(net 1)
		(net_name "GND")
		(layer "F.Cu")
		(name "$teardrop_padvia$")
		(hatch none 0.1)
		(priority 31929)
		(attr
			(teardrop
				(type padvia)
			)
		)
		(connect_pads yes
			(clearance 0)
		)
		(min_thickness 0.0254)
		(filled_areas_thickness no)
		(fill yes
			(thermal_gap 0.5)
			(thermal_bridge_width 0.5)
			(island_removal_mode 1)
			(island_area_min 10)
		)
		(polygon
			(pts
				(xy 112.89 132.31) (xy 112.879885 132.310153) (xy 112.849169 132.30954) (xy 112.81668 132.301218)
				(xy 112.787526 132.277325) (xy 112.766809 132.23) (xy 112.534 132.41) (xy 112.766809 132.59) (xy 112.780168 132.554099)
				(xy 112.798399 132.530801) (xy 112.843725 132.511101) (xy 112.879885 132.509847) (xy 112.89 132.51)
			)
		)
	)
	(zone
		(net 564)
		(net_name "/2xSFP+/~{LED0_2}")
		(layer "F.Cu")
		(name "$teardrop_padvia$")
		(hatch none 0.1)
		(priority 31312)
		(attr
			(teardrop
				(type padvia)
			)
		)
		(connect_pads yes
			(clearance 0)
		)
		(min_thickness 0.0254)
		(filled_areas_thickness no)
		(fill yes
			(thermal_gap 0.5)
			(thermal_bridge_width 0.5)
			(island_removal_mode 1)
			(island_area_min 10)
		)
		(polygon
			(pts
				(xy 156.166704 160.2975) (xy 156.140742 160.292596) (xy 156.1192 160.27827) (xy 156.087743 160.220972)
				(xy 156.0713 160.103051) (xy 156.074 159.984703) (xy 155.778 160.11) (xy 155.9265 160.43) (xy 155.989738 160.413254)
				(xy 156.105925 160.418106) (xy 156.166704 160.4225)
			)
		)
	)
	(zone
		(net 1)
		(net_name "GND")
		(layer "F.Cu")
		(name "$teardrop_padvia$")
		(hatch none 0.1)
		(priority 30608)
		(attr
			(teardrop
				(type padvia)
			)
		)
		(connect_pads yes
			(clearance 0)
		)
		(min_thickness 0.0254)
		(filled_areas_thickness no)
		(fill yes
			(thermal_gap 0.5)
			(thermal_bridge_width 0.5)
			(island_removal_mode 1)
			(island_area_min 10)
		)
		(polygon
			(pts
				(xy 213.425 167.75) (xy 213.428333 167.764486) (xy 213.43119 167.79461) (xy 213.419036 167.805651)
				(xy 213.39 167.81) (xy 213.525 168.686) (xy 213.66 167.81) (xy 213.630666 167.805525) (xy 213.618642 167.794199)
				(xy 213.621667 167.764486) (xy 213.625 167.75)
			)
		)
	)
	(zone
		(net 1)
		(net_name "GND")
		(layer "F.Cu")
		(name "$teardrop_padvia$")
		(hatch none 0.1)
		(priority 30781)
		(attr
			(teardrop
				(type padvia)
			)
		)
		(connect_pads yes
			(clearance 0)
		)
		(min_thickness 0.0254)
		(filled_areas_thickness no)
		(fill yes
			(thermal_gap 0.5)
			(thermal_bridge_width 0.5)
			(island_removal_mode 1)
			(island_area_min 10)
		)
		(polygon
			(pts
				(xy 152.969177 87.9085) (xy 152.811606 87.901569) (xy 152.698078 87.873049) (xy 152.656278 87.856)
				(xy 152.5675 88.0585) (xy 152.656278 88.261) (xy 152.752317 88.226618) (xy 152.854189 88.2114) (xy 152.969177 88.2085)
			)
		)
	)
	(zone
		(net 1)
		(net_name "GND")
		(layer "F.Cu")
		(name "$teardrop_padvia$")
		(hatch none 0.1)
		(priority 30782)
		(attr
			(teardrop
				(type padvia)
			)
		)
		(connect_pads yes
			(clearance 0)
		)
		(min_thickness 0.0254)
		(filled_areas_thickness no)
		(fill yes
			(thermal_gap 0.5)
			(thermal_bridge_width 0.5)
			(island_removal_mode 1)
			(island_area_min 10)
		)
		(polygon
			(pts
				(xy 145.471177 75.1585) (xy 145.313606 75.151569) (xy 145.200078 75.123049) (xy 145.158278 75.106)
				(xy 145.0695 75.3085) (xy 145.158278 75.511) (xy 145.254317 75.476618) (xy 145.356189 75.4614) (xy 145.471177 75.4585)
			)
		)
	)
	(zone
		(net 687)
		(net_name "/2xSFP+/KR to SFI #2/KR_R.RX+")
		(layer "F.Cu")
		(name "$teardrop_padvia$")
		(hatch none 0.1)
		(priority 31967)
		(attr
			(teardrop
				(type padvia)
			)
		)
		(connect_pads yes
			(clearance 0)
		)
		(min_thickness 0.0254)
		(filled_areas_thickness no)
		(fill yes
			(thermal_gap 0.5)
			(thermal_bridge_width 0.5)
			(island_removal_mode 1)
			(island_area_min 10)
		)
		(polygon
			(pts
				(xy 134.9 146.717279) (xy 134.924062 146.786651) (xy 134.960577 146.896598) (xy 134.970888 146.956686)
				(xy 134.97 147.018536) (xy 135.17 146.991) (xy 135.228769 146.76) (xy 135.147423 146.765298) (xy 135.095406 146.756508)
				(xy 135.073886 146.742657) (xy 135.061647 146.722599) (xy 135.06 146.717279)
			)
		)
	)
	(zone
		(net 1)
		(net_name "GND")
		(layer "F.Cu")
		(name "$teardrop_padvia$")
		(hatch none 0.1)
		(priority 30059)
		(attr
			(teardrop
				(type padvia)
			)
		)
		(connect_pads yes
			(clearance 0)
		)
		(min_thickness 0.0254)
		(filled_areas_thickness no)
		(fill yes
			(thermal_gap 0.5)
			(thermal_bridge_width 0.5)
			(island_removal_mode 1)
			(island_area_min 10)
		)
		(polygon
			(pts
				(xy 225.380797 159.592929) (xy 225.452196 159.669014) (xy 225.523419 159.767054) (xy 225.578132 159.889855)
				(xy 225.594193 159.961417) (xy 225.6 160.040221) (xy 226.000707 159.900707) (xy 225.952944 159.4)
				(xy 225.88961 159.430426) (xy 225.831548 159.448076) (xy 225.729952 159.451687) (xy 225.64446 159.420878)
				(xy 225.592929 159.380797)
			)
		)
	)
	(zone
		(net 2)
		(net_name "+3V3")
		(layer "F.Cu")
		(name "$teardrop_padvia$")
		(hatch none 0.1)
		(priority 31849)
		(attr
			(teardrop
				(type padvia)
			)
		)
		(connect_pads yes
			(clearance 0)
		)
		(min_thickness 0.0254)
		(filled_areas_thickness no)
		(fill yes
			(thermal_gap 0.5)
			(thermal_bridge_width 0.5)
			(island_removal_mode 1)
			(island_area_min 10)
		)
		(polygon
			(pts
				(xy 121.739127 73.762485) (xy 121.686618 73.808181) (xy 121.640623 73.834768) (xy 121.554174 73.855152)
				(xy 121.538841 73.856988) (xy 121.456105 73.869323) (xy 121.499293 74.090707) (xy 121.720677 74.133895)
				(xy 121.733011 74.05116) (xy 121.753349 73.953881) (xy 121.780057 73.905841) (xy 121.827515 73.850873)
			)
		)
	)
	(zone
		(net 1)
		(net_name "GND")
		(layer "F.Cu")
		(name "$teardrop_padvia$")
		(hatch none 0.1)
		(priority 30585)
		(attr
			(teardrop
				(type padvia)
			)
		)
		(connect_pads yes
			(clearance 0)
		)
		(min_thickness 0.0254)
		(filled_areas_thickness no)
		(fill yes
			(thermal_gap 0.5)
			(thermal_bridge_width 0.5)
			(island_removal_mode 1)
			(island_area_min 10)
		)
		(polygon
			(pts
				(xy 199.625 157.62) (xy 199.621667 157.605514) (xy 199.61881 157.57539) (xy 199.630964 157.564349)
				(xy 199.66 157.56) (xy 199.525 156.684) (xy 199.39 157.56) (xy 199.419334 157.564475) (xy 199.431358 157.575801)
				(xy 199.428333 157.605514) (xy 199.425 157.62)
			)
		)
	)
	(zone
		(net 365)
		(net_name "/Com Express 7 MGMT/PWR_OK")
		(layer "F.Cu")
		(name "$teardrop_padvia$")
		(hatch none 0.1)
		(priority 31602)
		(attr
			(teardrop
				(type padvia)
			)
		)
		(connect_pads yes
			(clearance 0)
		)
		(min_thickness 0.0254)
		(filled_areas_thickness no)
		(fill yes
			(thermal_gap 0.5)
			(thermal_bridge_width 0.5)
			(island_removal_mode 1)
			(island_area_min 10)
		)
		(polygon
			(pts
				(xy 187.4625 163.899323) (xy 187.457831 163.969201) (xy 187.445144 164.022579) (xy 187.400666 164.109579)
				(xy 187.342355 164.224641) (xy 187.55 164.301) (xy 187.737081 164.174997) (xy 187.66863 164.092342)
				(xy 187.610755 164.017857) (xy 187.593685 163.967955) (xy 187.5875 163.899323)
			)
		)
	)
	(zone
		(net 552)
		(net_name "Net-(R17-Pad2)")
		(layer "F.Cu")
		(name "$teardrop_padvia$")
		(hatch none 0.1)
		(priority 30334)
		(attr
			(teardrop
				(type padvia)
			)
		)
		(connect_pads yes
			(clearance 0)
		)
		(min_thickness 0.0254)
		(filled_areas_thickness no)
		(fill yes
			(thermal_gap 0.5)
			(thermal_bridge_width 0.5)
			(island_removal_mode 1)
			(island_area_min 10)
		)
		(polygon
			(pts
				(xy 135.845461 101.825961) (xy 135.89417 101.785415) (xy 135.957976 101.750465) (xy 136.016861 101.731669)
				(xy 136.084441 101.72303) (xy 136.175474 101.73) (xy 136.120707 101.409293) (xy 135.825 101.329526)
				(xy 135.819956 101.462711) (xy 135.781148 101.57805) (xy 135.714323 101.673873) (xy 135.704039 101.684539)
			)
		)
	)
	(zone
		(net 601)
		(net_name "Net-(U36-~{WP}(D2))")
		(layer "F.Cu")
		(name "$teardrop_padvia$")
		(hatch none 0.1)
		(priority 30068)
		(attr
			(teardrop
				(type padvia)
			)
		)
		(connect_pads yes
			(clearance 0)
		)
		(min_thickness 0.0254)
		(filled_areas_thickness no)
		(fill yes
			(thermal_gap 0.5)
			(thermal_bridge_width 0.5)
			(island_removal_mode 1)
			(island_area_min 10)
		)
		(polygon
			(pts
				(xy 257.4178 161.213814) (xy 257.395806 161.216142) (xy 257.375522 161.207798) (xy 257.339189 161.15877)
				(xy 257.30055 161.019595) (xy 256.522438 161.297707) (xy 257.312111 161.557101) (xy 257.344051 161.456496)
				(xy 257.409427 161.366578) (xy 257.452239 161.330526) (xy 257.494983 161.306495) (xy 257.506187 161.302201)
			)
		)
	)
	(zone
		(net 952)
		(net_name "/2xSFP+/KR to SFI #2/SFI_R.TX-")
		(layer "F.Cu")
		(name "$teardrop_padvia$")
		(hatch none 0.1)
		(priority 31953)
		(attr
			(teardrop
				(type padvia)
			)
		)
		(connect_pads yes
			(clearance 0)
		)
		(min_thickness 0.0254)
		(filled_areas_thickness no)
		(fill yes
			(thermal_gap 0.5)
			(thermal_bridge_width 0.5)
			(island_removal_mode 1)
			(island_area_min 10)
		)
		(polygon
			(pts
				(xy 128.52 146.717279) (xy 128.508264 146.740315) (xy 128.485802 146.756014) (xy 128.409443 146.765137)
				(xy 128.351231 146.76) (xy 128.41 146.991) (xy 128.61 147.018536) (xy 128.614353 146.919743) (xy 128.655938 146.786651)
				(xy 128.68 146.717279)
			)
		)
	)
	(zone
		(net 736)
		(net_name "Net-(U43A-LS_OK_{OUT_A})")
		(layer "F.Cu")
		(name "$teardrop_padvia$")
		(hatch none 0.1)
		(priority 31687)
		(attr
			(teardrop
				(type padvia)
			)
		)
		(connect_pads yes
			(clearance 0)
		)
		(min_thickness 0.0254)
		(filled_areas_thickness no)
		(fill yes
			(thermal_gap 0.5)
			(thermal_bridge_width 0.5)
			(island_removal_mode 1)
			(island_area_min 10)
		)
		(polygon
			(pts
				(xy 150.4375 129.739323) (xy 150.432682 129.808763) (xy 150.41896 129.860087) (xy 150.372245 129.935628)
				(xy 150.362702 129.947768) (xy 150.312919 130.014997) (xy 150.5 130.141) (xy 150.687081 130.014997)
				(xy 150.637299 129.947769) (xy 150.582894 129.864603) (xy 150.56781 129.811748) (xy 150.5625 129.739323)
			)
		)
	)
	(zone
		(net 1)
		(net_name "GND")
		(layer "F.Cu")
		(name "$teardrop_padvia$")
		(hatch none 0.1)
		(priority 31828)
		(attr
			(teardrop
				(type padvia)
			)
		)
		(connect_pads yes
			(clearance 0)
		)
		(min_thickness 0.0254)
		(filled_areas_thickness no)
		(fill yes
			(thermal_gap 0.5)
			(thermal_bridge_width 0.5)
			(island_removal_mode 1)
			(island_area_min 10)
		)
		(polygon
			(pts
				(xy 113.290677 149.8175) (xy 113.221236 149.812682) (xy 113.169913 149.79896) (xy 113.094371 149.752246)
				(xy 113.082231 149.742701) (xy 113.015003 149.692919) (xy 112.889 149.88) (xy 113.015003 150.067081)
				(xy 113.082229 150.017299) (xy 113.165396 149.962894) (xy 113.218251 149.94781) (xy 113.290677 149.9425)
			)
		)
	)
	(zone
		(net 543)
		(net_name "Net-(Q10-B)")
		(layer "F.Cu")
		(name "$teardrop_padvia$")
		(hatch none 0.1)
		(priority 30822)
		(attr
			(teardrop
				(type padvia)
			)
		)
		(connect_pads yes
			(clearance 0)
		)
		(min_thickness 0.0254)
		(filled_areas_thickness no)
		(fill yes
			(thermal_gap 0.5)
			(thermal_bridge_width 0.5)
			(island_removal_mode 1)
			(island_area_min 10)
		)
		(polygon
			(pts
				(xy 255.344 85.667498) (xy 255.317391 85.662135) (xy 255.292117 85.644598) (xy 255.274478 85.618304)
				(xy 255.26305 85.580158) (xy 255.26 85.540998) (xy 254.699 85.73) (xy 255.26 85.918998) (xy 255.264627 85.871635)
				(xy 255.277018 85.836587) (xy 255.294877 85.812649) (xy 255.316015 85.798452) (xy 255.344 85.792498)
			)
		)
	)
	(zone
		(net 51)
		(net_name "Net-(C13-Pad1)")
		(layer "F.Cu")
		(name "$teardrop_padvia$")
		(hatch none 0.1)
		(priority 30141)
		(attr
			(teardrop
				(type padvia)
			)
		)
		(connect_pads yes
			(clearance 0)
		)
		(min_thickness 0.0254)
		(filled_areas_thickness no)
		(fill yes
			(thermal_gap 0.5)
			(thermal_bridge_width 0.5)
			(island_removal_mode 1)
			(island_area_min 10)
		)
		(polygon
			(pts
				(xy 130.066964 107.149095) (xy 130.122924 107.161039) (xy 130.185844 107.18655) (xy 130.236481 107.219075)
				(xy 130.280113 107.262912) (xy 130.305358 107.304461) (xy 130.321088 107.353508) (xy 130.325207 107.394182)
				(xy 130.770707 107.060707) (xy 130.325861 106.722533) (xy 130.325165 106.797411) (xy 130.318981 106.910239)
				(xy 130.305389 106.932778) (xy 130.279095 106.936964)
			)
		)
	)
	(zone
		(net 527)
		(net_name "/Backplane/GPIO")
		(layer "F.Cu")
		(name "$teardrop_padvia$")
		(hatch none 0.1)
		(priority 31789)
		(attr
			(teardrop
				(type padvia)
			)
		)
		(connect_pads yes
			(clearance 0)
		)
		(min_thickness 0.0254)
		(filled_areas_thickness no)
		(fill yes
			(thermal_gap 0.5)
			(thermal_bridge_width 0.5)
			(island_removal_mode 1)
			(island_area_min 10)
		)
		(polygon
			(pts
				(xy 130.4625 76.160677) (xy 130.467318 76.091236) (xy 130.48104 76.039912) (xy 130.527755 75.96437)
				(xy 130.537299 75.952229) (xy 130.587081 75.885003) (xy 130.4 75.759) (xy 130.212919 75.885003)
				(xy 130.262701 75.952231) (xy 130.317106 76.035397) (xy 130.33219 76.088251) (xy 130.3375 76.160677)
			)
		)
	)
	(zone
		(net 90)
		(net_name "/Com Express 7 Interfaces/PCIe_{B2Ax4}.RX0+")
		(layer "F.Cu")
		(name "$teardrop_padvia$")
		(hatch none 0.1)
		(priority 30509)
		(attr
			(teardrop
				(type padvia)
			)
		)
		(connect_pads yes
			(clearance 0)
		)
		(min_thickness 0.0254)
		(filled_areas_thickness no)
		(fill yes
			(thermal_gap 0.5)
			(thermal_bridge_width 0.5)
			(island_removal_mode 1)
			(island_area_min 10)
		)
		(polygon
			(pts
				(xy 211.126 164.07) (xy 211.122463 164.055322) (xy 211.119192 164.025315) (xy 211.131143 164.014327)
				(xy 211.16 164.01) (xy 211.025 163.134) (xy 210.89 164.01) (xy 210.919204 164.014475) (xy 210.930997 164.025797)
				(xy 210.927537 164.055322) (xy 210.924 164.07)
			)
		)
	)
	(zone
		(net 51)
		(net_name "Net-(C13-Pad1)")
		(layer "F.Cu")
		(name "$teardrop_padvia$")
		(hatch none 0.1)
		(priority 30472)
		(attr
			(teardrop
				(type padvia)
			)
		)
		(connect_pads yes
			(clearance 0)
		)
		(min_thickness 0.0254)
		(filled_areas_thickness no)
		(fill yes
			(thermal_gap 0.5)
			(thermal_bridge_width 0.5)
			(island_removal_mode 1)
			(island_area_min 10)
		)
		(polygon
			(pts
				(xy 129.938 102.75) (xy 129.92113 102.750338) (xy 129.876174 102.749759) (xy 129.828831 102.737941)
				(xy 129.786427 102.703362) (xy 129.756292 102.6345) (xy 129.499 102.9) (xy 129.756292 103.1655)
				(xy 129.771849 103.120731) (xy 129.792565 103.089115) (xy 129.843701 103.056381) (xy 129.92113 103.049662)
				(xy 129.938 103.05)
			)
		)
	)
	(zone
		(net 1)
		(net_name "GND")
		(layer "F.Cu")
		(name "$teardrop_padvia$")
		(hatch none 0.1)
		(priority 31246)
		(attr
			(teardrop
				(type padvia)
			)
		)
		(connect_pads yes
			(clearance 0)
		)
		(min_thickness 0.0254)
		(filled_areas_thickness no)
		(fill yes
			(thermal_gap 0.5)
			(thermal_bridge_width 0.5)
			(island_removal_mode 1)
			(island_area_min 10)
		)
		(polygon
			(pts
				(xy 97.402 151.699323) (xy 97.397288 151.776422) (xy 97.384301 151.834668) (xy 97.341418 151.925924)
				(xy 97.297945 152.011146) (xy 97.5 152.101) (xy 97.702938 152.013281) (xy 97.661024 151.928204)
				(xy 97.618886 151.834781) (xy 97.606488 151.776387) (xy 97.602 151.699323)
			)
		)
	)
	(zone
		(net 625)
		(net_name "/PCIe redriver/TX_EQ2")
		(layer "F.Cu")
		(name "$teardrop_padvia$")
		(hatch none 0.1)
		(priority 31107)
		(attr
			(teardrop
				(type padvia)
			)
		)
		(connect_pads yes
			(clearance 0)
		)
		(min_thickness 0.0254)
		(filled_areas_thickness no)
		(fill yes
			(thermal_gap 0.5)
			(thermal_bridge_width 0.5)
			(island_removal_mode 1)
			(island_area_min 10)
		)
		(polygon
			(pts
				(xy 115.3375 143.467) (xy 115.317727 143.526412) (xy 115.254453 143.582496) (xy 115.205828 143.604198)
				(xy 115.146469 143.618872) (xy 115.1345 143.620652) (xy 115.4 143.881) (xy 115.6655 143.620652)
				(xy 115.605362 143.607803) (xy 115.555478 143.587869) (xy 115.515358 143.561944) (xy 115.486345 143.532124)
				(xy 115.468854 143.500706) (xy 115.462521 143.468895) (xy 115.4625 143.467)
			)
		)
	)
	(zone
		(net 325)
		(net_name "/Com Express 7 Interfaces/PCIe_{B2Ax4}.TX0-")
		(layer "F.Cu")
		(name "$teardrop_padvia$")
		(hatch none 0.1)
		(priority 30516)
		(attr
			(teardrop
				(type padvia)
			)
		)
		(connect_pads yes
			(clearance 0)
		)
		(min_thickness 0.0254)
		(filled_areas_thickness no)
		(fill yes
			(thermal_gap 0.5)
			(thermal_bridge_width 0.5)
			(island_removal_mode 1)
			(island_area_min 10)
		)
		(polygon
			(pts
				(xy 211.424 167.75) (xy 211.427537 167.764678) (xy 211.430808 167.794685) (xy 211.418857 167.805673)
				(xy 211.39 167.81) (xy 211.525 168.686) (xy 211.66 167.81) (xy 211.630796 167.805525) (xy 211.619003 167.794203)
				(xy 211.622463 167.764678) (xy 211.626 167.75)
			)
		)
	)
	(zone
		(net 65)
		(net_name "+12V")
		(layer "F.Cu")
		(name "$teardrop_padvia$")
		(hatch none 0.1)
		(priority 30161)
		(attr
			(teardrop
				(type padvia)
			)
		)
		(connect_pads yes
			(clearance 0)
		)
		(min_thickness 0.0254)
		(filled_areas_thickness no)
		(fill yes
			(thermal_gap 0.5)
			(thermal_bridge_width 0.5)
			(island_removal_mode 1)
			(island_area_min 10)
		)
		(polygon
			(pts
				(xy 193.60861 73.542163) (xy 193.60355 73.575682) (xy 193.588129 73.608588) (xy 193.562347 73.6389)
				(xy 193.525738 73.665407) (xy 193.478562 73.68631) (xy 193.420127 73.700395) (xy 193.34861 73.706141)
				(xy 193.70861 74.103163) (xy 194.06861 73.706141) (xy 193.998539 73.700621) (xy 193.940004 73.686759)
				(xy 193.892657 73.666073) (xy 193.856184 73.640095) (xy 193.8301 73.610127) (xy 193.814368 73.577901)
				(xy 193.80861 73.542163)
			)
		)
	)
	(zone
		(net 772)
		(net_name "/Backplane/PCIe_{x2}.RX1-")
		(layer "F.Cu")
		(name "$teardrop_padvia$")
		(hatch none 0.1)
		(priority 31429)
		(attr
			(teardrop
				(type padvia)
			)
		)
		(connect_pads yes
			(clearance 0)
		)
		(min_thickness 0.0254)
		(filled_areas_thickness no)
		(fill yes
			(thermal_gap 0.5)
			(thermal_bridge_width 0.5)
			(island_removal_mode 1)
			(island_area_min 10)
		)
		(polygon
			(pts
				(xy 270.567496 160.0935) (xy 270.405964 160.098895) (xy 270.321554 160.102445) (xy 270.21986 160.097823)
				(xy 270.199 160.3185) (xy 270.348852 160.481731) (xy 270.402992 160.413062) (xy 270.412883 160.396608)
				(xy 270.437383 160.357935) (xy 270.46689 160.325721) (xy 270.508046 160.303673) (xy 270.567496 160.2955)
			)
		)
	)
	(zone
		(net 2)
		(net_name "+3V3")
		(layer "F.Cu")
		(name "$teardrop_padvia$")
		(hatch none 0.1)
		(priority 30980)
		(attr
			(teardrop
				(type padvia)
			)
		)
		(connect_pads yes
			(clearance 0)
		)
		(min_thickness 0.0254)
		(filled_areas_thickness no)
		(fill yes
			(thermal_gap 0.5)
			(thermal_bridge_width 0.5)
			(island_removal_mode 1)
			(island_area_min 10)
		)
		(polygon
			(pts
				(xy 178.912 103.4525) (xy 178.974866 103.472469) (xy 179.006844 103.498921) (xy 179.035358 103.536332)
				(xy 179.057882 103.583527) (xy 179.073093 103.641167) (xy 179.073202 103.641798) (xy 179.351 103.39)
				(xy 179.073202 103.138202) (xy 179.058905 103.193635) (xy 179.037825 103.23952) (xy 179.01046 103.277201)
				(xy 178.979552 103.304434) (xy 178.946265 103.321472) (xy 178.913434 103.327489) (xy 178.912 103.3275)
			)
		)
	)
	(zone
		(net 314)
		(net_name "/2xUSB3.0+RJ45/FLG_1")
		(layer "F.Cu")
		(name "$teardrop_padvia$")
		(hatch none 0.1)
		(priority 31746)
		(attr
			(teardrop
				(type padvia)
			)
		)
		(connect_pads yes
			(clearance 0)
		)
		(min_thickness 0.0254)
		(filled_areas_thickness no)
		(fill yes
			(thermal_gap 0.5)
			(thermal_bridge_width 0.5)
			(island_removal_mode 1)
			(island_area_min 10)
		)
		(polygon
			(pts
				(xy 126.199323 93.0625) (xy 126.268764 93.067318) (xy 126.320088 93.08104) (xy 126.395629 93.127755)
				(xy 126.407769 93.137299) (xy 126.474997 93.187081) (xy 126.601 93) (xy 126.474997 92.812919) (xy 126.407768 92.862702)
				(xy 126.324602 92.917106) (xy 126.271748 92.93219) (xy 126.199323 92.9375)
			)
		)
	)
	(zone
		(net 571)
		(net_name "Net-(U7-A_{1})")
		(layer "F.Cu")
		(name "$teardrop_padvia$")
		(hatch none 0.1)
		(priority 31101)
		(attr
			(teardrop
				(type padvia)
			)
		)
		(connect_pads yes
			(clearance 0)
		)
		(min_thickness 0.0254)
		(filled_areas_thickness no)
		(fill yes
			(thermal_gap 0.5)
			(thermal_bridge_width 0.5)
			(island_removal_mode 1)
			(island_area_min 10)
		)
		(polygon
			(pts
				(xy 124.3375 74.917) (xy 124.317727 74.976412) (xy 124.254453 75.032496) (xy 124.205828 75.054198)
				(xy 124.146469 75.068872) (xy 124.1345 75.070652) (xy 124.4 75.331) (xy 124.6655 75.070652) (xy 124.605362 75.057803)
				(xy 124.555478 75.037869) (xy 124.515358 75.011944) (xy 124.486345 74.982124) (xy 124.468854 74.950706)
				(xy 124.462521 74.918895) (xy 124.4625 74.917)
			)
		)
	)
	(zone
		(net 645)
		(net_name "Net-(U41-IO0_6)")
		(layer "F.Cu")
		(name "$teardrop_padvia$")
		(hatch none 0.1)
		(priority 32003)
		(attr
			(teardrop
				(type padvia)
			)
		)
		(connect_pads yes
			(clearance 0)
		)
		(min_thickness 0.0254)
		(filled_areas_thickness no)
		(fill yes
			(thermal_gap 0.5)
			(thermal_bridge_width 0.5)
			(island_removal_mode 1)
			(island_area_min 10)
		)
		(polygon
			(pts
				(xy 129.4625 87.9595) (xy 129.462404 87.953178) (xy 129.467989 87.913675) (xy 129.482922 87.895452)
				(xy 129.5125 87.882504) (xy 129.4 87.496) (xy 129.2875 87.882504) (xy 129.314493 87.89362) (xy 129.329595 87.909147)
				(xy 129.337596 87.953178) (xy 129.3375 87.9595)
			)
		)
	)
	(zone
		(net 1)
		(net_name "GND")
		(layer "F.Cu")
		(name "$teardrop_padvia$")
		(hatch none 0.1)
		(priority 30605)
		(attr
			(teardrop
				(type padvia)
			)
		)
		(connect_pads yes
			(clearance 0)
		)
		(min_thickness 0.0254)
		(filled_areas_thickness no)
		(fill yes
			(thermal_gap 0.5)
			(thermal_bridge_width 0.5)
			(island_removal_mode 1)
			(island_area_min 10)
		)
		(polygon
			(pts
				(xy 226.925 150.2) (xy 226.928333 150.214486) (xy 226.93119 150.24461) (xy 226.919036 150.255651)
				(xy 226.89 150.26) (xy 227.025 151.136) (xy 227.16 150.26) (xy 227.130666 150.255525) (xy 227.118642 150.244199)
				(xy 227.121667 150.214486) (xy 227.125 150.2)
			)
		)
	)
	(zone
		(net 194)
		(net_name "/OCuLink/PCIe_{x4}.RX2+")
		(layer "F.Cu")
		(name "$teardrop_padvia$")
		(hatch none 0.1)
		(priority 32060)
		(attr
			(teardrop
				(type padvia)
			)
		)
		(connect_pads yes
			(clearance 0)
		)
		(min_thickness 0.0254)
		(filled_areas_thickness no)
		(fill yes
			(thermal_gap 0.5)
			(thermal_bridge_width 0.5)
			(island_removal_mode 1)
			(island_area_min 10)
		)
		(polygon
			(pts
				(xy 108.701 152.91) (xy 108.693802 152.889352) (xy 108.684208 152.857016) (xy 108.691035 152.842993)
				(xy 108.7125 152.833004) (xy 108.6 152.584) (xy 108.4875 152.833004) (xy 108.508676 152.842729)
				(xy 108.515731 152.856357) (xy 108.506198 152.889352) (xy 108.499 152.91)
			)
		)
	)
	(zone
		(net 875)
		(net_name "/2xSFP+/SCL1")
		(layer "F.Cu")
		(name "$teardrop_padvia$")
		(hatch none 0.1)
		(priority 31130)
		(attr
			(teardrop
				(type padvia)
			)
		)
		(connect_pads yes
			(clearance 0)
		)
		(min_thickness 0.0254)
		(filled_areas_thickness no)
		(fill yes
			(thermal_gap 0.5)
			(thermal_bridge_width 0.5)
			(island_removal_mode 1)
			(island_area_min 10)
		)
		(polygon
			(pts
				(xy 177.507 148.0625) (xy 177.566412 148.082273) (xy 177.622497 148.145547) (xy 177.644199 148.194172)
				(xy 177.658873 148.253531) (xy 177.660653 148.2655) (xy 177.921 148) (xy 177.660653 147.7345) (xy 177.647804 147.794638)
				(xy 177.62787 147.844522) (xy 177.601945 147.884641) (xy 177.572125 147.913654) (xy 177.540707 147.931146)
				(xy 177.508896 147.937479) (xy 177.507 147.9375)
			)
		)
	)
	(zone
		(net 310)
		(net_name "/Com Express 7 MGMT/~{BIOS_DIS0}")
		(layer "F.Cu")
		(name "$teardrop_padvia$")
		(hatch none 0.1)
		(priority 31763)
		(attr
			(teardrop
				(type padvia)
			)
		)
		(connect_pads yes
			(clearance 0)
		)
		(min_thickness 0.0254)
		(filled_areas_thickness no)
		(fill yes
			(thermal_gap 0.5)
			(thermal_bridge_width 0.5)
			(island_removal_mode 1)
			(island_area_min 10)
		)
		(polygon
			(pts
				(xy 224.699323 146.4625) (xy 224.768764 146.467318) (xy 224.820088 146.48104) (xy 224.895629 146.527755)
				(xy 224.907769 146.537299) (xy 224.974997 146.587081) (xy 225.101 146.4) (xy 224.974997 146.212919)
				(xy 224.907768 146.262702) (xy 224.824602 146.317106) (xy 224.771748 146.33219) (xy 224.699323 146.3375)
			)
		)
	)
	(zone
		(net 1)
		(net_name "GND")
		(layer "F.Cu")
		(name "$teardrop_padvia$")
		(hatch none 0.1)
		(priority 30772)
		(attr
			(teardrop
				(type padvia)
			)
		)
		(connect_pads yes
			(clearance 0)
		)
		(min_thickness 0.0254)
		(filled_areas_thickness no)
		(fill yes
			(thermal_gap 0.5)
			(thermal_bridge_width 0.5)
			(island_removal_mode 1)
			(island_area_min 10)
		)
		(polygon
			(pts
				(xy 307.668 80.938677) (xy 307.674932 80.7811) (xy 307.703456 80.667565) (xy 307.7205 80.625778)
				(xy 307.518 80.537) (xy 307.3155 80.625778) (xy 307.349883 80.721822) (xy 307.365101 80.823702)
				(xy 307.368 80.938677)
			)
		)
	)
	(zone
		(net 968)
		(net_name "/2xSFP+/KR to SFI #2/BYP_RX-")
		(layer "F.Cu")
		(name "$teardrop_padvia$")
		(hatch none 0.1)
		(priority 31959)
		(attr
			(teardrop
				(type padvia)
			)
		)
		(connect_pads yes
			(clearance 0)
		)
		(min_thickness 0.0254)
		(filled_areas_thickness no)
		(fill yes
			(thermal_gap 0.5)
			(thermal_bridge_width 0.5)
			(island_removal_mode 1)
			(island_area_min 10)
		)
		(polygon
			(pts
				(xy 134.68 148.527721) (xy 134.655938 148.458348) (xy 134.619423 148.348401) (xy 134.609113 148.288313)
				(xy 134.61 148.226463) (xy 134.41 148.254) (xy 134.351231 148.485) (xy 134.432579 148.479702) (xy 134.484596 148.488493)
				(xy 134.506116 148.502345) (xy 134.518354 148.522403) (xy 134.52 148.527721)
			)
		)
	)
	(zone
		(net 337)
		(net_name "/Com Express 7 Interfaces/PCIE_{REF}.CK-")
		(layer "F.Cu")
		(name "$teardrop_padvia$")
		(hatch none 0.1)
		(priority 30241)
		(attr
			(teardrop
				(type padvia)
			)
		)
		(connect_pads yes
			(clearance 0)
		)
		(min_thickness 0.0254)
		(filled_areas_thickness no)
		(fill yes
			(thermal_gap 0.5)
			(thermal_bridge_width 0.5)
			(island_removal_mode 1)
			(island_area_min 10)
		)
		(polygon
			(pts
				(xy 220.0705 169.62) (xy 220.06742 169.605773) (xy 220.065252 169.575473) (xy 220.078123 169.564372)
				(xy 220.108295 169.56) (xy 220.025 168.684) (xy 219.875 168.932978) (xy 219.894356 169.174182) (xy 219.879599 169.446888)
				(xy 219.8685 169.62)
			)
		)
	)
	(zone
		(net 977)
		(net_name "/PCIe redriver/RX_EQ1")
		(layer "F.Cu")
		(name "$teardrop_padvia$")
		(hatch none 0.1)
		(priority 31858)
		(attr
			(teardrop
				(type padvia)
			)
		)
		(connect_pads yes
			(clearance 0)
		)
		(min_thickness 0.0254)
		(filled_areas_thickness no)
		(fill yes
			(thermal_gap 0.5)
			(thermal_bridge_width 0.5)
			(island_removal_mode 1)
			(island_area_min 10)
		)
		(polygon
			(pts
				(xy 189.515261 139.805778) (xy 189.560957 139.858287) (xy 189.587544 139.904281) (xy 189.607928 139.99073)
				(xy 189.609764 140.006063) (xy 189.622099 140.0888) (xy 189.843483 140.045612) (xy 189.886671 139.824228)
				(xy 189.803934 139.811893) (xy 189.706656 139.791556) (xy 189.658617 139.764848) (xy 189.60365 139.71739)
			)
		)
	)
	(zone
		(net 91)
		(net_name "/Com Express 7 Interfaces/PCIe_{B2Ax4}.RX1+")
		(layer "F.Cu")
		(name "$teardrop_padvia$")
		(hatch none 0.1)
		(priority 31417)
		(attr
			(teardrop
				(type padvia)
			)
		)
		(connect_pads yes
			(clearance 0)
		)
		(min_thickness 0.0254)
		(filled_areas_thickness no)
		(fill yes
			(thermal_gap 0.5)
			(thermal_bridge_width 0.5)
			(island_removal_mode 1)
			(island_area_min 10)
		)
		(polygon
			(pts
				(xy 212.593744 160.925973) (xy 212.475707 160.815566) (xy 212.41351 160.75839) (xy 212.34487 160.683214)
				(xy 212.174079 160.824507) (xy 212.164619 161.045891) (xy 212.251457 161.035617) (xy 212.270087 161.030976)
				(xy 212.314757 161.020954) (xy 212.358399 161.019039) (xy 212.403091 161.032551) (xy 212.450908 161.068809)
			)
		)
	)
	(zone
		(net 23)
		(net_name "/M.2 key E/~{PERST_D}")
		(layer "F.Cu")
		(name "$teardrop_padvia$")
		(hatch none 0.1)
		(priority 30999)
		(attr
			(teardrop
				(type padvia)
			)
		)
		(connect_pads yes
			(clearance 0)
		)
		(min_thickness 0.0254)
		(filled_areas_thickness no)
		(fill yes
			(thermal_gap 0.5)
			(thermal_bridge_width 0.5)
			(island_removal_mode 1)
			(island_area_min 10)
		)
		(polygon
			(pts
				(xy 143.9925 84.498) (xy 144.012469 84.435134) (xy 144.038921 84.403156) (xy 144.076332 84.374642)
				(xy 144.123527 84.352118) (xy 144.181167 84.336907) (xy 144.181798 84.336798) (xy 143.93 84.059)
				(xy 143.678202 84.336798) (xy 143.733635 84.351095) (xy 143.77952 84.372175) (xy 143.817201 84.39954)
				(xy 143.844434 84.430448) (xy 143.861472 84.463735) (xy 143.867489 84.496566) (xy 143.8675 84.498)
			)
		)
	)
	(zone
		(net 699)
		(net_name "/USB-C console/FTDI_RX")
		(layer "F.Cu")
		(name "$teardrop_padvia$")
		(hatch none 0.1)
		(priority 30386)
		(attr
			(teardrop
				(type padvia)
			)
		)
		(connect_pads yes
			(clearance 0)
		)
		(min_thickness 0.0254)
		(filled_areas_thickness no)
		(fill yes
			(thermal_gap 0.5)
			(thermal_bridge_width 0.5)
			(island_removal_mode 1)
			(island_area_min 10)
		)
		(polygon
			(pts
				(xy 120.080779 72.317608) (xy 120.102403 72.245033) (xy 120.128795 72.208638) (xy 120.165765 72.179724)
				(xy 120.208711 72.164711) (xy 120.038707 71.458293) (xy 119.867289 72.164711) (xy 119.957843 72.187335)
				(xy 119.981811 72.202572) (xy 119.991978 72.22251) (xy 119.992392 72.229221)
			)
		)
	)
	(zone
		(net 581)
		(net_name "Net-(U19-FB)")
		(layer "F.Cu")
		(name "$teardrop_padvia$")
		(hatch none 0.1)
		(priority 31036)
		(attr
			(teardrop
				(type padvia)
			)
		)
		(connect_pads yes
			(clearance 0)
		)
		(min_thickness 0.0254)
		(filled_areas_thickness no)
		(fill yes
			(thermal_gap 0.5)
			(thermal_bridge_width 0.5)
			(island_removal_mode 1)
			(island_area_min 10)
		)
		(polygon
			(pts
				(xy 309.112499 105.372) (xy 309.092441 105.435721) (xy 309.065974 105.468088) (xy 309.028471 105.496866)
				(xy 308.983231 105.518558) (xy 308.928202 105.533202) (xy 309.18 105.811) (xy 309.431798 105.533202)
				(xy 309.374734 105.518813) (xy 309.327446 105.497615) (xy 309.28884 105.470274) (xy 309.260921 105.43934)
				(xy 309.243667 105.406374) (xy 309.237514 105.373629) (xy 309.237499 105.372)
			)
		)
	)
	(zone
		(net 1)
		(net_name "GND")
		(layer "F.Cu")
		(name "$teardrop_padvia$")
		(hatch none 0.1)
		(priority 31279)
		(attr
			(teardrop
				(type padvia)
			)
		)
		(connect_pads yes
			(clearance 0)
		)
		(min_thickness 0.0254)
		(filled_areas_thickness no)
		(fill yes
			(thermal_gap 0.5)
			(thermal_bridge_width 0.5)
			(island_removal_mode 1)
			(island_area_min 10)
		)
		(polygon
			(pts
				(xy 195.60861 77.701486) (xy 195.603897 77.779397) (xy 195.59091 77.838181) (xy 195.548809 77.929211)
				(xy 195.50611 78.014384) (xy 195.70861 78.103163) (xy 195.91111 78.014384) (xy 195.868411 77.929213)
				(xy 195.825743 77.83638) (xy 195.813166 77.778241) (xy 195.80861 77.701486)
			)
		)
	)
	(zone
		(net 889)
		(net_name "/Power/PG_{3V3}")
		(layer "F.Cu")
		(name "$teardrop_padvia$")
		(hatch none 0.1)
		(priority 32132)
		(attr
			(teardrop
				(type padvia)
			)
		)
		(connect_pads yes
			(clearance 0)
		)
		(min_thickness 0.0254)
		(filled_areas_thickness no)
		(fill yes
			(thermal_gap 0.5)
			(thermal_bridge_width 0.5)
			(island_removal_mode 1)
			(island_area_min 10)
		)
		(polygon
			(pts
				(xy 311.202499 103.01092) (xy 311.203974 103.028386) (xy 311.204103 103.069831) (xy 311.195116 103.090844)
				(xy 311.174999 103.109986) (xy 311.264999 103.349999) (xy 311.354999 103.109986) (xy 311.335581 103.091842)
				(xy 311.326393 103.071938) (xy 311.326024 103.028386) (xy 311.327499 103.01092)
			)
		)
	)
	(zone
		(net 584)
		(net_name "Net-(U21-EN)")
		(layer "F.Cu")
		(name "$teardrop_padvia$")
		(hatch none 0.1)
		(priority 30484)
		(attr
			(teardrop
				(type padvia)
			)
		)
		(connect_pads yes
			(clearance 0)
		)
		(min_thickness 0.0254)
		(filled_areas_thickness no)
		(fill yes
			(thermal_gap 0.5)
			(thermal_bridge_width 0.5)
			(island_removal_mode 1)
			(island_area_min 10)
		)
		(polygon
			(pts
				(xy 312.464443 97.345944) (xy 312.547786 97.290565) (xy 312.677775 97.254346) (xy 312.758365 97.247983)
				(xy 312.845973 97.2515) (xy 312.766206 96.955793) (xy 312.445499 96.901026) (xy 312.454517 97.052184)
				(xy 312.444673 97.119715) (xy 312.426408 97.178526) (xy 312.376055 97.257556)
			)
		)
	)
	(zone
		(net 429)
		(net_name "/2xSFP+/MDIO1.MDC")
		(layer "F.Cu")
		(name "$teardrop_padvia$")
		(hatch none 0.1)
		(priority 31780)
		(attr
			(teardrop
				(type padvia)
			)
		)
		(connect_pads yes
			(clearance 0)
		)
		(min_thickness 0.0254)
		(filled_areas_thickness no)
		(fill yes
			(thermal_gap 0.5)
			(thermal_bridge_width 0.5)
			(island_removal_mode 1)
			(island_area_min 10)
		)
		(polygon
			(pts
				(xy 126.8875 143.800677) (xy 126.892318 143.731236) (xy 126.90604 143.679912) (xy 126.952755 143.60437)
				(xy 126.962299 143.592229) (xy 127.012081 143.525003) (xy 126.825 143.399) (xy 126.637919 143.525003)
				(xy 126.687701 143.592231) (xy 126.742106 143.675397) (xy 126.75719 143.728251) (xy 126.7625 143.800677)
			)
		)
	)
	(zone
		(net 728)
		(net_name "Net-(U43C-AMUXA)")
		(layer "F.Cu")
		(name "$teardrop_padvia$")
		(hatch none 0.1)
		(priority 31713)
		(attr
			(teardrop
				(type padvia)
			)
		)
		(connect_pads yes
			(clearance 0)
		)
		(min_thickness 0.0254)
		(filled_areas_thickness no)
		(fill yes
			(thermal_gap 0.5)
			(thermal_bridge_width 0.5)
			(island_removal_mode 1)
			(island_area_min 10)
		)
		(polygon
			(pts
				(xy 147.8375 129.739323) (xy 147.832682 129.808763) (xy 147.81896 129.860087) (xy 147.772245 129.935628)
				(xy 147.762702 129.947768) (xy 147.712919 130.014997) (xy 147.9 130.141) (xy 148.087081 130.014997)
				(xy 148.037299 129.947769) (xy 147.982894 129.864603) (xy 147.96781 129.811748) (xy 147.9625 129.739323)
			)
		)
	)
	(zone
		(net 557)
		(net_name "Net-(U5-A0)")
		(layer "F.Cu")
		(name "$teardrop_padvia$")
		(hatch none 0.1)
		(priority 31131)
		(attr
			(teardrop
				(type padvia)
			)
		)
		(connect_pads yes
			(clearance 0)
		)
		(min_thickness 0.0254)
		(filled_areas_thickness no)
		(fill yes
			(thermal_gap 0.5)
			(thermal_bridge_width 0.5)
			(island_removal_mode 1)
			(island_area_min 10)
		)
		(polygon
			(pts
				(xy 162.207 159.4225) (xy 162.266412 159.442273) (xy 162.322497 159.505547) (xy 162.344199 159.554172)
				(xy 162.358873 159.613531) (xy 162.360653 159.6255) (xy 162.621 159.36) (xy 162.360653 159.0945)
				(xy 162.347804 159.154638) (xy 162.32787 159.204522) (xy 162.301945 159.244641) (xy 162.272125 159.273654)
				(xy 162.240707 159.291146) (xy 162.208896 159.297479) (xy 162.207 159.2975)
			)
		)
	)
	(zone
		(net 90)
		(net_name "/Com Express 7 Interfaces/PCIe_{B2Ax4}.RX0+")
		(layer "F.Cu")
		(name "$teardrop_padvia$")
		(hatch none 0.1)
		(priority 30373)
		(attr
			(teardrop
				(type padvia)
			)
		)
		(connect_pads yes
			(clearance 0)
		)
		(min_thickness 0.0254)
		(filled_areas_thickness no)
		(fill yes
			(thermal_gap 0.5)
			(thermal_bridge_width 0.5)
			(island_removal_mode 1)
			(island_area_min 10)
		)
		(polygon
			(pts
				(xy 296.355 74.87) (xy 296.343784 74.713526) (xy 296.329025 74.508886) (xy 296.331958 74.388472)
				(xy 296.348 74.253414) (xy 296.198 74.034) (xy 296.114678 74.81) (xy 296.145281 74.814477) (xy 296.158183 74.825818)
				(xy 296.15602 74.855836) (xy 296.153 74.87)
			)
		)
	)
	(zone
		(net 73)
		(net_name "+3V3_AON")
		(layer "F.Cu")
		(name "$teardrop_padvia$")
		(hatch none 0.1)
		(priority 30193)
		(attr
			(teardrop
				(type padvia)
			)
		)
		(connect_pads yes
			(clearance 0)
		)
		(min_thickness 0.0254)
		(filled_areas_thickness no)
		(fill yes
			(thermal_gap 0.5)
			(thermal_bridge_width 0.5)
			(island_removal_mode 1)
			(island_area_min 10)
		)
		(polygon
			(pts
				(xy 238.3095 125.77) (xy 238.303825 125.808514) (xy 238.284097 125.847619) (xy 238.257219 125.874469)
				(xy 238.218111 125.896281) (xy 238.1395 125.913927) (xy 238.4095 126.391) (xy 238.6795 125.913927)
				(xy 238.624894 125.904382) (xy 238.582658 125.887775) (xy 238.529693 125.840089) (xy 238.509816 125.779186)
				(xy 238.5095 125.77)
			)
		)
	)
	(zone
		(net 491)
		(net_name "/2xSFP+/MDIO0.MDIO")
		(layer "F.Cu")
		(name "$teardrop_padvia$")
		(hatch none 0.1)
		(priority 31803)
		(attr
			(teardrop
				(type padvia)
			)
		)
		(connect_pads yes
			(clearance 0)
		)
		(min_thickness 0.0254)
		(filled_areas_thickness no)
		(fill yes
			(thermal_gap 0.5)
			(thermal_bridge_width 0.5)
			(island_removal_mode 1)
			(island_area_min 10)
		)
		(polygon
			(pts
				(xy 195.350677 147.6625) (xy 195.281236 147.657682) (xy 195.229913 147.64396) (xy 195.154371 147.597246)
				(xy 195.142231 147.587701) (xy 195.075003 147.537919) (xy 194.949 147.725) (xy 195.075003 147.912081)
				(xy 195.142229 147.862299) (xy 195.225396 147.807894) (xy 195.278251 147.79281) (xy 195.350677 147.7875)
			)
		)
	)
	(zone
		(net 970)
		(net_name "/M.2 key M #2/M2_3V3")
		(layer "F.Cu")
		(name "$teardrop_padvia$")
		(hatch none 0.1)
		(priority 30758)
		(attr
			(teardrop
				(type padvia)
			)
		)
		(connect_pads yes
			(clearance 0)
		)
		(min_thickness 0.0254)
		(filled_areas_thickness no)
		(fill yes
			(thermal_gap 0.5)
			(thermal_bridge_width 0.5)
			(island_removal_mode 1)
			(island_area_min 10)
		)
		(polygon
			(pts
				(xy 290.098 80.978677) (xy 290.104932 80.8211) (xy 290.133456 80.707565) (xy 290.1505 80.665778)
				(xy 289.948 80.577) (xy 289.7455 80.665778) (xy 289.779883 80.761822) (xy 289.795101 80.863702)
				(xy 289.798 80.978677)
			)
		)
	)
	(zone
		(net 372)
		(net_name "/Com Express 7 MGMT/I2C.SDA")
		(layer "F.Cu")
		(name "$teardrop_padvia$")
		(hatch none 0.1)
		(priority 31570)
		(attr
			(teardrop
				(type padvia)
			)
		)
		(connect_pads yes
			(clearance 0)
		)
		(min_thickness 0.0254)
		(filled_areas_thickness no)
		(fill yes
			(thermal_gap 0.5)
			(thermal_bridge_width 0.5)
			(island_removal_mode 1)
			(island_area_min 10)
		)
		(polygon
			(pts
				(xy 240.1375 154.151852) (xy 240.132762 154.207625) (xy 240.119598 154.250063) (xy 240.074675 154.310145)
				(xy 240.047582 154.334331) (xy 240.005366 154.373058) (xy 239.962919 154.424997) (xy 240.15 154.551)
				(xy 240.362254 154.48577) (xy 240.313974 154.368126) (xy 240.277706 154.280496) (xy 240.2625 154.151852)
			)
		)
	)
	(zone
		(net 716)
		(net_name "Net-(U40-SDA)")
		(layer "F.Cu")
		(name "$teardrop_padvia$")
		(hatch none 0.1)
		(priority 31906)
		(attr
			(teardrop
				(type padvia)
			)
		)
		(connect_pads yes
			(clearance 0)
		)
		(min_thickness 0.0254)
		(filled_areas_thickness no)
		(fill yes
			(thermal_gap 0.5)
			(thermal_bridge_width 0.5)
			(island_removal_mode 1)
			(island_area_min 10)
		)
		(polygon
			(pts
				(xy 196.46652 131.911056) (xy 196.471278 131.875792) (xy 196.484588 131.852742) (xy 196.52679 131.833196)
				(xy 196.579449 131.829303) (xy 196.643189 131.824383) (xy 196.704304 131.801771) (xy 196.580797 131.613071)
				(xy 196.36012 131.588164) (xy 196.344804 131.740209) (xy 196.34152 131.911056)
			)
		)
	)
	(zone
		(net 271)
		(net_name "/M.2 key M #2/PCIE_{REF}.CK-")
		(layer "F.Cu")
		(name "$teardrop_padvia$")
		(hatch none 0.1)
		(priority 31340)
		(attr
			(teardrop
				(type padvia)
			)
		)
		(connect_pads yes
			(clearance 0)
		)
		(min_thickness 0.0254)
		(filled_areas_thickness no)
		(fill yes
			(thermal_gap 0.5)
			(thermal_bridge_width 0.5)
			(island_removal_mode 1)
			(island_area_min 10)
		)
		(polygon
			(pts
				(xy 299.153 75.127139) (xy 299.148265 75.173925) (xy 299.135121 75.209377) (xy 299.090113 75.257574)
				(xy 299.051893 75.28175) (xy 299.008726 75.309119) (xy 298.966768 75.345782) (xy 299.13 75.495635)
				(xy 299.350677 75.474775) (xy 299.346048 75.374104) (xy 299.34948 75.290737) (xy 299.349605 75.28867)
				(xy 299.355 75.127139)
			)
		)
	)
	(zone
		(net 2)
		(net_name "+3V3")
		(layer "F.Cu")
		(name "$teardrop_padvia$")
		(hatch none 0.1)
		(priority 30390)
		(attr
			(teardrop
				(type padvia)
			)
		)
		(connect_pads yes
			(clearance 0)
		)
		(min_thickness 0.0254)
		(filled_areas_thickness no)
		(fill yes
			(thermal_gap 0.5)
			(thermal_bridge_width 0.5)
			(island_removal_mode 1)
			(island_area_min 10)
		)
		(polygon
			(pts
				(xy 196.208859 136.088643) (xy 196.163028 136.071552) (xy 196.126068 136.061141) (xy 196.097128 136.044248)
				(xy 196.088314 136.015386) (xy 196.111729 135.969067) (xy 195.740047 135.97197) (xy 195.735661 136.343947)
				(xy 195.769503 136.32407) (xy 195.794355 136.321054) (xy 195.820758 136.343281) (xy 195.838113 136.396035)
				(xy 195.855306 136.442196)
			)
		)
	)
	(zone
		(net 385)
		(net_name "/Com Express 7 Interfaces/SDIO.CMD")
		(layer "F.Cu")
		(name "$teardrop_padvia$")
		(hatch none 0.1)
		(priority 30625)
		(attr
			(teardrop
				(type padvia)
			)
		)
		(connect_pads yes
			(clearance 0)
		)
		(min_thickness 0.0254)
		(filled_areas_thickness no)
		(fill yes
			(thermal_gap 0.5)
			(thermal_bridge_width 0.5)
			(island_removal_mode 1)
			(island_area_min 10)
		)
		(polygon
			(pts
				(xy 202.434 162.2) (xy 202.435718 162.212416) (xy 202.434894 162.243794) (xy 202.420838 162.25541)
				(xy 202.39 162.26) (xy 202.525 163.136) (xy 202.66 162.26) (xy 202.629435 162.255519) (xy 202.615302 162.244149)
				(xy 202.614282 162.212416) (xy 202.616 162.2)
			)
		)
	)
	(zone
		(net 606)
		(net_name "Net-(U37-~{OE4})")
		(layer "F.Cu")
		(name "$teardrop_padvia$")
		(hatch none 0.1)
		(priority 30923)
		(attr
			(teardrop
				(type padvia)
			)
		)
		(connect_pads yes
			(clearance 0)
		)
		(min_thickness 0.0254)
		(filled_areas_thickness no)
		(fill yes
			(thermal_gap 0.5)
			(thermal_bridge_width 0.5)
			(island_removal_mode 1)
			(island_area_min 10)
		)
		(polygon
			(pts
				(xy 222.1375 127.762) (xy 222.117531 127.824866) (xy 222.091079 127.856844) (xy 222.053668 127.885358)
				(xy 222.006473 127.907882) (xy 221.948833 127.923093) (xy 221.948202 127.923202) (xy 222.2 128.201)
				(xy 222.451798 127.923202) (xy 222.396365 127.908905) (xy 222.35048 127.887825) (xy 222.312799 127.86046)
				(xy 222.285566 127.829552) (xy 222.268528 127.796265) (xy 222.262511 127.763434) (xy 222.2625 127.762)
			)
		)
	)
	(zone
		(net 578)
		(net_name "/Power/PG_{1V0}")
		(layer "F.Cu")
		(name "$teardrop_padvia$")
		(hatch none 0.1)
		(priority 32150)
		(attr
			(teardrop
				(type padvia)
			)
		)
		(connect_pads yes
			(clearance 0)
		)
		(min_thickness 0.0254)
		(filled_areas_thickness no)
		(fill yes
			(thermal_gap 0.5)
			(thermal_bridge_width 0.5)
			(island_removal_mode 1)
			(island_area_min 10)
		)
		(polygon
			(pts
				(xy 306.6825 130.499323) (xy 306.677764 130.471184) (xy 306.664615 130.450239) (xy 306.618158 130.427664)
				(xy 306.541044 130.432043) (xy 306.494681 130.448623) (xy 306.454927 130.473459) (xy 306.429691 130.500944)
				(xy 306.417903 130.532268) (xy 306.4175 130.539) (xy 306.62 130.539) (xy 306.4175 130.539) (xy 306.422082 130.550036)
				(xy 306.434541 130.548577) (xy 306.480632 130.518082) (xy 306.532991 130.483768) (xy 306.550711 130.482013)
				(xy 306.5575 130.499323)
			)
		)
	)
	(zone
		(net 1)
		(net_name "GND")
		(layer "F.Cu")
		(name "$teardrop_padvia$")
		(hatch none 0.1)
		(priority 31318)
		(attr
			(teardrop
				(type padvia)
			)
		)
		(connect_pads yes
			(clearance 0)
		)
		(min_thickness 0.0254)
		(filled_areas_thickness no)
		(fill yes
			(thermal_gap 0.5)
			(thermal_bridge_width 0.5)
			(island_removal_mode 1)
			(island_area_min 10)
		)
		(polygon
			(pts
				(xy 215.425 164.012207) (xy 215.420269 164.067803) (xy 215.40715 164.110353) (xy 215.361978 164.172225)
				(xy 215.338296 164.194609) (xy 215.269305 164.26861) (xy 215.45 164.401) (xy 215.666731 164.346578)
				(xy 215.664817 164.338815) (xy 215.633194 164.189946) (xy 215.625 164.012207)
			)
		)
	)
	(zone
		(net 610)
		(net_name "Net-(Y1-EN)")
		(layer "F.Cu")
		(name "$teardrop_padvia$")
		(hatch none 0.1)
		(priority 31043)
		(attr
			(teardrop
				(type padvia)
			)
		)
		(connect_pads yes
			(clearance 0)
		)
		(min_thickness 0.0254)
		(filled_areas_thickness no)
		(fill yes
			(thermal_gap 0.5)
			(thermal_bridge_width 0.5)
			(island_removal_mode 1)
			(island_area_min 10)
		)
		(polygon
			(pts
				(xy 307.824698 76.853724) (xy 307.870798 76.764256) (xy 307.906678 76.71811) (xy 307.952267 76.678959)
				(xy 307.990493 76.658873) (xy 308.034218 76.647205) (xy 307.795707 76.361295) (xy 307.543202 76.6388)
				(xy 307.65214 76.663808) (xy 307.677375 76.677435) (xy 307.686652 76.69366) (xy 307.683278 76.712304)
			)
		)
	)
	(zone
		(net 2)
		(net_name "+3V3")
		(layer "F.Cu")
		(name "$teardrop_padvia$")
		(hatch none 0.1)
		(priority 31092)
		(attr
			(teardrop
				(type padvia)
			)
		)
		(connect_pads yes
			(clearance 0)
		)
		(min_thickness 0.0254)
		(filled_areas_thickness no)
		(fill yes
			(thermal_gap 0.5)
			(thermal_bridge_width 0.5)
			(island_removal_mode 1)
			(island_area_min 10)
		)
		(polygon
			(pts
				(xy 192.056374 139.510686) (xy 192.000382 139.538714) (xy 191.915983 139.533631) (xy 191.866254 139.514594)
				(xy 191.813905 139.482996) (xy 191.804182 139.475791) (xy 191.807826 139.847622) (xy 192.179656 139.851265)
				(xy 192.146218 139.799655) (xy 192.12504 139.750286) (xy 192.115003 139.703586) (xy 192.115573 139.661985)
				(xy 192.125421 139.627401) (xy 192.143437 139.600429) (xy 192.144762 139.599074)
			)
		)
	)
	(zone
		(net 533)
		(net_name "/Com Express 7 MGMT/PSON")
		(layer "F.Cu")
		(name "$teardrop_padvia$")
		(hatch none 0.1)
		(priority 31812)
		(attr
			(teardrop
				(type padvia)
			)
		)
		(connect_pads yes
			(clearance 0)
		)
		(min_thickness 0.0254)
		(filled_areas_thickness no)
		(fill yes
			(thermal_gap 0.5)
			(thermal_bridge_width 0.5)
			(island_removal_mode 1)
			(island_area_min 10)
		)
		(polygon
			(pts
				(xy 292.300677 138.9475) (xy 292.231236 138.942682) (xy 292.179913 138.92896) (xy 292.104371 138.882246)
				(xy 292.092231 138.872701) (xy 292.025003 138.822919) (xy 291.899 139.01) (xy 292.025003 139.197081)
				(xy 292.092229 139.147299) (xy 292.175396 139.092894) (xy 292.228251 139.07781) (xy 292.300677 139.0725)
			)
		)
	)
	(zone
		(net 1)
		(net_name "GND")
		(layer "F.Cu")
		(name "$teardrop_padvia$")
		(hatch none 0.1)
		(priority 30611)
		(attr
			(teardrop
				(type padvia)
			)
		)
		(connect_pads yes
			(clearance 0)
		)
		(min_thickness 0.0254)
		(filled_areas_thickness no)
		(fill yes
			(thermal_gap 0.5)
			(thermal_bridge_width 0.5)
			(island_removal_mode 1)
			(island_area_min 10)
		)
		(polygon
			(pts
				(xy 220.425 162.2) (xy 220.428333 162.214486) (xy 220.43119 162.24461) (xy 220.419036 162.255651)
				(xy 220.39 162.26) (xy 220.525 163.136) (xy 220.66 162.26) (xy 220.630666 162.255525) (xy 220.618642 162.244199)
				(xy 220.621667 162.214486) (xy 220.625 162.2)
			)
		)
	)
	(zone
		(net 203)
		(net_name "/Backplane/PCIe_{REF}.CK+")
		(layer "F.Cu")
		(name "$teardrop_padvia$")
		(hatch none 0.1)
		(priority 31445)
		(attr
			(teardrop
				(type padvia)
			)
		)
		(connect_pads yes
			(clearance 0)
		)
		(min_thickness 0.0254)
		(filled_areas_thickness no)
		(fill yes
			(thermal_gap 0.5)
			(thermal_bridge_width 0.5)
			(island_removal_mode 1)
			(island_area_min 10)
		)
		(polygon
			(pts
				(xy 259.1955 137.463584) (xy 259.200235 137.417781) (xy 259.213381 137.3832) (xy 259.258329 137.33671)
				(xy 259.297581 137.313183) (xy 259.341576 137.286771) (xy 259.384165 137.250918) (xy 259.223 137.099)
				(xy 259.002323 137.115931) (xy 259.000471 137.29335) (xy 258.9935 137.463584)
			)
		)
	)
	(zone
		(net 152)
		(net_name "/2xUSB3.0+RJ45/DD+")
		(layer "F.Cu")
		(name "$teardrop_padvia$")
		(hatch none 0.1)
		(priority 31158)
		(attr
			(teardrop
				(type padvia)
			)
		)
		(connect_pads yes
			(clearance 0)
		)
		(min_thickness 0.0254)
		(filled_areas_thickness no)
		(fill yes
			(thermal_gap 0.5)
			(thermal_bridge_width 0.5)
			(island_removal_mode 1)
			(island_area_min 10)
		)
		(polygon
			(pts
				(xy 125.867073 101.853139) (xy 125.912063 101.908172) (xy 125.94717 101.985302) (xy 125.955193 102.034101)
				(xy 125.9525 102.088424) (xy 126.290707 102.070707) (xy 126.326943 101.8325) (xy 126.239355 101.836626)
				(xy 126.161899 101.830762) (xy 126.095663 101.816263) (xy 126.039618 101.794147) (xy 125.973139 101.747073)
			)
		)
	)
	(zone
		(net 537)
		(net_name "/Backplane/PCIe_{x2}.RX0-")
		(layer "F.Cu")
		(name "$teardrop_padvia$")
		(hatch none 0.1)
		(priority 31436)
		(attr
			(teardrop
				(type padvia)
			)
		)
		(connect_pads yes
			(clearance 0)
		)
		(min_thickness 0.0254)
		(filled_areas_thickness no)
		(fill yes
			(thermal_gap 0.5)
			(thermal_bridge_width 0.5)
			(island_removal_mode 1)
			(island_area_min 10)
		)
		(polygon
			(pts
				(xy 271.167496 158.2935) (xy 271.005964 158.298895) (xy 270.921554 158.302445) (xy 270.81986 158.297823)
				(xy 270.799 158.5185) (xy 270.948852 158.681731) (xy 271.002992 158.613062) (xy 271.012883 158.596608)
				(xy 271.037383 158.557935) (xy 271.06689 158.525721) (xy 271.108046 158.503673) (xy 271.167496 158.4955)
			)
		)
	)
	(zone
		(net 1)
		(net_name "GND")
		(layer "F.Cu")
		(name "$teardrop_padvia$")
		(hatch none 0.1)
		(priority 30463)
		(attr
			(teardrop
				(type padvia)
			)
		)
		(connect_pads yes
			(clearance 0)
		)
		(min_thickness 0.0254)
		(filled_areas_thickness no)
		(fill yes
			(thermal_gap 0.5)
			(thermal_bridge_width 0.5)
			(island_removal_mode 1)
			(island_area_min 10)
		)
		(polygon
			(pts
				(xy 248.365708 76.198) (xy 248.36537 76.18113) (xy 248.365949 76.136174) (xy 248.377767 76.088831)
				(xy 248.412346 76.046427) (xy 248.481208 76.016291) (xy 248.215708 75.759) (xy 247.950208 76.016291)
				(xy 247.994977 76.031848) (xy 248.026593 76.052565) (xy 248.059327 76.103701) (xy 248.066046 76.18113)
				(xy 248.065708 76.198)
			)
		)
	)
	(zone
		(net 431)
		(net_name "/2xSFP+/MOD0_ABS")
		(layer "F.Cu")
		(name "$teardrop_padvia$")
		(hatch none 0.1)
		(priority 31073)
		(attr
			(teardrop
				(type padvia)
			)
		)
		(connect_pads yes
			(clearance 0)
		)
		(min_thickness 0.0254)
		(filled_areas_thickness no)
		(fill yes
			(thermal_gap 0.5)
			(thermal_bridge_width 0.5)
			(island_removal_mode 1)
			(island_area_min 10)
		)
		(polygon
			(pts
				(xy 179.293 144.9375) (xy 179.233588 144.917727) (xy 179.177503 144.854453) (xy 179.155801 144.805828)
				(xy 179.141127 144.746468) (xy 179.139347 144.7345) (xy 178.879 145) (xy 179.139347 145.2655) (xy 179.152197 145.205361)
				(xy 179.172131 145.155477) (xy 179.198056 145.115358) (xy 179.227876 145.086345) (xy 179.259294 145.068854)
				(xy 179.291105 145.062521) (xy 179.293 145.0625)
			)
		)
	)
	(zone
		(net 978)
		(net_name "/PCIe redriver/RX_EQ0")
		(layer "F.Cu")
		(name "$teardrop_padvia$")
		(hatch none 0.1)
		(priority 31658)
		(attr
			(teardrop
				(type padvia)
			)
		)
		(connect_pads yes
			(clearance 0)
		)
		(min_thickness 0.0254)
		(filled_areas_thickness no)
		(fill yes
			(thermal_gap 0.5)
			(thermal_bridge_width 0.5)
			(island_removal_mode 1)
			(island_area_min 10)
		)
		(polygon
			(pts
				(xy 190.721271 140.760222) (xy 190.683415 140.755449) (xy 190.657834 140.742038) (xy 190.634477 140.699472)
				(xy 190.628191 140.632037) (xy 190.622797 140.563001) (xy 190.599982 140.496304) (xy 190.407462 140.61059)
				(xy 190.372328 140.831267) (xy 190.494702 140.857318) (xy 190.588166 140.877058) (xy 190.721271 140.885222)
			)
		)
	)
	(zone
		(net 559)
		(net_name "Net-(U5-SCL)")
		(layer "F.Cu")
		(name "$teardrop_padvia$")
		(hatch none 0.1)
		(priority 30478)
		(attr
			(teardrop
				(type padvia)
			)
		)
		(connect_pads yes
			(clearance 0)
		)
		(min_thickness 0.0254)
		(filled_areas_thickness no)
		(fill yes
			(thermal_gap 0.5)
			(thermal_bridge_width 0.5)
			(island_removal_mode 1)
			(island_area_min 10)
		)
		(polygon
			(pts
				(xy 161.248944 157.679444) (xy 161.332287 157.624065) (xy 161.462276 157.587846) (xy 161.542866 157.581483)
				(xy 161.630474 157.585) (xy 161.550707 157.289293) (xy 161.23 157.234526) (xy 161.239018 157.385684)
				(xy 161.229174 157.453215) (xy 161.210909 157.512026) (xy 161.160556 157.591056)
			)
		)
	)
	(zone
		(net 73)
		(net_name "+3V3_AON")
		(layer "F.Cu")
		(name "$teardrop_padvia$")
		(hatch none 0.1)
		(priority 32141)
		(attr
			(teardrop
				(type padvia)
			)
		)
		(connect_pads yes
			(clearance 0)
		)
		(min_thickness 0.0254)
		(filled_areas_thickness no)
		(fill yes
			(thermal_gap 0.5)
			(thermal_bridge_width 0.5)
			(island_removal_mode 1)
			(island_area_min 10)
		)
		(polygon
			(pts
				(xy 237.541001 154.061999) (xy 237.555487 154.058666) (xy 237.58561 154.05581) (xy 237.596651 154.067964)
				(xy 237.601 154.097) (xy 237.751999 153.962) (xy 237.601 153.827) (xy 237.596525 153.856334) (xy 237.585199 153.868358)
				(xy 237.555486 153.865333) (xy 237.541 153.862)
			)
		)
	)
	(zone
		(net 164)
		(net_name "/2xSFP+/SDA0")
		(layer "F.Cu")
		(name "$teardrop_padvia$")
		(hatch none 0.1)
		(priority 31888)
		(attr
			(teardrop
				(type padvia)
			)
		)
		(connect_pads yes
			(clearance 0)
		)
		(min_thickness 0.0254)
		(filled_areas_thickness no)
		(fill yes
			(thermal_gap 0.5)
			(thermal_bridge_width 0.5)
			(island_removal_mode 1)
			(island_area_min 10)
		)
		(polygon
			(pts
				(xy 176.027515 142.939127) (xy 175.981819 142.886618) (xy 175.955231 142.840623) (xy 175.934847 142.754175)
				(xy 175.933011 142.73884) (xy 175.920677 142.656105) (xy 175.699293 142.699293) (xy 175.656105 142.920677)
				(xy 175.73884 142.933011) (xy 175.836119 142.953349) (xy 175.884159 142.980057) (xy 175.939127 143.027515)
			)
		)
	)
	(zone
		(net 1)
		(net_name "GND")
		(layer "F.Cu")
		(name "$teardrop_padvia$")
		(hatch none 0.1)
		(priority 31215)
		(attr
			(teardrop
				(type padvia)
			)
		)
		(connect_pads yes
			(clearance 0)
		)
		(min_thickness 0.0254)
		(filled_areas_thickness no)
		(fill yes
			(thermal_gap 0.5)
			(thermal_bridge_width 0.5)
			(island_removal_mode 1)
			(island_area_min 10)
		)
		(polygon
			(pts
				(xy 220.425 157.399323) (xy 220.42028 157.468646) (xy 220.407244 157.521549) (xy 220.355344 157.614135)
				(xy 220.303541 157.697636) (xy 220.5 157.801) (xy 220.707644 157.724641) (xy 220.675418 157.644142)
				(xy 220.639035 157.542683) (xy 220.625 157.399323)
			)
		)
	)
	(zone
		(net 78)
		(net_name "+1V8")
		(layer "F.Cu")
		(hatch edge 0.5)
		(priority 24)
		(connect_pads yes
			(clearance 0.15)
		)
		(min_thickness 0.25)
		(filled_areas_thickness no)
		(fill yes
			(thermal_gap 0.2)
			(thermal_bridge_width 0.5)
			(smoothing fillet)
			(radius 0.2)
		)
		(polygon
			(pts
				(xy 303.738 137.21) (xy 303.738 134.539) (xy 299.688 134.539) (xy 299.688 137.21)
			)
		)
	)
	(zone
		(net 1)
		(net_name "GND")
		(layer "F.Cu")
		(name "$teardrop_padvia$")
		(hatch none 0.1)
		(priority 31195)
		(attr
			(teardrop
				(type padvia)
			)
		)
		(connect_pads yes
			(clearance 0)
		)
		(min_thickness 0.0254)
		(filled_areas_thickness no)
		(fill yes
			(thermal_gap 0.5)
			(thermal_bridge_width 0.5)
			(island_removal_mode 1)
			(island_area_min 10)
		)
		(polygon
			(pts
				(xy 223.425 151.948323) (xy 223.42028 152.017646) (xy 223.407244 152.070549) (xy 223.355344 152.163135)
				(xy 223.303541 152.246636) (xy 223.5 152.35) (xy 223.707644 152.273641) (xy 223.675418 152.193142)
				(xy 223.639035 152.091683) (xy 223.625 151.948323)
			)
		)
	)
	(zone
		(net 932)
		(net_name "Net-(D7-C)")
		(layer "F.Cu")
		(name "$teardrop_padvia$")
		(hatch none 0.1)
		(priority 31116)
		(attr
			(teardrop
				(type padvia)
			)
		)
		(connect_pads yes
			(clearance 0)
		)
		(min_thickness 0.0254)
		(filled_areas_thickness no)
		(fill yes
			(thermal_gap 0.5)
			(thermal_bridge_width 0.5)
			(island_removal_mode 1)
			(island_area_min 10)
		)
		(polygon
			(pts
				(xy 154.406 168.4225) (xy 154.465412 168.442273) (xy 154.521497 168.505547) (xy 154.543199 168.554172)
				(xy 154.557873 168.613531) (xy 154.559653 168.6255) (xy 154.82 168.36) (xy 154.559653 168.0945)
				(xy 154.546804 168.154638) (xy 154.52687 168.204522) (xy 154.500945 168.244641) (xy 154.471125 168.273654)
				(xy 154.439707 168.291146) (xy 154.407896 168.297479) (xy 154.406 168.2975)
			)
		)
	)
	(zone
		(net 374)
		(net_name "/2xUSB3.0+RJ45/USB_2.D-")
		(layer "F.Cu")
		(name "$teardrop_padvia$")
		(hatch none 0.1)
		(priority 30450)
		(attr
			(teardrop
				(type padvia)
			)
		)
		(connect_pads yes
			(clearance 0)
		)
		(min_thickness 0.0254)
		(filled_areas_thickness no)
		(fill yes
			(thermal_gap 0.5)
			(thermal_bridge_width 0.5)
			(island_removal_mode 1)
			(island_area_min 10)
		)
		(polygon
			(pts
				(xy 130.923657 115.8175) (xy 130.896935 115.793029) (xy 130.876917 115.760924) (xy 130.854148 115.666011)
				(xy 130.855 115.50316) (xy 130.559 115.6) (xy 130.525508 115.92) (xy 130.645933 115.909599) (xy 130.777853 115.933647)
				(xy 130.904794 115.990278) (xy 130.923657 116.0025)
			)
		)
	)
	(zone
		(net 73)
		(net_name "+3V3_AON")
		(layer "F.Cu")
		(name "$teardrop_padvia$")
		(hatch none 0.1)
		(priority 31995)
		(attr
			(teardrop
				(type padvia)
			)
		)
		(connect_pads yes
			(clearance 0)
		)
		(min_thickness 0.0254)
		(filled_areas_thickness no)
		(fill yes
			(thermal_gap 0.5)
			(thermal_bridge_width 0.5)
			(island_removal_mode 1)
			(island_area_min 10)
		)
		(polygon
			(pts
				(xy 237.8135 157.271) (xy 237.824438 157.232177) (xy 237.846195 157.217067) (xy 237.886 157.211)
				(xy 237.751 156.86) (xy 237.616 157.211) (xy 237.651281 157.215517) (xy 237.672797 157.227138) (xy 237.687995 157.259961)
				(xy 237.6885 157.271)
			)
		)
	)
	(zone
		(net 327)
		(net_name "/Com Express 7 Interfaces/PCIe_{B2Ax4}.TX1-")
		(layer "F.Cu")
		(name "$teardrop_padvia$")
		(hatch none 0.1)
		(priority 31594)
		(attr
			(teardrop
				(type padvia)
			)
		)
		(connect_pads yes
			(clearance 0)
		)
		(min_thickness 0.0254)
		(filled_areas_thickness no)
		(fill yes
			(thermal_gap 0.5)
			(thermal_bridge_width 0.5)
			(island_removal_mode 1)
			(island_area_min 10)
		)
		(polygon
			(pts
				(xy 213.076624 167.281288) (xy 213.062862 167.260855) (xy 213.065998 167.245581) (xy 213.101515 167.226675)
				(xy 213.136458 167.216935) (xy 213.218503 167.187081) (xy 213.092793 166.999293) (xy 212.873004 167.044333)
				(xy 212.877097 167.143408) (xy 212.870227 167.195029) (xy 212.863202 167.251042) (xy 212.865556 167.306168)
				(xy 212.886136 167.362997) (xy 212.933789 167.424123)
			)
		)
	)
	(zone
		(net 162)
		(net_name "Net-(J2A-TX_{FAULT})")
		(layer "F.Cu")
		(name "$teardrop_padvia$")
		(hatch none 0.1)
		(priority 30061)
		(attr
			(teardrop
				(type padvia)
			)
		)
		(connect_pads yes
			(clearance 0)
		)
		(min_thickness 0.0254)
		(filled_areas_thickness no)
		(fill yes
			(thermal_gap 0.5)
			(thermal_bridge_width 0.5)
			(island_removal_mode 1)
			(island_area_min 10)
		)
		(polygon
			(pts
				(xy 144.252736 160.295652) (xy 144.317615 160.237595) (xy 144.377096 160.197584) (xy 144.482061 160.159114)
				(xy 144.618356 160.149873) (xy 144.71714 160.146966) (xy 144.833889 160.131738) (xy 144.750707 159.709293)
				(xy 144.328262 159.626111) (xy 144.310953 159.788348) (xy 144.310127 159.841644) (xy 144.307095 159.931998)
				(xy 144.29074 160.018037) (xy 144.247634 160.107285) (xy 144.164348 160.207264)
			)
		)
	)
	(zone
		(net 82)
		(net_name "Net-(U32-CT)")
		(layer "F.Cu")
		(name "$teardrop_padvia$")
		(hatch none 0.1)
		(priority 30319)
		(attr
			(teardrop
				(type padvia)
			)
		)
		(connect_pads yes
			(clearance 0)
		)
		(min_thickness 0.0254)
		(filled_areas_thickness no)
		(fill yes
			(thermal_gap 0.5)
			(thermal_bridge_width 0.5)
			(island_removal_mode 1)
			(island_area_min 10)
		)
		(polygon
			(pts
				(xy 257.785 126.159248) (xy 257.733303 126.139245) (xy 257.710285 126.113395) (xy 257.691813 126.076972)
				(xy 257.675 125.971899) (xy 257.174 126.209) (xy 257.675 126.467006) (xy 257.679697 126.40942) (xy 257.692578 126.36279)
				(xy 257.711895 126.32695) (xy 257.735786 126.30199) (xy 257.785 126.284248)
			)
		)
	)
	(zone
		(net 945)
		(net_name "/GPIO expander/GPIOEX5")
		(layer "F.Cu")
		(name "$teardrop_padvia$")
		(hatch none 0.1)
		(priority 30951)
		(attr
			(teardrop
				(type padvia)
			)
		)
		(connect_pads yes
			(clearance 0)
		)
		(min_thickness 0.0254)
		(filled_areas_thickness no)
		(fill yes
			(thermal_gap 0.5)
			(thermal_bridge_width 0.5)
			(island_removal_mode 1)
			(island_area_min 10)
		)
		(polygon
			(pts
				(xy 121.838 146.8185) (xy 121.775134 146.798531) (xy 121.743156 146.772079) (xy 121.714642 146.734668)
				(xy 121.692118 146.687473) (xy 121.676907 146.629833) (xy 121.676798 146.629202) (xy 121.399 146.881)
				(xy 121.676798 147.132798) (xy 121.691095 147.077365) (xy 121.712175 147.03148) (xy 121.73954 146.993799)
				(xy 121.770448 146.966566) (xy 121.803735 146.949528) (xy 121.836566 146.943511) (xy 121.838 146.9435)
			)
		)
	)
	(zone
		(net 64)
		(net_name "Net-(U19-V_{CC})")
		(layer "F.Cu")
		(name "$teardrop_padvia$")
		(hatch none 0.1)
		(priority 31718)
		(attr
			(teardrop
				(type padvia)
			)
		)
		(connect_pads yes
			(clearance 0)
		)
		(min_thickness 0.0254)
		(filled_areas_thickness no)
		(fill yes
			(thermal_gap 0.5)
			(thermal_bridge_width 0.5)
			(island_removal_mode 1)
			(island_area_min 10)
		)
		(polygon
			(pts
				(xy 311.202499 106.249323) (xy 311.197681 106.318763) (xy 311.183959 106.370087) (xy 311.137244 106.445628)
				(xy 311.127701 106.457768) (xy 311.077918 106.524997) (xy 311.264999 106.651) (xy 311.45208 106.524997)
				(xy 311.402298 106.457769) (xy 311.347893 106.374603) (xy 311.332809 106.321748) (xy 311.327499 106.249323)
			)
		)
	)
	(zone
		(net 576)
		(net_name "Net-(U19-MODE)")
		(layer "F.Cu")
		(name "$teardrop_padvia$")
		(hatch none 0.1)
		(priority 32135)
		(attr
			(teardrop
				(type padvia)
			)
		)
		(connect_pads yes
			(clearance 0)
		)
		(min_thickness 0.0254)
		(filled_areas_thickness no)
		(fill yes
			(thermal_gap 0.5)
			(thermal_bridge_width 0.5)
			(island_removal_mode 1)
			(island_area_min 10)
		)
		(polygon
			(pts
				(xy 309.97692 105.714499) (xy 309.993646 105.713084) (xy 310.03397 105.713109) (xy 310.054265 105.722236)
				(xy 310.072521 105.742564) (xy 310.315999 105.653999) (xy 310.079358 105.562602) (xy 310.060468 105.581759)
				(xy 310.039973 105.590813) (xy 309.995139 105.59104) (xy 309.97692 105.589499)
			)
		)
	)
	(zone
		(net 131)
		(net_name "Net-(D17-C_{B})")
		(layer "F.Cu")
		(name "$teardrop_padvia$")
		(hatch none 0.1)
		(priority 30026)
		(attr
			(teardrop
				(type padvia)
			)
		)
		(connect_pads yes
			(clearance 0)
		)
		(min_thickness 0.0254)
		(filled_areas_thickness no)
		(fill yes
			(thermal_gap 0.5)
			(thermal_bridge_width 0.5)
			(island_removal_mode 1)
			(island_area_min 10)
		)
		(polygon
			(pts
				(xy 103.194697 77.303691) (xy 103.232659 77.229983) (xy 103.316225 77.155628) (xy 103.447557 77.093302)
				(xy 103.526497 77.072682) (xy 103.610839 77.061569) (xy 103.656734 77.06) (xy 103.200707 76.309293)
				(xy 102.665353 77.06) (xy 102.816231 77.065236) (xy 102.943619 77.081888) (xy 103.017255 77.102056)
				(xy 103.071166 77.129608) (xy 103.095802 77.153955) (xy 103.107868 77.182499) (xy 103.106309 77.215303)
			)
		)
	)
	(zone
		(net 1)
		(net_name "GND")
		(layer "F.Cu")
		(name "$teardrop_padvia$")
		(hatch none 0.1)
		(priority 30865)
		(attr
			(teardrop
				(type padvia)
			)
		)
		(connect_pads yes
			(clearance 0)
		)
		(min_thickness 0.0254)
		(filled_areas_thickness no)
		(fill yes
			(thermal_gap 0.5)
			(thermal_bridge_width 0.5)
			(island_removal_mode 1)
			(island_area_min 10)
		)
		(polygon
			(pts
				(xy 129.6 108.193) (xy 129.605772 108.152263) (xy 129.626176 108.110348) (xy 129.653351 108.082047)
				(xy 129.692897 108.058618) (xy 129.7655 108.039347) (xy 129.5 107.779) (xy 129.2345 108.039347)
				(xy 129.287642 108.051214) (xy 129.328681 108.069662) (xy 129.380382 108.120336) (xy 129.399718 108.183905)
				(xy 129.4 108.193)
			)
		)
	)
	(zone
		(net 1)
		(net_name "GND")
		(layer "F.Cu")
		(name "$teardrop_padvia$")
		(hatch none 0.1)
		(priority 30954)
		(attr
			(teardrop
				(type padvia)
			)
		)
		(connect_pads yes
			(clearance 0)
		)
		(min_thickness 0.0254)
		(filled_areas_thickness no)
		(fill yes
			(thermal_gap 0.5)
			(thermal_bridge_width 0.5)
			(island_removal_mode 1)
			(island_area_min 10)
		)
		(polygon
			(pts
				(xy 142.5825 133.318) (xy 142.602469 133.255134) (xy 142.628921 133.223156) (xy 142.666332 133.194642)
				(xy 142.713527 133.172118) (xy 142.771167 133.156907) (xy 142.771798 133.156798) (xy 142.52 132.879)
				(xy 142.268202 133.156798) (xy 142.323635 133.171095) (xy 142.36952 133.192175) (xy 142.407201 133.21954)
				(xy 142.434434 133.250448) (xy 142.451472 133.283735) (xy 142.457489 133.316566) (xy 142.4575 133.318)
			)
		)
	)
	(zone
		(net 634)
		(net_name "Net-(U41-SDA)")
		(layer "F.Cu")
		(name "$teardrop_padvia$")
		(hatch none 0.1)
		(priority 31543)
		(attr
			(teardrop
				(type padvia)
			)
		)
		(connect_pads yes
			(clearance 0)
		)
		(min_thickness 0.0254)
		(filled_areas_thickness no)
		(fill yes
			(thermal_gap 0.5)
			(thermal_bridge_width 0.5)
			(island_removal_mode 1)
			(island_area_min 10)
		)
		(polygon
			(pts
				(xy 131.913789 82.6846) (xy 131.955391 82.611801) (xy 131.9943 82.574252) (xy 132.043133 82.542613)
				(xy 132.091697 82.522992) (xy 132.145813 82.512501) (xy 131.900707 82.239293) (xy 131.671054 82.523772)
				(xy 131.749404 82.532522) (xy 131.800735 82.54937) (xy 131.820812 82.566033) (xy 131.827031 82.586308)
				(xy 131.825401 82.596212)
			)
		)
	)
	(zone
		(net 300)
		(net_name "Net-(J12D-~{SUS_S4})")
		(layer "F.Cu")
		(name "$teardrop_padvia$")
		(hatch none 0.1)
		(priority 30648)
		(attr
			(teardrop
				(type padvia)
			)
		)
		(connect_pads yes
			(clearance 0)
		)
		(min_thickness 0.0254)
		(filled_areas_thickness no)
		(fill yes
			(thermal_gap 0.5)
			(thermal_bridge_width 0.5)
			(island_removal_mode 1)
			(island_area_min 10)
		)
		(polygon
			(pts
				(xy 184.5875 169.62) (xy 184.598438 169.581177) (xy 184.620195 169.566067) (xy 184.66 169.56) (xy 184.525 168.684)
				(xy 184.39 169.56) (xy 184.425281 169.564517) (xy 184.446797 169.576138) (xy 184.461995 169.608961)
				(xy 184.4625 169.62)
			)
		)
	)
	(zone
		(net 569)
		(net_name "/USB-C console/FTDI_D-")
		(layer "F.Cu")
		(name "$teardrop_padvia$")
		(hatch none 0.1)
		(priority 30918)
		(attr
			(teardrop
				(type padvia)
			)
		)
		(connect_pads yes
			(clearance 0)
		)
		(min_thickness 0.0254)
		(filled_areas_thickness no)
		(fill yes
			(thermal_gap 0.5)
			(thermal_bridge_width 0.5)
			(island_removal_mode 1)
			(island_area_min 10)
		)
		(polygon
			(pts
				(xy 112.779999 76.1075) (xy 112.820306 76.116552) (xy 112.83819 76.132427) (xy 112.851849 76.159919)
				(xy 112.859999 76.224408) (xy 113.260999 76.15) (xy 113.214522 75.95) (xy 113.073231 75.958918)
				(xy 112.90958 75.93822) (xy 112.779999 75.9225)
			)
		)
	)
	(zone
		(net 51)
		(net_name "Net-(C13-Pad1)")
		(layer "F.Cu")
		(name "$teardrop_padvia$")
		(hatch none 0.1)
		(priority 30093)
		(attr
			(teardrop
				(type padvia)
			)
		)
		(connect_pads yes
			(clearance 0)
		)
		(min_thickness 0.0254)
		(filled_areas_thickness no)
		(fill yes
			(thermal_gap 0.5)
			(thermal_bridge_width 0.5)
			(island_removal_mode 1)
			(island_area_min 10)
		)
		(polygon
			(pts
				(xy 131.374 106.91) (xy 131.317939 106.902567) (xy 131.262329 106.870538) (xy 131.238554 106.839894)
				(xy 131.220421 106.79702) (xy 131.208103 106.7135) (xy 130.769 107.06) (xy 131.208103 107.4065)
				(xy 131.214918 107.345202) (xy 131.229503 107.297953) (xy 131.249612 107.263687) (xy 131.273934 107.23947)
				(xy 131.334458 107.213449) (xy 131.374 107.21)
			)
		)
	)
	(zone
		(net 537)
		(net_name "/Backplane/PCIe_{x2}.RX0-")
		(layer "F.Cu")
		(name "$teardrop_padvia$")
		(hatch none 0.1)
		(priority 32033)
		(attr
			(teardrop
				(type padvia)
			)
		)
		(connect_pads yes
			(clearance 0)
		)
		(min_thickness 0.0254)
		(filled_areas_thickness no)
		(fill yes
			(thermal_gap 0.5)
			(thermal_bridge_width 0.5)
			(island_removal_mode 1)
			(island_area_min 10)
		)
		(polygon
			(pts
				(xy 314.038 160.4555) (xy 314.051941 160.450168) (xy 314.076365 160.443442) (xy 314.085289 160.452549)
				(xy 314.088953 160.477292) (xy 314.364 160.41) (xy 314.300083 160.285) (xy 314.217652 160.294335)
				(xy 314.117272 160.271146) (xy 314.038 160.2535)
			)
		)
	)
	(zone
		(net 1)
		(net_name "GND")
		(layer "F.Cu")
		(name "$teardrop_padvia$")
		(hatch none 0.1)
		(priority 30595)
		(attr
			(teardrop
				(type padvia)
			)
		)
		(connect_pads yes
			(clearance 0)
		)
		(min_thickness 0.0254)
		(filled_areas_thickness no)
		(fill yes
			(thermal_gap 0.5)
			(thermal_bridge_width 0.5)
			(island_removal_mode 1)
			(island_area_min 10)
		)
		(polygon
			(pts
				(xy 191.125 169.62) (xy 191.121667 169.605514) (xy 191.11881 169.57539) (xy 191.130964 169.564349)
				(xy 191.16 169.56) (xy 191.025 168.684) (xy 190.89 169.56) (xy 190.919334 169.564475) (xy 190.931358 169.575801)
				(xy 190.928333 169.605514) (xy 190.925 169.62)
			)
		)
	)
	(zone
		(net 192)
		(net_name "/OCuLink/PCIe_{REF0}.CK+")
		(layer "F.Cu")
		(name "$teardrop_padvia$")
		(hatch none 0.1)
		(priority 32054)
		(attr
			(teardrop
				(type padvia)
			)
		)
		(connect_pads yes
			(clearance 0)
		)
		(min_thickness 0.0254)
		(filled_areas_thickness no)
		(fill yes
			(thermal_gap 0.5)
			(thermal_bridge_width 0.5)
			(island_removal_mode 1)
			(island_area_min 10)
		)
		(polygon
			(pts
				(xy 111.801 152.91) (xy 111.793802 152.889352) (xy 111.784208 152.857016) (xy 111.791035 152.842993)
				(xy 111.8125 152.833004) (xy 111.7 152.584) (xy 111.5875 152.833004) (xy 111.608676 152.842729)
				(xy 111.615731 152.856357) (xy 111.606198 152.889352) (xy 111.599 152.91)
			)
		)
	)
	(zone
		(net 2)
		(net_name "+3V3")
		(layer "F.Cu")
		(name "$teardrop_padvia$")
		(hatch none 0.1)
		(priority 30082)
		(attr
			(teardrop
				(type padvia)
			)
		)
		(connect_pads yes
			(clearance 0)
		)
		(min_thickness 0.0254)
		(filled_areas_thickness no)
		(fill yes
			(thermal_gap 0.5)
			(thermal_bridge_width 0.5)
			(island_removal_mode 1)
			(island_area_min 10)
		)
		(polygon
			(pts
				(xy 197.80861 73.469957) (xy 197.813461 73.37858) (xy 197.827419 73.306651) (xy 197.87436 73.2051)
				(xy 197.93378 73.126257) (xy 198.020411 73.010502) (xy 197.70861 72.801163) (xy 197.396809 73.010502)
				(xy 197.48344 73.126258) (xy 197.53478 73.19314) (xy 197.574276 73.262875) (xy 197.599646 73.350226)
				(xy 197.60861 73.469957)
			)
		)
	)
	(zone
		(net 604)
		(net_name "Net-(U37-~{OE2})")
		(layer "F.Cu")
		(name "$teardrop_padvia$")
		(hatch none 0.1)
		(priority 30915)
		(attr
			(teardrop
				(type padvia)
			)
		)
		(connect_pads yes
			(clearance 0)
		)
		(min_thickness 0.0254)
		(filled_areas_thickness no)
		(fill yes
			(thermal_gap 0.5)
			(thermal_bridge_width 0.5)
			(island_removal_mode 1)
			(island_area_min 10)
		)
		(polygon
			(pts
				(xy 216.363 136.3975) (xy 216.29834 136.377342) (xy 216.265588 136.350868) (xy 216.236569 136.313281)
				(xy 216.201798 136.218202) (xy 215.924 136.47) (xy 216.201798 136.721798) (xy 216.216282 136.663071)
				(xy 216.237602 136.614357) (xy 216.264918 136.574836) (xy 216.295879 136.546246) (xy 216.328534 136.528797)
				(xy 216.361196 136.522518) (xy 216.363 136.5225)
			)
		)
	)
	(zone
		(net 1)
		(net_name "GND")
		(layer "F.Cu")
		(name "$teardrop_padvia$")
		(hatch none 0.1)
		(priority 31226)
		(attr
			(teardrop
				(type padvia)
			)
		)
		(connect_pads yes
			(clearance 0)
		)
		(min_thickness 0.0254)
		(filled_areas_thickness no)
		(fill yes
			(thermal_gap 0.5)
			(thermal_bridge_width 0.5)
			(island_removal_mode 1)
			(island_area_min 10)
		)
		(polygon
			(pts
				(xy 204.125 167.900677) (xy 204.129737 167.809676) (xy 204.142896 167.742587) (xy 204.175418 167.655855)
				(xy 204.207644 167.575358) (xy 204 167.499) (xy 203.803541 167.602363) (xy 203.855343 167.685863)
				(xy 203.904833 167.771955) (xy 203.919614 167.82716) (xy 203.925 167.900677)
			)
		)
	)
	(zone
		(net 978)
		(net_name "/PCIe redriver/RX_EQ0")
		(layer "F.Cu")
		(name "$teardrop_padvia$")
		(hatch none 0.1)
		(priority 31137)
		(attr
			(teardrop
				(type padvia)
			)
		)
		(connect_pads yes
			(clearance 0)
		)
		(min_thickness 0.0254)
		(filled_areas_thickness no)
		(fill yes
			(thermal_gap 0.5)
			(thermal_bridge_width 0.5)
			(island_removal_mode 1)
			(island_area_min 10)
		)
		(polygon
			(pts
				(xy 190.88187 140.861966) (xy 190.937862 140.833937) (xy 191.022261 140.83902) (xy 191.07199 140.858058)
				(xy 191.124339 140.889656) (xy 191.134061 140.89686) (xy 191.130418 140.52503) (xy 190.758587 140.521386)
				(xy 190.792026 140.572996) (xy 190.813204 140.622365) (xy 190.823241 140.669066) (xy 190.822671 140.710667)
				(xy 190.812823 140.745251) (xy 190.794808 140.772223) (xy 190.793482 140.773578)
			)
		)
	)
	(zone
		(net 951)
		(net_name "/2xSFP+/KR to SFI #2/BYP_TX-")
		(layer "F.Cu")
		(name "$teardrop_padvia$")
		(hatch none 0.1)
		(priority 31961)
		(attr
			(teardrop
				(type padvia)
			)
		)
		(connect_pads yes
			(clearance 0)
		)
		(min_thickness 0.0254)
		(filled_areas_thickness no)
		(fill yes
			(thermal_gap 0.5)
			(thermal_bridge_width 0.5)
			(island_removal_mode 1)
			(island_area_min 10)
		)
		(polygon
			(pts
				(xy 128.68 148.527721) (xy 128.655938 148.458348) (xy 128.619423 148.348401) (xy 128.609113 148.288313)
				(xy 128.61 148.226463) (xy 128.41 148.254) (xy 128.351231 148.485) (xy 128.432579 148.479702) (xy 128.484596 148.488493)
				(xy 128.506116 148.502345) (xy 128.518354 148.522403) (xy 128.52 148.527721)
			)
		)
	)
	(zone
		(net 63)
		(net_name "Net-(U18-V_{CC})")
		(layer "F.Cu")
		(name "$teardrop_padvia$")
		(hatch none 0.1)
		(priority 32128)
		(attr
			(teardrop
				(type padvia)
			)
		)
		(connect_pads yes
			(clearance 0)
		)
		(min_thickness 0.0254)
		(filled_areas_thickness no)
		(fill yes
			(thermal_gap 0.5)
			(thermal_bridge_width 0.5)
			(island_removal_mode 1)
			(island_area_min 10)
		)
		(polygon
			(pts
				(xy 311.327499 122.297078) (xy 311.326024 122.279612) (xy 311.325895 122.238167) (xy 311.334882 122.217153)
				(xy 311.354999 122.198011) (xy 311.264999 121.957999) (xy 311.174999 122.198011) (xy 311.194418 122.216155)
				(xy 311.203605 122.23606) (xy 311.203974 122.279612) (xy 311.202499 122.297078)
			)
		)
	)
	(zone
		(net 527)
		(net_name "/Backplane/GPIO")
		(layer "F.Cu")
		(name "$teardrop_padvia$")
		(hatch none 0.1)
		(priority 31699)
		(attr
			(teardrop
				(type padvia)
			)
		)
		(connect_pads yes
			(clearance 0)
		)
		(min_thickness 0.0254)
		(filled_areas_thickness no)
		(fill yes
			(thermal_gap 0.5)
			(thermal_bridge_width 0.5)
			(island_removal_mode 1)
			(island_area_min 10)
		)
		(polygon
			(pts
				(xy 130.3375 77.659323) (xy 130.332682 77.728763) (xy 130.31896 77.780087) (xy 130.272245 77.855628)
				(xy 130.262702 77.867768) (xy 130.212919 77.934997) (xy 130.4 78.061) (xy 130.587081 77.934997)
				(xy 130.537299 77.867769) (xy 130.482894 77.784603) (xy 130.46781 77.731748) (xy 130.4625 77.659323)
			)
		)
	)
	(zone
		(net 326)
		(net_name "/Com Express 7 Interfaces/PCIe_{B2Ax4}.TX1+")
		(layer "F.Cu")
		(name "$teardrop_padvia$")
		(hatch none 0.1)
		(priority 30366)
		(attr
			(teardrop
				(type padvia)
			)
		)
		(connect_pads yes
			(clearance 0)
		)
		(min_thickness 0.0254)
		(filled_areas_thickness no)
		(fill yes
			(thermal_gap 0.5)
			(thermal_bridge_width 0.5)
			(island_removal_mode 1)
			(island_area_min 10)
		)
		(polygon
			(pts
				(xy 294.6535 73.2) (xy 294.656524 73.214169) (xy 294.658552 73.244507) (xy 294.645562 73.255622)
				(xy 294.61522 73.26) (xy 294.699 74.036) (xy 294.849 73.814533) (xy 294.829652 73.60088) (xy 294.844397 73.355527)
				(xy 294.8555 73.2)
			)
		)
	)
	(zone
		(net 1)
		(net_name "GND")
		(layer "F.Cu")
		(name "$teardrop_padvia$")
		(hatch none 0.1)
		(priority 31199)
		(attr
			(teardrop
				(type padvia)
			)
		)
		(connect_pads yes
			(clearance 0)
		)
		(min_thickness 0.0254)
		(filled_areas_thickness no)
		(fill yes
			(thermal_gap 0.5)
			(thermal_bridge_width 0.5)
			(island_removal_mode 1)
			(island_area_min 10)
		)
		(polygon
			(pts
				(xy 218.925 157.399323) (xy 218.92028 157.468646) (xy 218.907244 157.521549) (xy 218.855344 157.614135)
				(xy 218.803541 157.697636) (xy 219 157.801) (xy 219.207644 157.724641) (xy 219.175418 157.644142)
				(xy 219.139035 157.542683) (xy 219.125 157.399323)
			)
		)
	)
	(zone
		(net 585)
		(net_name "Net-(U21-FB)")
		(layer "F.Cu")
		(name "$teardrop_padvia$")
		(hatch none 0.1)
		(priority 30493)
		(attr
			(teardrop
				(type padvia)
			)
		)
		(connect_pads yes
			(clearance 0)
		)
		(min_thickness 0.0254)
		(filled_areas_thickness no)
		(fill yes
			(thermal_gap 0.5)
			(thermal_bridge_width 0.5)
			(island_removal_mode 1)
			(island_area_min 10)
		)
		(polygon
			(pts
				(xy 314.154943 97.257556) (xy 314.10509 97.179739) (xy 314.07697 97.058296) (xy 314.075756 96.984024)
				(xy 314.085007 96.903738) (xy 314.085499 96.901026) (xy 313.764792 96.955793) (xy 313.685025 97.2515)
				(xy 313.771465 97.247962) (xy 313.851098 97.254046) (xy 313.923637 97.269081) (xy 313.986451 97.292044)
				(xy 314.066555 97.345944)
			)
		)
	)
	(zone
		(net 425)
		(net_name "/2xSFP+/I2C_{SFP0}.SDA")
		(layer "F.Cu")
		(name "$teardrop_padvia$")
		(hatch none 0.1)
		(priority 31088)
		(attr
			(teardrop
				(type padvia)
			)
		)
		(connect_pads yes
			(clearance 0)
		)
		(min_thickness 0.0254)
		(filled_areas_thickness no)
		(fill yes
			(thermal_gap 0.5)
			(thermal_bridge_width 0.5)
			(island_removal_mode 1)
			(island_area_min 10)
		)
		(polygon
			(pts
				(xy 179.293 142.937498) (xy 179.233588 142.917725) (xy 179.177503 142.854451) (xy 179.155801 142.805826)
				(xy 179.141127 142.746466) (xy 179.139347 142.734498) (xy 178.879 142.999998) (xy 179.139347 143.265498)
				(xy 179.152197 143.205359) (xy 179.172131 143.155475) (xy 179.198056 143.115356) (xy 179.227876 143.086343)
				(xy 179.259294 143.068852) (xy 179.291105 143.062519) (xy 179.293 143.062498)
			)
		)
	)
	(zone
		(net 2)
		(net_name "+3V3")
		(layer "F.Cu")
		(name "$teardrop_padvia$")
		(hatch none 0.1)
		(priority 30336)
		(attr
			(teardrop
				(type padvia)
			)
		)
		(connect_pads yes
			(clearance 0)
		)
		(min_thickness 0.0254)
		(filled_areas_thickness no)
		(fill yes
			(thermal_gap 0.5)
			(thermal_bridge_width 0.5)
			(island_removal_mode 1)
			(island_area_min 10)
		)
		(polygon
			(pts
				(xy 261.097708 78.3605) (xy 261.063845 78.354719) (xy 261.029223 78.334254) (xy 261.007401 78.307188)
				(xy 260.991708 78.267848) (xy 260.988419 78.252289) (xy 260.281708 78.423) (xy 260.988419 78.593711)
				(xy 261.000009 78.55349) (xy 261.017593 78.524016) (xy 261.065176 78.490827) (xy 261.097708 78.4855)
			)
		)
	)
	(zone
		(net 126)
		(net_name "/2xUSB3.0+RJ45/P2_D+")
		(layer "F.Cu")
		(name "$teardrop_padvia$")
		(hatch none 0.1)
		(priority 31495)
		(attr
			(teardrop
				(type padvia)
			)
		)
		(connect_pads yes
			(clearance 0)
		)
		(min_thickness 0.0254)
		(filled_areas_thickness no)
		(fill yes
			(thermal_gap 0.5)
			(thermal_bridge_width 0.5)
			(island_removal_mode 1)
			(island_area_min 10)
		)
		(polygon
			(pts
				(xy 113.5325 107.459584) (xy 113.528316 107.295141) (xy 113.528177 107.112437) (xy 113.3075 107.099)
				(xy 113.148311 107.252895) (xy 113.215836 107.301773) (xy 113.242179 107.315148) (xy 113.282443 107.336523)
				(xy 113.316001 107.363232) (xy 113.338979 107.402007) (xy 113.3475 107.459584)
			)
		)
	)
	(zone
		(net 555)
		(net_name "/2xUSB3.0+RJ45/EN_1B")
		(layer "F.Cu")
		(name "$teardrop_padvia$")
		(hatch none 0.1)
		(priority 31134)
		(attr
			(teardrop
				(type padvia)
			)
		)
		(connect_pads yes
			(clearance 0)
		)
		(min_thickness 0.0254)
		(filled_areas_thickness no)
		(fill yes
			(thermal_gap 0.5)
			(thermal_bridge_width 0.5)
			(island_removal_mode 1)
			(island_area_min 10)
		)
		(polygon
			(pts
				(xy 121.157 86.1225) (xy 121.216412 86.142273) (xy 121.272497 86.205547) (xy 121.294199 86.254172)
				(xy 121.308873 86.313531) (xy 121.310653 86.3255) (xy 121.571 86.06) (xy 121.310653 85.7945) (xy 121.297804 85.854638)
				(xy 121.27787 85.904522) (xy 121.251945 85.944641) (xy 121.222125 85.973654) (xy 121.190707 85.991146)
				(xy 121.158896 85.997479) (xy 121.157 85.9975)
			)
		)
	)
	(zone
		(net 739)
		(net_name "Net-(U43B-LS_OK_{OUT_B})")
		(layer "F.Cu")
		(name "$teardrop_padvia$")
		(hatch none 0.1)
		(priority 31691)
		(attr
			(teardrop
				(type padvia)
			)
		)
		(connect_pads yes
			(clearance 0)
		)
		(min_thickness 0.0254)
		(filled_areas_thickness no)
		(fill yes
			(thermal_gap 0.5)
			(thermal_bridge_width 0.5)
			(island_removal_mode 1)
			(island_area_min 10)
		)
		(polygon
			(pts
				(xy 147.1875 130.109323) (xy 147.182682 130.178763) (xy 147.16896 130.230087) (xy 147.122245 130.305628)
				(xy 147.112702 130.317768) (xy 147.062919 130.384997) (xy 147.25 130.511) (xy 147.437081 130.384997)
				(xy 147.387299 130.317769) (xy 147.332894 130.234603) (xy 147.31781 130.181748) (xy 147.3125 130.109323)
			)
		)
	)
	(zone
		(net 526)
		(net_name "/Backplane/~{PRSNT}")
		(layer "F.Cu")
		(name "$teardrop_padvia$")
		(hatch none 0.1)
		(priority 31805)
		(attr
			(teardrop
				(type padvia)
			)
		)
		(connect_pads yes
			(clearance 0)
		)
		(min_thickness 0.0254)
		(filled_areas_thickness no)
		(fill yes
			(thermal_gap 0.5)
			(thermal_bridge_width 0.5)
			(island_removal_mode 1)
			(island_area_min 10)
		)
		(polygon
			(pts
				(xy 160.075677 108.5375) (xy 160.006236 108.532682) (xy 159.954913 108.51896) (xy 159.879371 108.472246)
				(xy 159.867231 108.462701) (xy 159.800003 108.412919) (xy 159.674 108.6) (xy 159.800003 108.787081)
				(xy 159.867229 108.737299) (xy 159.950396 108.682894) (xy 160.003251 108.66781) (xy 160.075677 108.6625)
			)
		)
	)
	(zone
		(net 87)
		(net_name "/Com Express 7 Interfaces/PCIe_{B2Ax4}.RX1-")
		(layer "F.Cu")
		(name "$teardrop_padvia$")
		(hatch none 0.1)
		(priority 30372)
		(attr
			(teardrop
				(type padvia)
			)
		)
		(connect_pads yes
			(clearance 0)
		)
		(min_thickness 0.0254)
		(filled_areas_thickness no)
		(fill yes
			(thermal_gap 0.5)
			(thermal_bridge_width 0.5)
			(island_removal_mode 1)
			(island_area_min 10)
		)
		(polygon
			(pts
				(xy 293.745 74.87) (xy 293.741962 74.855816) (xy 293.739898 74.825488) (xy 293.752858 74.814376)
				(xy 293.783157 74.81) (xy 293.698 74.034) (xy 293.548 74.26187) (xy 293.567969 74.47342) (xy 293.557181 74.68361)
				(xy 293.553768 74.717365) (xy 293.543 74.87)
			)
		)
	)
	(zone
		(net 967)
		(net_name "/2xSFP+/KR to SFI #1/BYP_RX-")
		(layer "F.Cu")
		(name "$teardrop_padvia$")
		(hatch none 0.1)
		(priority 31943)
		(attr
			(teardrop
				(type padvia)
			)
		)
		(connect_pads yes
			(clearance 0)
		)
		(min_thickness 0.0254)
		(filled_areas_thickness no)
		(fill yes
			(thermal_gap 0.5)
			(thermal_bridge_width 0.5)
			(island_removal_mode 1)
			(island_area_min 10)
		)
		(polygon
			(pts
				(xy 150.22 148.553721) (xy 150.231736 148.530685) (xy 150.254198 148.514987) (xy 150.330557 148.505864)
				(xy 150.388769 148.511) (xy 150.33 148.28) (xy 150.13 148.252463) (xy 150.125648 148.351256) (xy 150.084062 148.484347)
				(xy 150.06 148.553721)
			)
		)
	)
	(zone
		(net 1)
		(net_name "GND")
		(layer "F.Cu")
		(name "$teardrop_padvia$")
		(hatch none 0.1)
		(priority 30612)
		(attr
			(teardrop
				(type padvia)
			)
		)
		(connect_pads yes
			(clearance 0)
		)
		(min_thickness 0.0254)
		(filled_areas_thickness no)
		(fill yes
			(thermal_gap 0.5)
			(thermal_bridge_width 0.5)
			(island_removal_mode 1)
			(island_area_min 10)
		)
		(polygon
			(pts
				(xy 230.625 164.07) (xy 230.621667 164.055514) (xy 230.61881 164.02539) (xy 230.630964 164.014349)
				(xy 230.66 164.01) (xy 230.525 163.134) (xy 230.39 164.01) (xy 230.419334 164.014475) (xy 230.431358 164.025801)
				(xy 230.428333 164.055514) (xy 230.425 164.07)
			)
		)
	)
	(zone
		(net 892)
		(net_name "Net-(D14-A)")
		(layer "F.Cu")
		(name "$teardrop_padvia$")
		(hatch none 0.1)
		(priority 30172)
		(attr
			(teardrop
				(type padvia)
			)
		)
		(connect_pads yes
			(clearance 0)
		)
		(min_thickness 0.0254)
		(filled_areas_thickness no)
		(fill yes
			(thermal_gap 0.5)
			(thermal_bridge_width 0.5)
			(island_removal_mode 1)
			(island_area_min 10)
		)
		(polygon
			(pts
				(xy 283.4225 76.96) (xy 283.441757 76.90156) (xy 283.502765 76.847485) (xy 283.612366 76.807203)
				(xy 283.72 76.796021) (xy 283.36 76.399) (xy 283 76.796021) (xy 283.075789 76.801642) (xy 283.142251 76.815856)
				(xy 283.19852 76.837451) (xy 283.243209 76.865051) (xy 283.273499 76.895041) (xy 283.291876 76.928017)
				(xy 283.2975 76.96)
			)
		)
	)
	(zone
		(net 135)
		(net_name "Net-(D19-Pad3)")
		(layer "F.Cu")
		(name "$teardrop_padvia$")
		(hatch none 0.1)
		(priority 30163)
		(attr
			(teardrop
				(type padvia)
			)
		)
		(connect_pads yes
			(clearance 0)
		)
		(min_thickness 0.0254)
		(filled_areas_thickness no)
		(fill yes
			(thermal_gap 0.5)
			(thermal_bridge_width 0.5)
			(island_removal_mode 1)
			(island_area_min 10)
		)
		(polygon
			(pts
				(xy 221.248 77.79) (xy 221.267413 77.831941) (xy 221.285699 77.864343) (xy 221.293616 77.895428)
				(xy 221.278578 77.920266) (xy 221.228 77.933927) (xy 221.498 78.411) (xy 221.768 77.933927) (xy 221.728208 77.92573)
				(xy 221.707777 77.9113) (xy 221.704766 77.878573) (xy 221.728587 77.831941) (xy 221.748 77.79)
			)
		)
	)
	(zone
		(net 197)
		(net_name "/OCuLink/PCIe_{x4}.RX3-")
		(layer "F.Cu")
		(name "$teardrop_padvia$")
		(hatch none 0.1)
		(priority 32065)
		(attr
			(teardrop
				(type padvia)
			)
		)
		(connect_pads yes
			(clearance 0)
		)
		(min_thickness 0.0254)
		(filled_areas_thickness no)
		(fill yes
			(thermal_gap 0.5)
			(thermal_bridge_width 0.5)
			(island_removal_mode 1)
			(island_area_min 10)
		)
		(polygon
			(pts
				(xy 106.703 152.138) (xy 106.695802 152.117352) (xy 106.686208 152.085016) (xy 106.693035 152.070993)
				(xy 106.7145 152.061004) (xy 106.602 151.812) (xy 106.4895 152.061004) (xy 106.510676 152.070729)
				(xy 106.517731 152.084357) (xy 106.508198 152.117352) (xy 106.501 152.138)
			)
		)
	)
	(zone
		(net 315)
		(net_name "Net-(J12H-VCC_RTC)")
		(layer "F.Cu")
		(name "$teardrop_padvia$")
		(hatch none 0.1)
		(priority 30686)
		(attr
			(teardrop
				(type padvia)
			)
		)
		(connect_pads yes
			(clearance 0)
		)
		(min_thickness 0.0254)
		(filled_areas_thickness no)
		(fill yes
			(thermal_gap 0.5)
			(thermal_bridge_width 0.5)
			(island_removal_mode 1)
			(island_area_min 10)
		)
		(polygon
			(pts
				(xy 198.9625 167.75) (xy 198.951563 167.788823) (xy 198.929805 167.803933) (xy 198.89 167.81) (xy 199.025 168.686)
				(xy 199.16 167.81) (xy 199.124719 167.805483) (xy 199.103203 167.793862) (xy 199.088005 167.761039)
				(xy 199.0875 167.75)
			)
		)
	)
	(zone
		(net 1)
		(net_name "GND")
		(layer "F.Cu")
		(hatch edge 0.5)
		(priority 36)
		(connect_pads yes
			(clearance 0.15)
		)
		(min_thickness 0.25)
		(filled_areas_thickness no)
		(fill yes
			(thermal_gap 0.5)
			(thermal_bridge_width 0.5)
			(smoothing fillet)
			(radius 0.2)
		)
		(polygon
			(pts
				(xy 116.3 87.26) (xy 116.3 86.56) (xy 116.25 86.51) (xy 112.95 86.51) (xy 112.4 87.06) (xy 109.3 87.06)
				(xy 109.3 89.16) (xy 113 89.16) (xy 114.9 87.26)
			)
		)
	)
	(zone
		(net 117)
		(net_name "/2xSFP+/KR to SFI #2/CLK-")
		(layer "F.Cu")
		(name "$teardrop_padvia$")
		(hatch none 0.1)
		(priority 30057)
		(attr
			(teardrop
				(type padvia)
			)
		)
		(connect_pads yes
			(clearance 0)
		)
		(min_thickness 0.0254)
		(filled_areas_thickness no)
		(fill yes
			(thermal_gap 0.5)
			(thermal_bridge_width 0.5)
			(island_removal_mode 1)
			(island_area_min 10)
		)
		(polygon
			(pts
				(xy 123.365 139.537218) (xy 123.381955 139.508121) (xy 123.406702 139.485041) (xy 123.483444 139.454015)
				(xy 123.616601 139.444482) (xy 123.794172 139.46) (xy 123.74 138.934) (xy 123.34 138.866481) (xy 123.322258 139.103192)
				(xy 123.269236 139.348707) (xy 123.205 139.537218)
			)
		)
	)
	(zone
		(net 91)
		(net_name "/Com Express 7 Interfaces/PCIe_{B2Ax4}.RX1+")
		(layer "F.Cu")
		(name "$teardrop_padvia$")
		(hatch none 0.1)
		(priority 31344)
		(attr
			(teardrop
				(type padvia)
			)
		)
		(connect_pads yes
			(clearance 0)
		)
		(min_thickness 0.0254)
		(filled_areas_thickness no)
		(fill yes
			(thermal_gap 0.5)
			(thermal_bridge_width 0.5)
			(island_removal_mode 1)
			(island_area_min 10)
		)
		(polygon
			(pts
				(xy 293.154 75.019852) (xy 293.149265 75.066638) (xy 293.136121 75.10209) (xy 293.091113 75.150287)
				(xy 293.052893 75.174463) (xy 293.009726 75.201832) (xy 292.967768 75.238495) (xy 293.131 75.388348)
				(xy 293.351677 75.367488) (xy 293.347048 75.266817) (xy 293.35048 75.18345) (xy 293.350605 75.181383)
				(xy 293.356 75.019852)
			)
		)
	)
	(zone
		(net 595)
		(net_name "/Misc/PWM_{SRCSEL}")
		(layer "F.Cu")
		(name "$teardrop_padvia$")
		(hatch none 0.1)
		(priority 30495)
		(attr
			(teardrop
				(type padvia)
			)
		)
		(connect_pads yes
			(clearance 0)
		)
		(min_thickness 0.0254)
		(filled_areas_thickness no)
		(fill yes
			(thermal_gap 0.5)
			(thermal_bridge_width 0.5)
			(island_removal_mode 1)
			(island_area_min 10)
		)
		(polygon
			(pts
				(xy 252.843944 84.839443) (xy 252.921761 84.78959) (xy 253.043204 84.76147) (xy 253.117476 84.760256)
				(xy 253.197762 84.769507) (xy 253.200474 84.769999) (xy 253.145707 84.449292) (xy 252.85 84.369525)
				(xy 252.853538 84.455965) (xy 252.847454 84.535598) (xy 252.832419 84.608137) (xy 252.809456 84.670951)
				(xy 252.755556 84.751055)
			)
		)
	)
	(zone
		(net 283)
		(net_name "/Misc/TACH_{C5V}")
		(layer "F.Cu")
		(name "$teardrop_padvia$")
		(hatch none 0.1)
		(priority 32030)
		(attr
			(teardrop
				(type padvia)
			)
		)
		(connect_pads yes
			(clearance 0)
		)
		(min_thickness 0.0254)
		(filled_areas_thickness no)
		(fill yes
			(thermal_gap 0.5)
			(thermal_bridge_width 0.5)
			(island_removal_mode 1)
			(island_area_min 10)
		)
		(polygon
			(pts
				(xy 237.059207 76.843) (xy 237.053685 76.870072) (xy 237.035029 76.895611) (xy 237.00841 76.91178)
				(xy 236.969669 76.921399) (xy 236.941707 76.923) (xy 237.121707 77.124) (xy 237.301707 76.923) (xy 237.256207 76.918387)
				(xy 237.223239 76.9061) (xy 237.188863 76.867945) (xy 237.184207 76.843)
			)
		)
	)
	(zone
		(net 999)
		(net_name "Net-(C101-Pad1)")
		(layer "F.Cu")
		(name "$teardrop_padvia$")
		(hatch none 0.1)
		(priority 31004)
		(attr
			(teardrop
				(type padvia)
			)
		)
		(connect_pads yes
			(clearance 0)
		)
		(min_thickness 0.0254)
		(filled_areas_thickness no)
		(fill yes
			(thermal_gap 0.5)
			(thermal_bridge_width 0.5)
			(island_removal_mode 1)
			(island_area_min 10)
		)
		(polygon
			(pts
				(xy 247.912 127.8925) (xy 247.974866 127.912469) (xy 248.006844 127.938921) (xy 248.035358 127.976332)
				(xy 248.057882 128.023527) (xy 248.073093 128.081167) (xy 248.073202 128.081798) (xy 248.351 127.83)
				(xy 248.073202 127.578202) (xy 248.058905 127.633635) (xy 248.037825 127.67952) (xy 248.01046 127.717201)
				(xy 247.979552 127.744434) (xy 247.946265 127.761472) (xy 247.913434 127.767489) (xy 247.912 127.7675)
			)
		)
	)
	(zone
		(net 549)
		(net_name "Net-(R14-Pad2)")
		(layer "F.Cu")
		(name "$teardrop_padvia$")
		(hatch none 0.1)
		(priority 30331)
		(attr
			(teardrop
				(type padvia)
			)
		)
		(connect_pads yes
			(clearance 0)
		)
		(min_thickness 0.0254)
		(filled_areas_thickness no)
		(fill yes
			(thermal_gap 0.5)
			(thermal_bridge_width 0.5)
			(island_removal_mode 1)
			(island_area_min 10)
		)
		(polygon
			(pts
				(xy 135.845461 113.525961) (xy 135.89417 113.485415) (xy 135.957976 113.450465) (xy 136.016861 113.431669)
				(xy 136.084441 113.42303) (xy 136.175474 113.43) (xy 136.120707 113.109293) (xy 135.825 113.029526)
				(xy 135.819956 113.162711) (xy 135.781148 113.27805) (xy 135.714323 113.373873) (xy 135.704039 113.384539)
			)
		)
	)
	(zone
		(net 528)
		(net_name "/Backplane/~{PERST}")
		(layer "F.Cu")
		(name "$teardrop_padvia$")
		(hatch none 0.1)
		(priority 32122)
		(attr
			(teardrop
				(type padvia)
			)
		)
		(connect_pads yes
			(clearance 0)
		)
		(min_thickness 0.0254)
		(filled_areas_thickness no)
		(fill yes
			(thermal_gap 0.5)
			(thermal_bridge_width 0.5)
			(island_removal_mode 1)
			(island_area_min 10)
		)
		(polygon
			(pts
				(xy 315.46 163.3975) (xy 315.453678 163.397596) (xy 315.414175 163.392011) (xy 315.395953 163.377078)
				(xy 315.383005 163.3475) (xy 315.134 163.46) (xy 315.383005 163.5725) (xy 315.394121 163.545506)
				(xy 315.409648 163.530405) (xy 315.453678 163.522404) (xy 315.46 163.5225)
			)
		)
	)
	(zone
		(net 132)
		(net_name "Net-(D18-C_{R})")
		(layer "F.Cu")
		(name "$teardrop_padvia$")
		(hatch none 0.1)
		(priority 31807)
		(attr
			(teardrop
				(type padvia)
			)
		)
		(connect_pads yes
			(clearance 0)
		)
		(min_thickness 0.0254)
		(filled_areas_thickness no)
		(fill yes
			(thermal_gap 0.5)
			(thermal_bridge_width 0.5)
			(island_removal_mode 1)
			(island_area_min 10)
		)
		(polygon
			(pts
				(xy 100.180677 75.7475) (xy 100.111236 75.742682) (xy 100.059913 75.72896) (xy 99.984371 75.682246)
				(xy 99.972231 75.672701) (xy 99.905003 75.622919) (xy 99.779 75.81) (xy 99.905003 75.997081) (xy 99.972229 75.947299)
				(xy 100.055396 75.892894) (xy 100.108251 75.87781) (xy 100.180677 75.8725)
			)
		)
	)
	(zone
		(net 315)
		(net_name "Net-(J12H-VCC_RTC)")
		(layer "F.Cu")
		(name "$teardrop_padvia$")
		(hatch none 0.1)
		(priority 31846)
		(attr
			(teardrop
				(type padvia)
			)
		)
		(connect_pads yes
			(clearance 0)
		)
		(min_thickness 0.0254)
		(filled_areas_thickness no)
		(fill yes
			(thermal_gap 0.5)
			(thermal_bridge_width 0.5)
			(island_removal_mode 1)
			(island_area_min 10)
		)
		(polygon
			(pts
				(xy 167.389127 158.572485) (xy 167.336618 158.618181) (xy 167.290623 158.644768) (xy 167.204174 158.665152)
				(xy 167.188841 158.666988) (xy 167.106105 158.679323) (xy 167.149293 158.900707) (xy 167.370677 158.943895)
				(xy 167.383011 158.86116) (xy 167.403349 158.763881) (xy 167.430057 158.715841) (xy 167.477515 158.660873)
			)
		)
	)
	(zone
		(net 708)
		(net_name "Net-(U32-~{MR})")
		(layer "F.Cu")
		(name "$teardrop_padvia$")
		(hatch none 0.1)
		(priority 30080)
		(attr
			(teardrop
				(type padvia)
			)
		)
		(connect_pads yes
			(clearance 0)
		)
		(min_thickness 0.0254)
		(filled_areas_thickness no)
		(fill yes
			(thermal_gap 0.5)
			(thermal_bridge_width 0.5)
			(island_removal_mode 1)
			(island_area_min 10)
		)
		(polygon
			(pts
				(xy 257.704093 128.1715) (xy 257.770166 128.176305) (xy 257.823433 128.18994) (xy 257.898293 128.236633)
				(xy 257.957924 128.31496) (xy 257.978561 128.350071) (xy 258.039113 128.445079) (xy 258.07945 128.491856)
				(xy 258.130816 128.535956) (xy 258.351 128.235) (xy 258.261228 127.873672) (xy 258.109591 127.926898)
				(xy 258.041595 127.961114) (xy 257.905907 128.020777) (xy 257.818315 128.039522) (xy 257.704093 128.0465)
			)
		)
	)
	(zone
		(net 52)
		(net_name "+5V")
		(layer "F.Cu")
		(name "$teardrop_padvia$")
		(hatch none 0.1)
		(priority 30464)
		(attr
			(teardrop
				(type padvia)
			)
		)
		(connect_pads yes
			(clearance 0)
		)
		(min_thickness 0.0254)
		(filled_areas_thickness no)
		(fill yes
			(thermal_gap 0.5)
			(thermal_bridge_width 0.5)
			(island_removal_mode 1)
			(island_area_min 10)
		)
		(polygon
			(pts
				(xy 235.600708 76.198) (xy 235.60037 76.18113) (xy 235.600949 76.136174) (xy 235.612767 76.088831)
				(xy 235.647346 76.046427) (xy 235.716208 76.016291) (xy 235.450708 75.759) (xy 235.185208 76.016291)
				(xy 235.229977 76.031848) (xy 235.261593 76.052565) (xy 235.294327 76.103701) (xy 235.301046 76.18113)
				(xy 235.300708 76.198)
			)
		)
	)
	(zone
		(net 9)
		(net_name "/Com Express 7 Interfaces/PCIe_{B1x2}.TX0+")
		(layer "F.Cu")
		(name "$teardrop_padvia$")
		(hatch none 0.1)
		(priority 31395)
		(attr
			(teardrop
				(type padvia)
			)
		)
		(connect_pads yes
			(clearance 0)
		)
		(min_thickness 0.0254)
		(filled_areas_thickness no)
		(fill yes
			(thermal_gap 0.5)
			(thermal_bridge_width 0.5)
			(island_removal_mode 1)
			(island_area_min 10)
		)
		(polygon
			(pts
				(xy 203.1815 167.367496) (xy 203.176105 167.205964) (xy 203.172555 167.121553) (xy 203.177177 167.019859)
				(xy 202.9565 166.999) (xy 202.793268 167.148852) (xy 202.861936 167.202992) (xy 202.878392 167.212884)
				(xy 202.917064 167.237384) (xy 202.949279 167.26689) (xy 202.971327 167.308046) (xy 202.9795 167.367496)
			)
		)
	)
	(zone
		(net 1)
		(net_name "GND")
		(layer "F.Cu")
		(name "$teardrop_padvia$")
		(hatch none 0.1)
		(priority 31936)
		(attr
			(teardrop
				(type padvia)
			)
		)
		(connect_pads yes
			(clearance 0)
		)
		(min_thickness 0.0254)
		(filled_areas_thickness no)
		(fill yes
			(thermal_gap 0.5)
			(thermal_bridge_width 0.5)
			(island_removal_mode 1)
			(island_area_min 10)
		)
		(polygon
			(pts
				(xy 112.18 138.01) (xy 112.190115 138.009847) (xy 112.220832 138.01046) (xy 112.25332 138.018782)
				(xy 112.282475 138.042675) (xy 112.303191 138.09) (xy 112.536 137.91) (xy 112.303191 137.73) (xy 112.289833 137.765901)
				(xy 112.271601 137.789199) (xy 112.226276 137.808899) (xy 112.190115 137.810153) (xy 112.18 137.81)
			)
		)
	)
	(zone
		(net 378)
		(net_name "/Com Express 7 Interfaces/USB1.D+")
		(layer "F.Cu")
		(name "$teardrop_padvia$")
		(hatch none 0.1)
		(priority 30451)
		(attr
			(teardrop
				(type padvia)
			)
		)
		(connect_pads yes
			(clearance 0)
		)
		(min_thickness 0.0254)
		(filled_areas_thickness no)
		(fill yes
			(thermal_gap 0.5)
			(thermal_bridge_width 0.5)
			(island_removal_mode 1)
			(island_area_min 10)
		)
		(polygon
			(pts
				(xy 157.318657 71.5275) (xy 157.291935 71.503029) (xy 157.271917 71.470924) (xy 157.249148 71.376011)
				(xy 157.25 71.21316) (xy 156.954 71.31) (xy 156.920508 71.63) (xy 157.040933 71.619599) (xy 157.172853 71.643647)
				(xy 157.299794 71.700278) (xy 157.318657 71.7125)
			)
		)
	)
	(zone
		(net 310)
		(net_name "/Com Express 7 MGMT/~{BIOS_DIS0}")
		(layer "F.Cu")
		(name "$teardrop_padvia$")
		(hatch none 0.1)
		(priority 30688)
		(attr
			(teardrop
				(type padvia)
			)
		)
		(connect_pads yes
			(clearance 0)
		)
		(min_thickness 0.0254)
		(filled_areas_thickness no)
		(fill yes
			(thermal_gap 0.5)
			(thermal_bridge_width 0.5)
			(island_removal_mode 1)
			(island_area_min 10)
		)
		(polygon
			(pts
				(xy 192.4625 167.75) (xy 192.451563 167.788823) (xy 192.429805 167.803933) (xy 192.39 167.81) (xy 192.525 168.686)
				(xy 192.66 167.81) (xy 192.624719 167.805483) (xy 192.603203 167.793862) (xy 192.588005 167.761039)
				(xy 192.5875 167.75)
			)
		)
	)
	(zone
		(net 784)
		(net_name "Net-(U30-1Y)")
		(layer "F.Cu")
		(name "$teardrop_padvia$")
		(hatch none 0.1)
		(priority 31986)
		(attr
			(teardrop
				(type padvia)
			)
		)
		(connect_pads yes
			(clearance 0)
		)
		(min_thickness 0.0254)
		(filled_areas_thickness no)
		(fill yes
			(thermal_gap 0.5)
			(thermal_bridge_width 0.5)
			(island_removal_mode 1)
			(island_area_min 10)
		)
		(polygon
			(pts
				(xy 308.1935 151.998) (xy 308.182563 152.036823) (xy 308.160805 152.051933) (xy 308.121 152.058)
				(xy 308.256 152.434) (xy 308.391 152.058) (xy 308.355719 152.053483) (xy 308.334203 152.041862)
				(xy 308.319005 152.009039) (xy 308.3185 151.998)
			)
		)
	)
	(zone
		(net 373)
		(net_name "Net-(J12D-~{THRM})")
		(layer "F.Cu")
		(name "$teardrop_padvia$")
		(hatch none 0.1)
		(priority 31611)
		(attr
			(teardrop
				(type padvia)
			)
		)
		(connect_pads yes
			(clearance 0)
		)
		(min_thickness 0.0254)
		(filled_areas_thickness no)
		(fill yes
			(thermal_gap 0.5)
			(thermal_bridge_width 0.5)
			(island_removal_mode 1)
			(island_area_min 10)
		)
		(polygon
			(pts
				(xy 192.9625 163.899323) (xy 192.957747 163.960452) (xy 192.94448 164.006552) (xy 192.899229 164.073244)
				(xy 192.88137 164.092341) (xy 192.812919 164.174997) (xy 193 164.301) (xy 193.207644 164.224641)
				(xy 193.149334 164.109581) (xy 193.105855 164.02547) (xy 193.092451 163.971061) (xy 193.0875 163.899323)
			)
		)
	)
	(zone
		(net 24)
		(net_name "/M.2 key E/~{CLKREQ}")
		(layer "F.Cu")
		(name "$teardrop_padvia$")
		(hatch none 0.1)
		(priority 30860)
		(attr
			(teardrop
				(type padvia)
			)
		)
		(connect_pads yes
			(clearance 0)
		)
		(min_thickness 0.0254)
		(filled_areas_thickness no)
		(fill yes
			(thermal_gap 0.5)
			(thermal_bridge_width 0.5)
			(island_removal_mode 1)
			(island_area_min 10)
		)
		(polygon
			(pts
				(xy 154.4085 83.997) (xy 154.369677 83.986063) (xy 154.354567 83.964305) (xy 154.3485 83.9245) (xy 153.5725 84.0595)
				(xy 154.3485 84.1945) (xy 154.353017 84.159219) (xy 154.364638 84.137703) (xy 154.397461 84.122505)
				(xy 154.4085 84.122)
			)
		)
	)
	(zone
		(net 243)
		(net_name "/Com Express 7 Interfaces/PCIe_{B2Bx4}.RX2-")
		(layer "F.Cu")
		(name "$teardrop_padvia$")
		(hatch none 0.1)
		(priority 31447)
		(attr
			(teardrop
				(type padvia)
			)
		)
		(connect_pads yes
			(clearance 0)
		)
		(min_thickness 0.0254)
		(filled_areas_thickness no)
		(fill yes
			(thermal_gap 0.5)
			(thermal_bridge_width 0.5)
			(island_removal_mode 1)
			(island_area_min 10)
		)
		(polygon
			(pts
				(xy 186.436416 125.7065) (xy 186.606647 125.699528) (xy 186.784069 125.697677) (xy 186.801 125.477)
				(xy 186.649081 125.315834) (xy 186.597229 125.384098) (xy 186.586815 125.402419) (xy 186.563455 125.441426)
				(xy 186.535008 125.473955) (xy 186.494865 125.496236) (xy 186.436416 125.5045)
			)
		)
	)
	(zone
		(net 377)
		(net_name "/Com Express 7 Interfaces/USB1.D-")
		(layer "F.Cu")
		(name "$teardrop_padvia$")
		(hatch none 0.1)
		(priority 31492)
		(attr
			(teardrop
				(type padvia)
			)
		)
		(connect_pads yes
			(clearance 0)
		)
		(min_thickness 0.0254)
		(filled_areas_thickness no)
		(fill yes
			(thermal_gap 0.5)
			(thermal_bridge_width 0.5)
			(island_removal_mode 1)
			(island_area_min 10)
		)
		(polygon
			(pts
				(xy 197.504506 164.645978) (xy 197.469609 164.674171) (xy 197.436676 164.688468) (xy 197.374183 164.687628)
				(xy 197.327903 164.673636) (xy 197.275931 164.65795) (xy 197.21751 164.651281) (xy 197.221251 164.872665)
				(xy 197.386794 165.019205) (xy 197.516085 164.890111) (xy 197.635321 164.776793)
			)
		)
	)
	(zone
		(net 640)
		(net_name "Net-(U41-IO0_1)")
		(layer "F.Cu")
		(name "$teardrop_padvia$")
		(hatch none 0.1)
		(priority 32024)
		(attr
			(teardrop
				(type padvia)
			)
		)
		(connect_pads yes
			(clearance 0)
		)
		(min_thickness 0.0254)
		(filled_areas_thickness no)
		(fill yes
			(thermal_gap 0.5)
			(thermal_bridge_width 0.5)
			(island_removal_mode 1)
			(island_area_min 10)
		)
		(polygon
			(pts
				(xy 128.2495 84.872499) (xy 128.255822 84.872403) (xy 128.295325 84.877988) (xy 128.313546 84.892921)
				(xy 128.326494 84.922499) (xy 128.713 84.81) (xy 128.326496 84.697499) (xy 128.31538 84.724492)
				(xy 128.299853 84.739594) (xy 128.255822 84.747595) (xy 128.2495 84.747499)
			)
		)
	)
	(zone
		(net 324)
		(net_name "/Com Express 7 Interfaces/PCIe_{B2Ax4}.TX0+")
		(layer "F.Cu")
		(name "$teardrop_padvia$")
		(hatch none 0.1)
		(priority 31597)
		(attr
			(teardrop
				(type padvia)
			)
		)
		(connect_pads yes
			(clearance 0)
		)
		(min_thickness 0.0254)
		(filled_areas_thickness no)
		(fill yes
			(thermal_gap 0.5)
			(thermal_bridge_width 0.5)
			(island_removal_mode 1)
			(island_area_min 10)
		)
		(polygon
			(pts
				(xy 211.116211 167.424123) (xy 211.152728 167.380889) (xy 211.174756 167.340129) (xy 211.187384 167.262836)
				(xy 211.179773 167.195028) (xy 211.171481 167.124235) (xy 211.176995 167.044332) (xy 210.957207 166.999293)
				(xy 210.831497 167.187081) (xy 210.913542 167.216935) (xy 210.9778 167.239792) (xy 210.987777 167.256866)
				(xy 210.973376 167.281288)
			)
		)
	)
	(zone
		(net 352)
		(net_name "Net-(J12D-LPC_AD3{slash}ESPI_IO_3)")
		(layer "F.Cu")
		(name "$teardrop_padvia$")
		(hatch none 0.1)
		(priority 31615)
		(attr
			(teardrop
				(type padvia)
			)
		)
		(connect_pads yes
			(clearance 0)
		)
		(min_thickness 0.0254)
		(filled_areas_thickness no)
		(fill yes
			(thermal_gap 0.5)
			(thermal_bridge_width 0.5)
			(island_removal_mode 1)
			(island_area_min 10)
		)
		(polygon
			(pts
				(xy 178.9625 164.199323) (xy 178.957747 164.260452) (xy 178.94448 164.306552) (xy 178.899229 164.373244)
				(xy 178.88137 164.392341) (xy 178.812919 164.474997) (xy 179 164.601) (xy 179.207644 164.524641)
				(xy 179.149334 164.409581) (xy 179.105855 164.32547) (xy 179.092451 164.271061) (xy 179.0875 164.199323)
			)
		)
	)
	(zone
		(net 206)
		(net_name "/Backplane/USB.D+")
		(layer "F.Cu")
		(name "$teardrop_padvia$")
		(hatch none 0.1)
		(priority 30622)
		(attr
			(teardrop
				(type padvia)
			)
		)
		(connect_pads yes
			(clearance 0)
		)
		(min_thickness 0.0254)
		(filled_areas_thickness no)
		(fill yes
			(thermal_gap 0.5)
			(thermal_bridge_width 0.5)
			(island_removal_mode 1)
			(island_area_min 10)
		)
		(polygon
			(pts
				(xy 198.6175 169.62) (xy 198.615543 169.607187) (xy 198.615762 169.576049) (xy 198.62949 169.564544)
				(xy 198.66 169.56) (xy 198.525 168.684) (xy 198.39 169.56) (xy 198.420352 169.56448) (xy 198.434128 169.575842)
				(xy 198.434457 169.607187) (xy 198.4325 169.62)
			)
		)
	)
	(zone
		(net 1)
		(net_name "GND")
		(layer "F.Cu")
		(name "$teardrop_padvia$")
		(hatch none 0.1)
		(priority 30710)
		(attr
			(teardrop
				(type padvia)
			)
		)
		(connect_pads yes
			(clearance 0)
		)
		(min_thickness 0.0254)
		(filled_areas_thickness no)
		(fill yes
			(thermal_gap 0.5)
			(thermal_bridge_width 0.5)
			(island_removal_mode 1)
			(island_area_min 10)
		)
		(polygon
			(pts
				(xy 227.1 157.62) (xy 227.096865 157.605714) (xy 227.094488 157.575461) (xy 227.107042 157.564369)
				(xy 227.136651 157.56) (xy 227.025 156.684) (xy 226.875 157.56) (xy 226.90119 157.56447) (xy 226.910657 157.575762)
				(xy 226.90468 157.604279) (xy 226.9 157.62)
			)
		)
	)
	(zone
		(net 372)
		(net_name "/Com Express 7 MGMT/I2C.SDA")
		(layer "F.Cu")
		(name "$teardrop_padvia$")
		(hatch none 0.1)
		(priority 30739)
		(attr
			(teardrop
				(type padvia)
			)
		)
		(connect_pads yes
			(clearance 0)
		)
		(min_thickness 0.0254)
		(filled_areas_thickness no)
		(fill yes
			(thermal_gap 0.5)
			(thermal_bridge_width 0.5)
			(island_removal_mode 1)
			(island_area_min 10)
		)
		(polygon
			(pts
				(xy 303.4145 93.22) (xy 303.409203 93.251401) (xy 303.392126 93.283656) (xy 303.365646 93.309863)
				(xy 303.327224 93.330921) (xy 303.28295 93.34295) (xy 303.475 93.861) (xy 303.66705 93.34295) (xy 303.623198 93.330629)
				(xy 303.589633 93.312077) (xy 303.548347 93.261289) (xy 303.5395 93.22)
			)
		)
	)
	(zone
		(net 362)
		(net_name "Net-(J12D-~{SUS_STAT}{slash}~{ESPI_RESET})")
		(layer "F.Cu")
		(name "$teardrop_padvia$")
		(hatch none 0.1)
		(priority 31867)
		(attr
			(teardrop
				(type padvia)
			)
		)
		(connect_pads yes
			(clearance 0)
		)
		(min_thickness 0.0254)
		(filled_areas_thickness no)
		(fill yes
			(thermal_gap 0.5)
			(thermal_bridge_width 0.5)
			(island_removal_mode 1)
			(island_area_min 10)
		)
		(polygon
			(pts
				(xy 184.722485 165.710873) (xy 184.768181 165.763382) (xy 184.794768 165.809376) (xy 184.815152 165.895825)
				(xy 184.816988 165.911158) (xy 184.829323 165.993895) (xy 185.050707 165.950707) (xy 185.093895 165.729323)
				(xy 185.011158 165.716988) (xy 184.91388 165.696651) (xy 184.86584 165.669943) (xy 184.810873 165.622485)
			)
		)
	)
	(zone
		(net 729)
		(net_name "Net-(U43C-AMUXB)")
		(layer "F.Cu")
		(name "$teardrop_padvia$")
		(hatch none 0.1)
		(priority 30116)
		(attr
			(teardrop
				(type padvia)
			)
		)
		(connect_pads yes
			(clearance 0)
		)
		(min_thickness 0.0254)
		(filled_areas_thickness no)
		(fill yes
			(thermal_gap 0.5)
			(thermal_bridge_width 0.5)
			(island_removal_mode 1)
			(island_area_min 10)
		)
		(polygon
			(pts
				(xy 154.4625 129.377794) (xy 154.467315 129.295733) (xy 154.481019 129.230388) (xy 154.527576 129.13712)
				(xy 154.595787 129.058657) (xy 154.651942 128.997158) (xy 154.711801 128.918339) (xy 154.4 128.709)
				(xy 154.088199 128.918339) (xy 154.185219 129.038517) (xy 154.204214 129.058658) (xy 154.257366 129.117541)
				(xy 154.299591 129.181624) (xy 154.327449 129.264008) (xy 154.3375 129.377794)
			)
		)
	)
	(zone
		(net 646)
		(net_name "Net-(U41-IO0_7)")
		(layer "F.Cu")
		(name "$teardrop_padvia$")
		(hatch none 0.1)
		(priority 32004)
		(attr
			(teardrop
				(type padvia)
			)
		)
		(connect_pads yes
			(clearance 0)
		)
		(min_thickness 0.0254)
		(filled_areas_thickness no)
		(fill yes
			(thermal_gap 0.5)
			(thermal_bridge_width 0.5)
			(island_removal_mode 1)
			(island_area_min 10)
		)
		(polygon
			(pts
				(xy 129.9625 87.9595) (xy 129.962404 87.953178) (xy 129.967989 87.913675) (xy 129.982922 87.895452)
				(xy 130.0125 87.882504) (xy 129.9 87.496) (xy 129.7875 87.882504) (xy 129.814493 87.89362) (xy 129.829595 87.909147)
				(xy 129.837596 87.953178) (xy 129.8375 87.9595)
			)
		)
	)
	(zone
		(net 954)
		(net_name "/2xSFP+/KR to SFI #1/BYP_TX+")
		(layer "F.Cu")
		(name "$teardrop_padvia$")
		(hatch none 0.1)
		(priority 31957)
		(attr
			(teardrop
				(type padvia)
			)
		)
		(connect_pads yes
			(clearance 0)
		)
		(min_thickness 0.0254)
		(filled_areas_thickness no)
		(fill yes
			(thermal_gap 0.5)
			(thermal_bridge_width 0.5)
			(island_removal_mode 1)
			(island_area_min 10)
		)
		(polygon
			(pts
				(xy 155.84 148.52855) (xy 155.815301 148.453648) (xy 155.780633 148.345962) (xy 155.770977 148.287503)
				(xy 155.772 148.227485) (xy 155.572 148.254) (xy 155.512023 148.485) (xy 155.592739 148.479808)
				(xy 155.644487 148.488465) (xy 155.666066 148.502201) (xy 155.678125 148.522056) (xy 155.68 148.52855)
			)
		)
	)
	(zone
		(net 227)
		(net_name "/Com Express 7 Interfaces/PCIe_{B1x4}.TX0+")
		(layer "F.Cu")
		(name "$teardrop_padvia$")
		(hatch none 0.1)
		(priority 31383)
		(attr
			(teardrop
				(type padvia)
			)
		)
		(connect_pads yes
			(clearance 0)
		)
		(min_thickness 0.0254)
		(filled_areas_thickness no)
		(fill yes
			(thermal_gap 0.5)
			(thermal_bridge_width 0.5)
			(island_removal_mode 1)
			(island_area_min 10)
		)
		(polygon
			(pts
				(xy 210.682504 170.8705) (xy 210.72929 170.875235) (xy 210.764742 170.888379) (xy 210.812939 170.933387)
				(xy 210.837116 170.971608) (xy 210.864485 171.014773) (xy 210.901147 171.056731) (xy 211.051 170.8935)
				(xy 211.03014 170.672823) (xy 210.929466 170.677452) (xy 210.846096 170.674019) (xy 210.844035 170.673895)
				(xy 210.682504 170.6685)
			)
		)
	)
	(zone
		(net 687)
		(net_name "/2xSFP+/KR to SFI #2/KR_R.RX+")
		(layer "F.Cu")
		(name "$teardrop_padvia$")
		(hatch none 0.1)
		(priority 31168)
		(attr
			(teardrop
				(type padvia)
			)
		)
		(connect_pads yes
			(clearance 0)
		)
		(min_thickness 0.0254)
		(filled_areas_thickness no)
		(fill yes
			(thermal_gap 0.5)
			(thermal_bridge_width 0.5)
			(island_removal_mode 1)
			(island_area_min 10)
		)
		(polygon
			(pts
				(xy 135.06 143.17679) (xy 135.064788 143.139695) (xy 135.078304 143.115431) (xy 135.120007 143.096705)
				(xy 135.208927 143.101889) (xy 135.274222 143.108714) (xy 135.338773 143.105196) (xy 135.29 142.859)
				(xy 135.044804 142.811227) (xy 135.008876 142.909201) (xy 134.972391 142.964616) (xy 134.922365 143.048601)
				(xy 134.906125 143.104227) (xy 134.9 143.17679)
			)
		)
	)
	(zone
		(net 581)
		(net_name "Net-(U19-FB)")
		(layer "F.Cu")
		(name "$teardrop_padvia$")
		(hatch none 0.1)
		(priority 31077)
		(attr
			(teardrop
				(type padvia)
			)
		)
		(connect_pads yes
			(clearance 0)
		)
		(min_thickness 0.0254)
		(filled_areas_thickness no)
		(fill yes
			(thermal_gap 0.5)
			(thermal_bridge_width 0.5)
			(island_removal_mode 1)
			(island_area_min 10)
		)
		(polygon
			(pts
				(xy 309.237499 105.243) (xy 309.257272 105.183588) (xy 309.320546 105.127503) (xy 309.369171 105.105801)
				(xy 309.428531 105.091127) (xy 309.440499 105.089347) (xy 309.174999 104.829) (xy 308.909499 105.089347)
				(xy 308.969638 105.102197) (xy 309.019522 105.122131) (xy 309.059641 105.148056) (xy 309.088654 105.177876)
				(xy 309.106145 105.209294) (xy 309.112478 105.241105) (xy 309.112499 105.243)
			)
		)
	)
	(zone
		(net 1)
		(net_name "GND")
		(layer "F.Cu")
		(name "$teardrop_padvia$")
		(hatch none 0.1)
		(priority 30614)
		(attr
			(teardrop
				(type padvia)
			)
		)
		(connect_pads yes
			(clearance 0)
		)
		(min_thickness 0.0254)
		(filled_areas_thickness no)
		(fill yes
			(thermal_gap 0.5)
			(thermal_bridge_width 0.5)
			(island_removal_mode 1)
			(island_area_min 10)
		)
		(polygon
			(pts
				(xy 189.625 152.07) (xy 189.621667 152.055514) (xy 189.61881 152.02539) (xy 189.630964 152.014349)
				(xy 189.66 152.01) (xy 189.525 151.134) (xy 189.39 152.01) (xy 189.419334 152.014475) (xy 189.431358 152.025801)
				(xy 189.428333 152.055514) (xy 189.425 152.07)
			)
		)
	)
	(zone
		(net 2)
		(net_name "+3V3")
		(layer "F.Cu")
		(name "$teardrop_padvia$")
		(hatch none 0.1)
		(priority 30891)
		(attr
			(teardrop
				(type padvia)
			)
		)
		(connect_pads yes
			(clearance 0)
		)
		(min_thickness 0.0254)
		(filled_areas_thickness no)
		(fill yes
			(thermal_gap 0.5)
			(thermal_bridge_width 0.5)
			(island_removal_mode 1)
			(island_area_min 10)
		)
		(polygon
			(pts
				(xy 143.34 150.061219) (xy 143.344702 150.025773) (xy 143.357618 149.999777) (xy 143.402254 149.966893)
				(xy 143.439487 149.952763) (xy 143.502003 149.925081) (xy 143.377 149.737) (xy 143.156323 149.714302)
				(xy 143.130973 149.798834) (xy 143.104937 149.845867) (xy 143.060725 149.934341) (xy 143.045743 149.990948)
				(xy 143.04 150.061219)
			)
		)
	)
	(zone
		(net 422)
		(net_name "/2xSFP+/I2C_{LED}.SDA")
		(layer "F.Cu")
		(name "$teardrop_padvia$")
		(hatch none 0.1)
		(priority 31818)
		(attr
			(teardrop
				(type padvia)
			)
		)
		(connect_pads yes
			(clearance 0)
		)
		(min_thickness 0.0254)
		(filled_areas_thickness no)
		(fill yes
			(thermal_gap 0.5)
			(thermal_bridge_width 0.5)
			(island_removal_mode 1)
			(island_area_min 10)
		)
		(polygon
			(pts
				(xy 176.975677 153.8875) (xy 176.906236 153.882682) (xy 176.854913 153.86896) (xy 176.779371 153.822246)
				(xy 176.767231 153.812701) (xy 176.700003 153.762919) (xy 176.574 153.95) (xy 176.700003 154.137081)
				(xy 176.767229 154.087299) (xy 176.850396 154.032894) (xy 176.903251 154.01781) (xy 176.975677 154.0125)
			)
		)
	)
	(zone
		(net 2)
		(net_name "+3V3")
		(layer "F.Cu")
		(name "$teardrop_padvia$")
		(hatch none 0.1)
		(priority 30401)
		(attr
			(teardrop
				(type padvia)
			)
		)
		(connect_pads yes
			(clearance 0)
		)
		(min_thickness 0.0254)
		(filled_areas_thickness no)
		(fill yes
			(thermal_gap 0.5)
			(thermal_bridge_width 0.5)
			(island_removal_mode 1)
			(island_area_min 10)
		)
		(polygon
			(pts
				(xy 114.65 145.253) (xy 114.629597 145.208355) (xy 114.610779 145.174808) (xy 114.602205 145.142345)
				(xy 114.616303 145.115635) (xy 114.6655 145.099347) (xy 114.4 144.839) (xy 114.1345 145.099347)
				(xy 114.172593 145.109167) (xy 114.192358 145.124574) (xy 114.195352 145.1589) (xy 114.170403 145.208355)
				(xy 114.15 145.253)
			)
		)
	)
	(zone
		(net 92)
		(net_name "/Com Express 7 Interfaces/PCIe_{B2Ax4}.RX2+")
		(layer "F.Cu")
		(name "$teardrop_padvia$")
		(hatch none 0.1)
		(priority 31392)
		(attr
			(teardrop
				(type padvia)
			)
		)
		(connect_pads yes
			(clearance 0)
		)
		(min_thickness 0.0254)
		(filled_areas_thickness no)
		(fill yes
			(thermal_gap 0.5)
			(thermal_bridge_width 0.5)
			(island_removal_mode 1)
			(island_area_min 10)
		)
		(polygon
			(pts
				(xy 214.1815 161.867496) (xy 214.176105 161.705964) (xy 214.172555 161.621553) (xy 214.177177 161.519859)
				(xy 213.9565 161.499) (xy 213.793268 161.648852) (xy 213.861936 161.702992) (xy 213.878392 161.712884)
				(xy 213.917064 161.737384) (xy 213.949279 161.76689) (xy 213.971327 161.808046) (xy 213.9795 161.867496)
			)
		)
	)
	(zone
		(net 746)
		(net_name "/2xSFP+/KR to SFI #2/~{TRST}")
		(layer "F.Cu")
		(name "$teardrop_padvia$")
		(hatch none 0.1)
		(priority 30136)
		(attr
			(teardrop
				(type padvia)
			)
		)
		(connect_pads yes
			(clearance 0)
		)
		(min_thickness 0.0254)
		(filled_areas_thickness no)
		(fill yes
			(thermal_gap 0.5)
			(thermal_bridge_width 0.5)
			(island_removal_mode 1)
			(island_area_min 10)
		)
		(polygon
			(pts
				(xy 133.0525 130.227794) (xy 133.057315 130.145733) (xy 133.071019 130.080388) (xy 133.117576 129.98712)
				(xy 133.185787 129.908657) (xy 133.241942 129.847158) (xy 133.301801 129.768339) (xy 132.99 129.559)
				(xy 132.678199 129.768339) (xy 132.775219 129.888517) (xy 132.794214 129.908658) (xy 132.847366 129.967541)
				(xy 132.889591 130.031624) (xy 132.917449 130.114008) (xy 132.9275 130.227794)
			)
		)
	)
	(zone
		(net 382)
		(net_name "Net-(J12D-~{CB_RESET})")
		(layer "F.Cu")
		(name "$teardrop_padvia$")
		(hatch none 0.1)
		(priority 31677)
		(attr
			(teardrop
				(type padvia)
			)
		)
		(connect_pads yes
			(clearance 0)
		)
		(min_thickness 0.0254)
		(filled_areas_thickness no)
		(fill yes
			(thermal_gap 0.5)
			(thermal_bridge_width 0.5)
			(island_removal_mode 1)
			(island_area_min 10)
		)
		(polygon
			(pts
				(xy 307.8205 155.637) (xy 307.826022 155.609928) (xy 307.844678 155.584389) (xy 307.871297 155.56822)
				(xy 307.910038 155.558601) (xy 307.938 155.557) (xy 307.758 155.181) (xy 307.578 155.557) (xy 307.6235 155.561613)
				(xy 307.656468 155.5739) (xy 307.690844 155.612055) (xy 307.6955 155.637)
			)
		)
	)
	(zone
		(net 52)
		(net_name "+5V")
		(layer "F.Cu")
		(name "$teardrop_padvia$")
		(hatch none 0.1)
		(priority 30083)
		(attr
			(teardrop
				(type padvia)
			)
		)
		(connect_pads yes
			(clearance 0)
		)
		(min_thickness 0.0254)
		(filled_areas_thickness no)
		(fill yes
			(thermal_gap 0.5)
			(thermal_bridge_width 0.5)
			(island_removal_mode 1)
			(island_area_min 10)
		)
		(polygon
			(pts
				(xy 195.80861 73.469957) (xy 195.813461 73.37858) (xy 195.827419 73.306651) (xy 195.87436 73.2051)
				(xy 195.93378 73.126257) (xy 196.020411 73.010502) (xy 195.70861 72.801163) (xy 195.396809 73.010502)
				(xy 195.48344 73.126258) (xy 195.53478 73.19314) (xy 195.574276 73.262875) (xy 195.599646 73.350226)
				(xy 195.60861 73.469957)
			)
		)
	)
	(zone
		(net 91)
		(net_name "/Com Express 7 Interfaces/PCIe_{B2Ax4}.RX1+")
		(layer "F.Cu")
		(name "$teardrop_padvia$")
		(hatch none 0.1)
		(priority 30376)
		(attr
			(teardrop
				(type padvia)
			)
		)
		(connect_pads yes
			(clearance 0)
		)
		(min_thickness 0.0254)
		(filled_areas_thickness no)
		(fill yes
			(thermal_gap 0.5)
			(thermal_bridge_width 0.5)
			(island_removal_mode 1)
			(island_area_min 10)
		)
		(polygon
			(pts
				(xy 293.356 74.87) (xy 293.344784 74.713526) (xy 293.330025 74.508886) (xy 293.332958 74.388472)
				(xy 293.349 74.253414) (xy 293.199 74.034) (xy 293.115678 74.81) (xy 293.146281 74.814477) (xy 293.159183 74.825818)
				(xy 293.15702 74.855836) (xy 293.154 74.87)
			)
		)
	)
	(zone
		(net 1)
		(net_name "GND")
		(layer "F.Cu")
		(name "$teardrop_padvia$")
		(hatch none 0.1)
		(priority 30738)
		(attr
			(teardrop
				(type padvia)
			)
		)
		(connect_pads yes
			(clearance 0)
		)
		(min_thickness 0.0254)
		(filled_areas_thickness no)
		(fill yes
			(thermal_gap 0.5)
			(thermal_bridge_width 0.5)
			(island_removal_mode 1)
			(island_area_min 10)
		)
		(polygon
			(pts
				(xy 305.7645 149.77) (xy 305.759203 149.801401) (xy 305.742126 149.833656) (xy 305.715646 149.859863)
				(xy 305.677224 149.880921) (xy 305.63295 149.89295) (xy 305.825 150.411) (xy 306.01705 149.89295)
				(xy 305.973198 149.880629) (xy 305.939633 149.862077) (xy 305.898347 149.811289) (xy 305.8895 149.77)
			)
		)
	)
	(zone
		(net 644)
		(net_name "Net-(U41-IO0_5)")
		(layer "F.Cu")
		(name "$teardrop_padvia$")
		(hatch none 0.1)
		(priority 31079)
		(attr
			(teardrop
				(type padvia)
			)
		)
		(connect_pads yes
			(clearance 0)
		)
		(min_thickness 0.0254)
		(filled_areas_thickness no)
		(fill yes
			(thermal_gap 0.5)
			(thermal_bridge_width 0.5)
			(island_removal_mode 1)
			(island_area_min 10)
		)
		(polygon
			(pts
				(xy 127.318 87.9975) (xy 127.258588 87.977727) (xy 127.202503 87.914453) (xy 127.180801 87.865828)
				(xy 127.166127 87.806468) (xy 127.164347 87.7945) (xy 126.904 88.06) (xy 127.164347 88.3255) (xy 127.177197 88.265361)
				(xy 127.197131 88.215477) (xy 127.223056 88.175358) (xy 127.252876 88.146345) (xy 127.284294 88.128854)
				(xy 127.316105 88.122521) (xy 127.318 88.1225)
			)
		)
	)
	(zone
		(net 350)
		(net_name "Net-(J12D-LPC_AD1{slash}ESPI_IO_1)")
		(layer "F.Cu")
		(name "$teardrop_padvia$")
		(hatch none 0.1)
		(priority 30665)
		(attr
			(teardrop
				(type padvia)
			)
		)
		(connect_pads yes
			(clearance 0)
		)
		(min_thickness 0.0254)
		(filled_areas_thickness no)
		(fill yes
			(thermal_gap 0.5)
			(thermal_bridge_width 0.5)
			(island_removal_mode 1)
			(island_area_min 10)
		)
		(polygon
			(pts
				(xy 178.0875 164.07) (xy 178.098438 164.031177) (xy 178.120195 164.016067) (xy 178.16 164.01) (xy 178.025 163.134)
				(xy 177.89 164.01) (xy 177.925281 164.014517) (xy 177.946797 164.026138) (xy 177.961995 164.058961)
				(xy 177.9625 164.07)
			)
		)
	)
	(zone
		(net 530)
		(net_name "/M.2 key M #2/~{CLKREQ}")
		(layer "F.Cu")
		(name "$teardrop_padvia$")
		(hatch none 0.1)
		(priority 31896)
		(attr
			(teardrop
				(type padvia)
			)
		)
		(connect_pads yes
			(clearance 0)
		)
		(min_thickness 0.0254)
		(filled_areas_thickness no)
		(fill yes
			(thermal_gap 0.5)
			(thermal_bridge_width 0.5)
			(island_removal_mode 1)
			(island_area_min 10)
		)
		(polygon
			(pts
				(xy 298.8865 83.233291) (xy 298.891086 83.307791) (xy 298.903186 83.364316) (xy 298.9327 83.437943)
				(xy 298.957734 83.496663) (xy 298.979323 83.573895) (xy 299.2 83.531) (xy 299.243895 83.309323)
				(xy 299.141289 83.307406) (xy 299.091297 83.309496) (xy 299.049984 83.303227) (xy 299.021876 83.280518)
				(xy 299.0115 83.233291)
			)
		)
	)
	(zone
		(net 108)
		(net_name "/2xSFP+/KR to SFI #1/REFCLK+")
		(layer "F.Cu")
		(name "$teardrop_padvia$")
		(hatch none 0.1)
		(priority 30629)
		(attr
			(teardrop
				(type padvia)
			)
		)
		(connect_pads yes
			(clearance 0)
		)
		(min_thickness 0.0254)
		(filled_areas_thickness no)
		(fill yes
			(thermal_gap 0.5)
			(thermal_bridge_width 0.5)
			(island_removal_mode 1)
			(island_area_min 10)
		)
		(polygon
			(pts
				(xy 143.843657 141.09) (xy 143.79805 141.034807) (xy 143.774544 140.940672) (xy 143.775 140.76316)
				(xy 143.479 140.86) (xy 143.445508 141.18) (xy 143.573895 141.167745) (xy 143.711767 141.190112)
				(xy 143.834974 141.244238) (xy 143.843657 141.25)
			)
		)
	)
	(zone
		(net 2)
		(net_name "+3V3")
		(layer "F.Cu")
		(hatch edge 0.5)
		(priority 26)
		(connect_pads yes
			(clearance 0.15)
		)
		(min_thickness 0.25)
		(filled_areas_thickness no)
		(fill yes
			(thermal_gap 0.2)
			(thermal_bridge_width 0.5)
			(smoothing fillet)
			(radius 0.2)
		)
		(polygon
			(pts
				(xy 181.98 88.23) (xy 180.28 88.23) (xy 180.28 91.23) (xy 181.98 91.23)
			)
		)
	)
	(zone
		(net 578)
		(net_name "/Power/PG_{1V0}")
		(layer "F.Cu")
		(name "$teardrop_padvia$")
		(hatch none 0.1)
		(priority 30988)
		(attr
			(teardrop
				(type padvia)
			)
		)
		(connect_pads yes
			(clearance 0)
		)
		(min_thickness 0.0254)
		(filled_areas_thickness no)
		(fill yes
			(thermal_gap 0.5)
			(thermal_bridge_width 0.5)
			(island_removal_mode 1)
			(island_area_min 10)
		)
		(polygon
			(pts
				(xy 306.6825 130.468) (xy 306.702469 130.405134) (xy 306.728921 130.373156) (xy 306.766332 130.344642)
				(xy 306.813527 130.322118) (xy 306.871167 130.306907) (xy 306.871798 130.306798) (xy 306.62 130.029)
				(xy 306.368202 130.306798) (xy 306.423635 130.321095) (xy 306.46952 130.342175) (xy 306.507201 130.36954)
				(xy 306.534434 130.400448) (xy 306.551472 130.433735) (xy 306.557489 130.466566) (xy 306.5575 130.468)
			)
		)
	)
	(zone
		(net 973)
		(net_name "/PCIe redriver/RX_SW")
		(layer "F.Cu")
		(name "$teardrop_padvia$")
		(hatch none 0.1)
		(priority 31139)
		(attr
			(teardrop
				(type padvia)
			)
		)
		(connect_pads yes
			(clearance 0)
		)
		(min_thickness 0.0254)
		(filled_areas_thickness no)
		(fill yes
			(thermal_gap 0.5)
			(thermal_bridge_width 0.5)
			(island_removal_mode 1)
			(island_area_min 10)
		)
		(polygon
			(pts
				(xy 191.048534 129.461426) (xy 191.104526 129.433397) (xy 191.188925 129.43848) (xy 191.238654 129.457518)
				(xy 191.291003 129.489116) (xy 191.300725 129.49632) (xy 191.297082 129.12449) (xy 190.925251 129.120846)
				(xy 190.95869 129.172456) (xy 190.979868 129.221825) (xy 190.989905 129.268526) (xy 190.989335 129.310127)
				(xy 190.979487 129.344711) (xy 190.961472 129.371683) (xy 190.960146 129.373038)
			)
		)
	)
	(zone
		(net 597)
		(net_name "/Misc/PWM1")
		(layer "F.Cu")
		(name "$teardrop_padvia$")
		(hatch none 0.1)
		(priority 30740)
		(attr
			(teardrop
				(type padvia)
			)
		)
		(connect_pads yes
			(clearance 0)
		)
		(min_thickness 0.0254)
		(filled_areas_thickness no)
		(fill yes
			(thermal_gap 0.5)
			(thermal_bridge_width 0.5)
			(island_removal_mode 1)
			(island_area_min 10)
		)
		(polygon
			(pts
				(xy 255.660707 79.0225) (xy 255.604256 79.002455) (xy 255.577446 78.976276) (xy 255.554655 78.939267)
				(xy 255.528772 78.8375) (xy 255.149707 79.085) (xy 255.528772 79.3325) (xy 255.538581 79.275174)
				(xy 255.555735 79.228495) (xy 255.578881 79.191945) (xy 255.605972 79.166305) (xy 255.660707 79.1475)
			)
		)
	)
	(zone
		(net 2)
		(net_name "+3V3")
		(layer "F.Cu")
		(name "$teardrop_padvia$")
		(hatch none 0.1)
		(priority 31514)
		(attr
			(teardrop
				(type padvia)
			)
		)
		(connect_pads yes
			(clearance 0)
		)
		(min_thickness 0.0254)
		(filled_areas_thickness no)
		(fill yes
			(thermal_gap 0.5)
			(thermal_bridge_width 0.5)
			(island_removal_mode 1)
			(island_area_min 10)
		)
		(polygon
			(pts
				(xy 218.407095 130.620999) (xy 218.486808 130.616481) (xy 218.547892 130.604853) (xy 218.616275 130.582625)
				(xy 218.677595 130.562211) (xy 218.754788 130.546677) (xy 218.727999 130.326) (xy 218.538625 130.204119)
				(xy 218.512637 130.272385) (xy 218.506148 130.308234) (xy 218.497793 130.351364) (xy 218.483077 130.387293)
				(xy 218.455133 130.411884) (xy 218.407096 130.421)
			)
		)
	)
	(zone
		(net 620)
		(net_name "/PCIe misc/DIF4-")
		(layer "F.Cu")
		(name "$teardrop_padvia$")
		(hatch none 0.1)
		(priority 30412)
		(attr
			(teardrop
				(type padvia)
			)
		)
		(connect_pads yes
			(clearance 0)
		)
		(min_thickness 0.0254)
		(filled_areas_thickness no)
		(fill yes
			(thermal_gap 0.5)
			(thermal_bridge_width 0.5)
			(island_removal_mode 1)
			(island_area_min 10)
		)
		(polygon
			(pts
				(xy 220.309758 130.056499) (xy 220.397422 130.011634) (xy 220.508018 129.974212) (xy 220.58433 129.961584)
				(xy 220.662914 129.961952) (xy 220.70997 129.97) (xy 220.680999 129.65) (xy 220.385 129.549742)
				(xy 220.387519 129.667308) (xy 220.376143 129.755629) (xy 220.359544 129.800712) (xy 220.335152 129.834691)
				(xy 220.309761 129.8545)
			)
		)
	)
	(zone
		(net 897)
		(net_name "Net-(J2B-RS1)")
		(layer "F.Cu")
		(name "$teardrop_padvia$")
		(hatch none 0.1)
		(priority 31709)
		(attr
			(teardrop
				(type padvia)
			)
		)
		(connect_pads yes
			(clearance 0)
		)
		(min_thickness 0.0254)
		(filled_areas_thickness no)
		(fill yes
			(thermal_gap 0.5)
			(thermal_bridge_width 0.5)
			(island_removal_mode 1)
			(island_area_min 10)
		)
		(polygon
			(pts
				(xy 137.2375 167.159323) (xy 137.232682 167.228763) (xy 137.21896 167.280087) (xy 137.172245 167.355628)
				(xy 137.162702 167.367768) (xy 137.112919 167.434997) (xy 137.3 167.561) (xy 137.487081 167.434997)
				(xy 137.437299 167.367769) (xy 137.382894 167.284603) (xy 137.36781 167.231748) (xy 137.3625 167.159323)
			)
		)
	)
	(zone
		(net 2)
		(net_name "+3V3")
		(layer "F.Cu")
		(name "$teardrop_padvia$")
		(hatch none 0.1)
		(priority 30755)
		(attr
			(teardrop
				(type padvia)
			)
		)
		(connect_pads yes
			(clearance 0)
		)
		(min_thickness 0.0254)
		(filled_areas_thickness no)
		(fill yes
			(thermal_gap 0.5)
			(thermal_bridge_width 0.5)
			(island_removal_mode 1)
			(island_area_min 10)
		)
		(polygon
			(pts
				(xy 146.679823 88.9585) (xy 146.8374 88.965432) (xy 146.950934 88.993956) (xy 146.992722 89.011)
				(xy 147.0815 88.8085) (xy 146.992722 88.606) (xy 146.896677 88.640383) (xy 146.794796 88.655601)
				(xy 146.679823 88.6585)
			)
		)
	)
	(zone
		(net 603)
		(net_name "Net-(U37-~{OE1})")
		(layer "F.Cu")
		(name "$teardrop_padvia$")
		(hatch none 0.1)
		(priority 31532)
		(attr
			(teardrop
				(type padvia)
			)
		)
		(connect_pads yes
			(clearance 0)
		)
		(min_thickness 0.0254)
		(filled_areas_thickness no)
		(fill yes
			(thermal_gap 0.5)
			(thermal_bridge_width 0.5)
			(island_removal_mode 1)
			(island_area_min 10)
		)
		(polygon
			(pts
				(xy 213.429141 132.192472) (xy 213.408921 132.19175) (xy 213.39165 132.180389) (xy 213.365709 132.124172)
				(xy 213.353772 132.031054) (xy 213.069293 132.260707) (xy 213.339295 132.51061) (xy 213.367029 132.414532)
				(xy 213.426709 132.333276) (xy 213.465628 132.302959) (xy 213.504734 132.28433) (xy 213.517528 132.280859)
			)
		)
	)
	(zone
		(net 490)
		(net_name "/2xSFP+/MDIO1.MDIO")
		(layer "F.Cu")
		(name "$teardrop_padvia$")
		(hatch none 0.1)
		(priority 31728)
		(attr
			(teardrop
				(type padvia)
			)
		)
		(connect_pads yes
			(clearance 0)
		)
		(min_thickness 0.0254)
		(filled_areas_thickness no)
		(fill yes
			(thermal_gap 0.5)
			(thermal_bridge_width 0.5)
			(island_removal_mode 1)
			(island_area_min 10)
		)
		(polygon
			(pts
				(xy 125.6195 152.111323) (xy 125.614682 152.180763) (xy 125.60096 152.232087) (xy 125.554245 152.307628)
				(xy 125.544702 152.319768) (xy 125.494919 152.386997) (xy 125.682 152.513) (xy 125.869081 152.386997)
				(xy 125.819299 152.319769) (xy 125.764894 152.236603) (xy 125.74981 152.183748) (xy 125.7445 152.111323)
			)
		)
	)
	(zone
		(net 732)
		(net_name "Net-(U43C-CLKOUTB+)")
		(layer "F.Cu")
		(name "$teardrop_padvia$")
		(hatch none 0.1)
		(priority 30137)
		(attr
			(teardrop
				(type padvia)
			)
		)
		(connect_pads yes
			(clearance 0)
		)
		(min_thickness 0.0254)
		(filled_areas_thickness no)
		(fill yes
			(thermal_gap 0.5)
			(thermal_bridge_width 0.5)
			(island_removal_mode 1)
			(island_area_min 10)
		)
		(polygon
			(pts
				(xy 156.866396 129.988007) (xy 156.811775 129.926577) (xy 156.775259 129.87068) (xy 156.742229 129.771809)
				(xy 156.73498 129.668095) (xy 156.731201 129.5849) (xy 156.717794 129.486841) (xy 156.349293 129.559293)
				(xy 156.276841 129.927794) (xy 156.430423 129.944169) (xy 156.458095 129.94498) (xy 156.537316 129.949032)
				(xy 156.612488 129.964488) (xy 156.690441 130.003043) (xy 156.778007 130.076396)
			)
		)
	)
	(zone
		(net 400)
		(net_name "/Com Express 7 MGMT/FAN_PWM")
		(layer "F.Cu")
		(name "$teardrop_padvia$")
		(hatch none 0.1)
		(priority 31767)
		(attr
			(teardrop
				(type padvia)
			)
		)
		(connect_pads yes
			(clearance 0)
		)
		(min_thickness 0.0254)
		(filled_areas_thickness no)
		(fill yes
			(thermal_gap 0.5)
			(thermal_bridge_width 0.5)
			(island_removal_mode 1)
			(island_area_min 10)
		)
		(polygon
			(pts
				(xy 233.670031 79.1345) (xy 233.739472 79.139318) (xy 233.790796 79.15304) (xy 233.866337 79.199755)
				(xy 233.878477 79.209299) (xy 233.945705 79.259081) (xy 234.071708 79.072) (xy 233.945705 78.884919)
				(xy 233.878476 78.934702) (xy 233.79531 78.989106) (xy 233.742456 79.00419) (xy 233.670031 79.0095)
			)
		)
	)
	(zone
		(net 55)
		(net_name "/USB-C console/USB_D+")
		(layer "F.Cu")
		(name "$teardrop_padvia$")
		(hatch none 0.1)
		(priority 30716)
		(attr
			(teardrop
				(type padvia)
			)
		)
		(connect_pads yes
			(clearance 0)
		)
		(min_thickness 0.0254)
		(filled_areas_thickness no)
		(fill yes
			(thermal_gap 0.5)
			(thermal_bridge_width 0.5)
			(island_removal_mode 1)
			(island_area_min 10)
		)
		(polygon
			(pts
				(xy 102.071908 82.92899) (xy 102.075516 82.946311) (xy 102.079637 82.979833) (xy 102.07015 82.992147)
				(xy 102.046198 82.997) (xy 102.099805 83.81048) (xy 102.225 83.640086) (xy 102.216297 83.383973)
				(xy 102.237747 83.137695) (xy 102.253352 82.965082)
			)
		)
	)
	(zone
		(net 868)
		(net_name "/Backplane/PCIe_{x2}.TX1+")
		(layer "F.Cu")
		(name "$teardrop_padvia$")
		(hatch none 0.1)
		(priority 30248)
		(attr
			(teardrop
				(type padvia)
			)
		)
		(connect_pads yes
			(clearance 0)
		)
		(min_thickness 0.0254)
		(filled_areas_thickness no)
		(fill yes
			(thermal_gap 0.5)
			(thermal_bridge_width 0.5)
			(island_removal_mode 1)
			(island_area_min 10)
		)
		(polygon
			(pts
				(xy 202.9795 150.2) (xy 202.98258 150.214227) (xy 202.984749 150.244527) (xy 202.971877 150.255628)
				(xy 202.941705 150.26) (xy 203.025 151.136) (xy 203.175 150.887021) (xy 203.155644 150.645818) (xy 203.170401 150.373112)
				(xy 203.1815 150.2)
			)
		)
	)
	(zone
		(net 427)
		(net_name "/2xSFP+/10GKR_SFP1.RX+")
		(layer "F.Cu")
		(name "$teardrop_padvia$")
		(hatch none 0.1)
		(priority 31668)
		(attr
			(teardrop
				(type padvia)
			)
		)
		(connect_pads yes
			(clearance 0)
		)
		(min_thickness 0.0254)
		(filled_areas_thickness no)
		(fill yes
			(thermal_gap 0.5)
			(thermal_bridge_width 0.5)
			(island_removal_mode 1)
			(island_area_min 10)
		)
		(polygon
			(pts
				(xy 195.182443 154.768635) (xy 195.127281 154.740737) (xy 195.088817 154.711151) (xy 195.036372 154.642839)
				(xy 194.967815 154.554493) (xy 194.812196 154.711499) (xy 194.857014 154.932558) (xy 194.934145 154.911545)
				(xy 195.016113 154.893381) (xy 195.062815 154.897667) (xy 195.121201 154.916449)
			)
		)
	)
	(zone
		(net 607)
		(net_name "Net-(U37-~{HIBW_BYPM_LOBW})")
		(layer "F.Cu")
		(name "$teardrop_padvia$")
		(hatch none 0.1)
		(priority 32105)
		(attr
			(teardrop
				(type padvia)
			)
		)
		(connect_pads yes
			(clearance 0)
		)
		(min_thickness 0.0254)
		(filled_areas_thickness no)
		(fill yes
			(thermal_gap 0.5)
			(thermal_bridge_width 0.5)
			(island_removal_mode 1)
			(island_area_min 10)
		)
		(polygon
			(pts
				(xy 217.0165 125.834) (xy 217.017952 125.845797) (xy 217.018129 125.874081) (xy 217.009153 125.886652)
				(xy 216.989 125.895596) (xy 217.079 126.25) (xy 217.169 125.895596) (xy 217.148044 125.885992) (xy 217.13937 125.872447)
				(xy 217.140048 125.845797) (xy 217.1415 125.834)
			)
		)
	)
	(zone
		(net 52)
		(net_name "+5V")
		(layer "F.Cu")
		(name "$teardrop_padvia$")
		(hatch none 0.1)
		(priority 30771)
		(attr
			(teardrop
				(type padvia)
			)
		)
		(connect_pads yes
			(clearance 0)
		)
		(min_thickness 0.0254)
		(filled_areas_thickness no)
		(fill yes
			(thermal_gap 0.5)
			(thermal_bridge_width 0.5)
			(island_removal_mode 1)
			(island_area_min 10)
		)
		(polygon
			(pts
				(xy 235.600708 76.160677) (xy 235.60764 76.0031) (xy 235.636164 75.889565) (xy 235.653208 75.847778)
				(xy 235.450708 75.759) (xy 235.248208 75.847778) (xy 235.282591 75.943822) (xy 235.297809 76.045702)
				(xy 235.300708 76.160677)
			)
		)
	)
	(zone
		(net 690)
		(net_name "/2xUSB3.0+RJ45/DA_FL-")
		(layer "F.Cu")
		(name "$teardrop_padvia$")
		(hatch none 0.1)
		(priority 31916)
		(attr
			(teardrop
				(type padvia)
			)
		)
		(connect_pads yes
			(clearance 0)
		)
		(min_thickness 0.0254)
		(filled_areas_thickness no)
		(fill yes
			(thermal_gap 0.5)
			(thermal_bridge_width 0.5)
			(island_removal_mode 1)
			(island_area_min 10)
		)
		(polygon
			(pts
				(xy 130.282428 113.21) (xy 130.363593 113.192068) (xy 130.516854 113.161156) (xy 130.607147 113.152998)
				(xy 130.707959 113.155) (xy 130.746 113.015) (xy 130.32 112.995121) (xy 130.319693 113.032722) (xy 130.310451 113.051116)
				(xy 130.288136 113.059129) (xy 130.282428 113.06)
			)
		)
	)
	(zone
		(net 206)
		(net_name "/Backplane/USB.D+")
		(layer "F.Cu")
		(name "$teardrop_padvia$")
		(hatch none 0.1)
		(priority 31490)
		(attr
			(teardrop
				(type padvia)
			)
		)
		(connect_pads yes
			(clearance 0)
		)
		(min_thickness 0.0254)
		(filled_areas_thickness no)
		(fill yes
			(thermal_gap 0.5)
			(thermal_bridge_width 0.5)
			(island_removal_mode 1)
			(island_area_min 10)
		)
		(polygon
			(pts
				(xy 226.354022 145.204506) (xy 226.325828 145.169609) (xy 226.311532 145.136676) (xy 226.312371 145.074183)
				(xy 226.326363 145.027902) (xy 226.34205 144.975929) (xy 226.348719 144.917508) (xy 226.127335 144.921251)
				(xy 225.980795 145.086795) (xy 226.109886 145.216083) (xy 226.223207 145.335321)
			)
		)
	)
	(zone
		(net 605)
		(net_name "Net-(U37-~{OE3})")
		(layer "F.Cu")
		(name "$teardrop_padvia$")
		(hatch none 0.1)
		(priority 32099)
		(attr
			(teardrop
				(type padvia)
			)
		)
		(connect_pads yes
			(clearance 0)
		)
		(min_thickness 0.0254)
		(filled_areas_thickness no)
		(fill yes
			(thermal_gap 0.5)
			(thermal_bridge_width 0.5)
			(island_removal_mode 1)
			(island_area_min 10)
		)
		(polygon
			(pts
				(xy 217.1415 131.615) (xy 217.140048 131.603203) (xy 217.139871 131.574919) (xy 217.148847 131.562347)
				(xy 217.169 131.553403) (xy 217.079 131.199) (xy 216.989 131.553403) (xy 217.009956 131.563008)
				(xy 217.01863 131.576553) (xy 217.017952 131.603203) (xy 217.0165 131.615)
			)
		)
	)
	(zone
		(net 2)
		(net_name "+3V3")
		(layer "F.Cu")
		(name "$teardrop_padvia$")
		(hatch none 0.1)
		(priority 31528)
		(attr
			(teardrop
				(type padvia)
			)
		)
		(connect_pads yes
			(clearance 0)
		)
		(min_thickness 0.0254)
		(filled_areas_thickness no)
		(fill yes
			(thermal_gap 0.5)
			(thermal_bridge_width 0.5)
			(island_removal_mode 1)
			(island_area_min 10)
		)
		(polygon
			(pts
				(xy 125.770457 135.85207) (xy 125.701459 135.822426) (xy 125.663354 135.789638) (xy 125.629594 135.746681)
				(xy 125.604415 135.697622) (xy 125.588554 135.641435) (xy 125.586156 135.624691) (xy 125.319293 135.879293)
				(xy 125.603772 136.108946) (xy 125.612652 136.029493) (xy 125.630224 135.974232) (xy 125.648147 135.950277)
				(xy 125.670391 135.94024) (xy 125.68207 135.940457)
			)
		)
	)
	(zone
		(net 1)
		(net_name "GND")
		(layer "F.Cu")
		(name "$teardrop_padvia$")
		(hatch none 0.1)
		(priority 30795)
		(attr
			(teardrop
				(type padvia)
			)
		)
		(connect_pads yes
			(clearance 0)
		)
		(min_thickness 0.0254)
		(filled_areas_thickness no)
		(fill yes
			(thermal_gap 0.5)
			(thermal_bridge_width 0.5)
			(island_removal_mode 1)
			(island_area_min 10)
		)
		(polygon
			(pts
				(xy 298.549 74.639323) (xy 298.542069 74.796893) (xy 298.513549 74.910421) (xy 298.4965 74.952221)
				(xy 298.699 75.041) (xy 298.9015 74.952221) (xy 298.867117 74.856179) (xy 298.8519 74.754304) (xy 298.849 74.639323)
			)
		)
	)
	(zone
		(net 294)
		(net_name "/2xUSB3.0+RJ45/GbE.MDI0-")
		(layer "F.Cu")
		(name "$teardrop_padvia$")
		(hatch none 0.1)
		(priority 31647)
		(attr
			(teardrop
				(type padvia)
			)
		)
		(connect_pads yes
			(clearance 0)
		)
		(min_thickness 0.0254)
		(filled_areas_thickness no)
		(fill yes
			(thermal_gap 0.5)
			(thermal_bridge_width 0.5)
			(island_removal_mode 1)
			(island_area_min 10)
		)
		(polygon
			(pts
				(xy 181.675 167.742084) (xy 181.672797 167.536718) (xy 181.670677 167.398242) (xy 181.45 167.399)
				(xy 181.324997 167.587081) (xy 181.401138 167.620995) (xy 181.417738 167.62605) (xy 181.459281 167.639844)
				(xy 181.493398 167.659262) (xy 181.516501 167.691083) (xy 181.525 167.742084)
			)
		)
	)
	(zone
		(net 722)
		(net_name "/2xSFP+/KR to SFI #1/TDI")
		(layer "F.Cu")
		(name "$teardrop_padvia$")
		(hatch none 0.1)
		(priority 30106)
		(attr
			(teardrop
				(type padvia)
			)
		)
		(connect_pads yes
			(clearance 0)
		)
		(min_thickness 0.0254)
		(filled_areas_thickness no)
		(fill yes
			(thermal_gap 0.5)
			(thermal_bridge_width 0.5)
			(island_removal_mode 1)
			(island_area_min 10)
		)
		(polygon
			(pts
				(xy 153.1625 129.377794) (xy 153.167315 129.295733) (xy 153.181019 129.230388) (xy 153.227576 129.13712)
				(xy 153.295787 129.058657) (xy 153.351942 128.997158) (xy 153.411801 128.918339) (xy 153.1 128.709)
				(xy 152.788199 128.918339) (xy 152.885219 129.038517) (xy 152.904214 129.058658) (xy 152.957366 129.117541)
				(xy 152.999591 129.181624) (xy 153.027449 129.264008) (xy 153.0375 129.377794)
			)
		)
	)
	(zone
		(net 193)
		(net_name "/OCuLink/PCIe_{REF0}.CK-")
		(layer "F.Cu")
		(name "$teardrop_padvia$")
		(hatch none 0.1)
		(priority 31412)
		(attr
			(teardrop
				(type padvia)
			)
		)
		(connect_pads yes
			(clearance 0)
		)
		(min_thickness 0.0254)
		(filled_areas_thickness no)
		(fill yes
			(thermal_gap 0.5)
			(thermal_bridge_width 0.5)
			(island_removal_mode 1)
			(island_area_min 10)
		)
		(polygon
			(pts
				(xy 150.557504 113.6815) (xy 150.719035 113.676105) (xy 150.803445 113.672554) (xy 150.90514 113.677177)
				(xy 150.926 113.4565) (xy 150.776147 113.293268) (xy 150.722007 113.361935) (xy 150.712115 113.378393)
				(xy 150.687615 113.417065) (xy 150.658109 113.449279) (xy 150.616953 113.471327) (xy 150.557504 113.4795)
			)
		)
	)
	(zone
		(net 790)
		(net_name "Net-(U38-1A)")
		(layer "F.Cu")
		(name "$teardrop_padvia$")
		(hatch none 0.1)
		(priority 30071)
		(attr
			(teardrop
				(type padvia)
			)
		)
		(connect_pads yes
			(clearance 0)
		)
		(min_thickness 0.0254)
		(filled_areas_thickness no)
		(fill yes
			(thermal_gap 0.5)
			(thermal_bridge_width 0.5)
			(island_removal_mode 1)
			(island_area_min 10)
		)
		(polygon
			(pts
				(xy 308.56761 79.853779) (xy 308.64667 79.801952) (xy 308.770153 79.769493) (xy 308.939349 79.767237)
				(xy 309.057117 79.785) (xy 308.998707 79.334293) (xy 308.598 79.225884) (xy 308.602666 79.343529)
				(xy 308.59696 79.45375) (xy 308.582146 79.548712) (xy 308.558237 79.632935) (xy 308.529639 79.696724)
				(xy 308.494052 79.749211) (xy 308.479221 79.76539)
			)
		)
	)
	(zone
		(net 124)
		(net_name "/2xUSB3.0+RJ45/P1_D+")
		(layer "F.Cu")
		(name "$teardrop_padvia$")
		(hatch none 0.1)
		(priority 31488)
		(attr
			(teardrop
				(type padvia)
			)
		)
		(connect_pads yes
			(clearance 0)
		)
		(min_thickness 0.0254)
		(filled_areas_thickness no)
		(fill yes
			(thermal_gap 0.5)
			(thermal_bridge_width 0.5)
			(island_removal_mode 1)
			(island_area_min 10)
		)
		(polygon
			(pts
				(xy 104.128157 105.6475) (xy 104.172769 105.65224) (xy 104.206165 105.665418) (xy 104.24976 105.710201)
				(xy 104.272592 105.752819) (xy 104.29825 105.800662) (xy 104.334845 105.846688) (xy 104.488741 105.6875)
				(xy 104.475303 105.466823) (xy 104.292599 105.466684) (xy 104.128157 105.4625)
			)
		)
	)
	(zone
		(net 427)
		(net_name "/2xSFP+/10GKR_SFP1.RX+")
		(layer "F.Cu")
		(name "$teardrop_padvia$")
		(hatch none 0.1)
		(priority 30907)
		(attr
			(teardrop
				(type padvia)
			)
		)
		(connect_pads yes
			(clearance 0)
		)
		(min_thickness 0.0254)
		(filled_areas_thickness no)
		(fill yes
			(thermal_gap 0.5)
			(thermal_bridge_width 0.5)
			(island_removal_mode 1)
			(island_area_min 10)
		)
		(polygon
			(pts
				(xy 196.505 155.75) (xy 196.505255 155.757452) (xy 196.499209 155.791839) (xy 196.481452 155.804832)
				(xy 196.445877 155.81) (xy 196.525 156.686) (xy 196.675 155.81) (xy 196.657064 155.805534) (xy 196.652035 155.794271)
				(xy 196.659583 155.767388) (xy 196.665 155.75)
			)
		)
	)
	(zone
		(net 682)
		(net_name "Net-(U45C-PRTAD4)")
		(layer "F.Cu")
		(name "$teardrop_padvia$")
		(hatch none 0.1)
		(priority 31463)
		(attr
			(teardrop
				(type padvia)
			)
		)
		(connect_pads yes
			(clearance 0)
		)
		(min_thickness 0.0254)
		(filled_areas_thickness no)
		(fill yes
			(thermal_gap 0.5)
			(thermal_bridge_width 0.5)
			(island_removal_mode 1)
			(island_area_min 10)
		)
		(polygon
			(pts
				(xy 126.822635 138.851023) (xy 126.893655 138.915544) (xy 126.952383 138.957066) (xy 127.023166 138.995115)
				(xy 127.151107 139.067867) (xy 127.290707 138.860707) (xy 127.151107 138.652133) (xy 127.073312 138.723429)
				(xy 127.034719 138.762477) (xy 126.996592 138.788485) (xy 126.956253 138.791767) (xy 126.911023 138.762635)
			)
		)
	)
	(zone
		(net 324)
		(net_name "/Com Express 7 Interfaces/PCIe_{B2Ax4}.TX0+")
		(layer "F.Cu")
		(name "$teardrop_padvia$")
		(hatch none 0.1)
		(priority 30512)
		(attr
			(teardrop
				(type padvia)
			)
		)
		(connect_pads yes
			(clearance 0)
		)
		(min_thickness 0.0254)
		(filled_areas_thickness no)
		(fill yes
			(thermal_gap 0.5)
			(thermal_bridge_width 0.5)
			(island_removal_mode 1)
			(island_area_min 10)
		)
		(polygon
			(pts
				(xy 210.924 167.75) (xy 210.927537 167.764678) (xy 210.930808 167.794685) (xy 210.918857 167.805673)
				(xy 210.89 167.81) (xy 211.025 168.686) (xy 211.16 167.81) (xy 211.130796 167.805525) (xy 211.119003 167.794203)
				(xy 211.122463 167.764678) (xy 211.126 167.75)
			)
		)
	)
	(zone
		(net 566)
		(net_name "/2xSFP+/~{LED1_1}")
		(layer "F.Cu")
		(name "$teardrop_padvia$")
		(hatch none 0.1)
		(priority 32010)
		(attr
			(teardrop
				(type padvia)
			)
		)
		(connect_pads yes
			(clearance 0)
		)
		(min_thickness 0.0254)
		(filled_areas_thickness no)
		(fill yes
			(thermal_gap 0.5)
			(thermal_bridge_width 0.5)
			(island_removal_mode 1)
			(island_area_min 10)
		)
		(polygon
			(pts
				(xy 156.8995 161.4205) (xy 156.905822 161.420404) (xy 156.945325 161.425989) (xy 156.963547 161.440922)
				(xy 156.976495 161.4705) (xy 157.363 161.358) (xy 156.976495 161.2455) (xy 156.965379 161.272493)
				(xy 156.949852 161.287595) (xy 156.905822 161.295596) (xy 156.8995 161.2955)
			)
		)
	)
	(zone
		(net 607)
		(net_name "Net-(U37-~{HIBW_BYPM_LOBW})")
		(layer "F.Cu")
		(name "$teardrop_padvia$")
		(hatch none 0.1)
		(priority 30924)
		(attr
			(teardrop
				(type padvia)
			)
		)
		(connect_pads yes
			(clearance 0)
		)
		(min_thickness 0.0254)
		(filled_areas_thickness no)
		(fill yes
			(thermal_gap 0.5)
			(thermal_bridge_width 0.5)
			(island_removal_mode 1)
			(island_area_min 10)
		)
		(polygon
			(pts
				(xy 219.1875 123.462) (xy 219.167531 123.524866) (xy 219.141079 123.556844) (xy 219.103668 123.585358)
				(xy 219.056473 123.607882) (xy 218.998833 123.623093) (xy 218.998202 123.623202) (xy 219.25 123.901)
				(xy 219.501798 123.623202) (xy 219.446365 123.608905) (xy 219.40048 123.587825) (xy 219.362799 123.56046)
				(xy 219.335566 123.529552) (xy 219.318528 123.496265) (xy 219.312511 123.463434) (xy 219.3125 123.462)
			)
		)
	)
	(zone
		(net 1)
		(net_name "GND")
		(layer "F.Cu")
		(name "$teardrop_padvia$")
		(hatch none 0.1)
		(priority 30524)
		(attr
			(teardrop
				(type padvia)
			)
		)
		(connect_pads yes
			(clearance 0)
		)
		(min_thickness 0.0254)
		(filled_areas_thickness no)
		(fill yes
			(thermal_gap 0.5)
			(thermal_bridge_width 0.5)
			(island_removal_mode 1)
			(island_area_min 10)
		)
		(polygon
			(pts
				(xy 260.623999 88.12) (xy 260.601961 88.12684) (xy 260.560854 88.134995) (xy 260.545884 88.119961)
				(xy 260.54 88.081) (xy 259.979001 88.27) (xy 260.54 88.459) (xy 260.544553 88.423474) (xy 260.556426 88.407011)
				(xy 260.585712 88.406915) (xy 260.601961 88.413159) (xy 260.624 88.419999)
			)
		)
	)
	(zone
		(net 423)
		(net_name "/2xSFP+/I2C_{LED}.SCL")
		(layer "F.Cu")
		(name "$teardrop_padvia$")
		(hatch none 0.1)
		(priority 30694)
		(attr
			(teardrop
				(type padvia)
			)
		)
		(connect_pads yes
			(clearance 0)
		)
		(min_thickness 0.0254)
		(filled_areas_thickness no)
		(fill yes
			(thermal_gap 0.5)
			(thermal_bridge_width 0.5)
			(island_removal_mode 1)
			(island_area_min 10)
		)
		(polygon
			(pts
				(xy 193.9625 155.75) (xy 193.951563 155.788823) (xy 193.929805 155.803933) (xy 193.89 155.81) (xy 194.025 156.686)
				(xy 194.16 155.81) (xy 194.124719 155.805483) (xy 194.103203 155.793862) (xy 194.088005 155.761039)
				(xy 194.0875 155.75)
			)
		)
	)
	(zone
		(net 650)
		(net_name "/2xSFP+/KR to SFI #1/MDC_R")
		(layer "F.Cu")
		(name "$teardrop_padvia$")
		(hatch none 0.1)
		(priority 30349)
		(attr
			(teardrop
				(type padvia)
			)
		)
		(connect_pads yes
			(clearance 0)
		)
		(min_thickness 0.0254)
		(filled_areas_thickness no)
		(fill yes
			(thermal_gap 0.5)
			(thermal_bridge_width 0.5)
			(island_removal_mode 1)
			(island_area_min 10)
		)
		(polygon
			(pts
				(xy 141.8275 146.295) (xy 141.821719 146.328863) (xy 141.801254 146.363486) (xy 141.774188 146.385307)
				(xy 141.734849 146.401) (xy 141.719289 146.404289) (xy 141.89 147.111) (xy 142.060711 146.404289)
				(xy 142.02049 146.3927) (xy 141.991017 146.375116) (xy 141.957827 146.327533) (xy 141.9525 146.295)
			)
		)
	)
	(zone
		(net 359)
		(net_name "/Com Express 7 MGMT/SMBus.~{INT}")
		(layer "F.Cu")
		(name "$teardrop_padvia$")
		(hatch none 0.1)
		(priority 31657)
		(attr
			(teardrop
				(type padvia)
			)
		)
		(connect_pads yes
			(clearance 0)
		)
		(min_thickness 0.0254)
		(filled_areas_thickness no)
		(fill yes
			(thermal_gap 0.5)
			(thermal_bridge_width 0.5)
			(island_removal_mode 1)
			(island_area_min 10)
		)
		(polygon
			(pts
				(xy 185.873005 158.915383) (xy 185.943062 158.838911) (xy 185.987191 158.778166) (xy 186.013482 158.735443)
				(xy 186.081592 158.630491) (xy 185.900707 158.499293) (xy 185.683762 158.554613) (xy 185.717235 158.621244)
				(xy 185.759794 158.670538) (xy 185.792532 158.70774) (xy 185.813499 158.744463) (xy 185.81382 158.783338)
				(xy 185.784617 158.826995)
			)
		)
	)
	(zone
		(net 706)
		(net_name "Net-(U24-GPIO0)")
		(layer "F.Cu")
		(name "$teardrop_padvia$")
		(hatch none 0.1)
		(priority 31764)
		(attr
			(teardrop
				(type padvia)
			)
		)
		(connect_pads yes
			(clearance 0)
		)
		(min_thickness 0.0254)
		(filled_areas_thickness no)
		(fill yes
			(thermal_gap 0.5)
			(thermal_bridge_width 0.5)
			(island_removal_mode 1)
			(island_area_min 10)
		)
		(polygon
			(pts
				(xy 260.439323 87.062499) (xy 260.508764 87.067317) (xy 260.560088 87.081039) (xy 260.635629 87.127754)
				(xy 260.647769 87.137298) (xy 260.714997 87.18708) (xy 260.841 86.999999) (xy 260.714997 86.812918)
				(xy 260.647768 86.862701) (xy 260.564602 86.917105) (xy 260.511748 86.932189) (xy 260.439323 86.937499)
			)
		)
	)
	(zone
		(net 186)
		(net_name "/OCuLink/PCIe_{x4}.RX0+")
		(layer "F.Cu")
		(name "$teardrop_padvia$")
		(hatch none 0.1)
		(priority 32067)
		(attr
			(teardrop
				(type padvia)
			)
		)
		(connect_pads yes
			(clearance 0)
		)
		(min_thickness 0.0254)
		(filled_areas_thickness no)
		(fill yes
			(thermal_gap 0.5)
			(thermal_bridge_width 0.5)
			(island_removal_mode 1)
			(island_area_min 10)
		)
		(polygon
			(pts
				(xy 96.603 151.025) (xy 96.595802 151.004352) (xy 96.586208 150.972016) (xy 96.593035 150.957993)
				(xy 96.6145 150.948004) (xy 96.502 150.699) (xy 96.3895 150.948004) (xy 96.410676 150.957729) (xy 96.417731 150.971357)
				(xy 96.408198 151.004352) (xy 96.401 151.025)
			)
		)
	)
	(zone
		(net 357)
		(net_name "/Com Express 7 MGMT/SMBus.SCL")
		(layer "F.Cu")
		(name "$teardrop_padvia$")
		(hatch none 0.1)
		(priority 31841)
		(attr
			(teardrop
				(type padvia)
			)
		)
		(connect_pads yes
			(clearance 0)
		)
		(min_thickness 0.0254)
		(filled_areas_thickness no)
		(fill yes
			(thermal_gap 0.5)
			(thermal_bridge_width 0.5)
			(island_removal_mode 1)
			(island_area_min 10)
		)
		(polygon
			(pts
				(xy 181.839127 164.172485) (xy 181.786618 164.218181) (xy 181.740623 164.244768) (xy 181.654174 164.265152)
				(xy 181.638841 164.266988) (xy 181.556105 164.279323) (xy 181.599293 164.500707) (xy 181.820677 164.543895)
				(xy 181.833011 164.46116) (xy 181.853349 164.363881) (xy 181.880057 164.315841) (xy 181.927515 164.260873)
			)
		)
	)
	(zone
		(net 45)
		(net_name "/2xUSB3.0+RJ45/USBSS_2.TX+")
		(layer "F.Cu")
		(name "$teardrop_padvia$")
		(hatch none 0.1)
		(priority 31479)
		(attr
			(teardrop
				(type padvia)
			)
		)
		(connect_pads yes
			(clearance 0)
		)
		(min_thickness 0.0254)
		(filled_areas_thickness no)
		(fill yes
			(thermal_gap 0.5)
			(thermal_bridge_width 0.5)
			(island_removal_mode 1)
			(island_area_min 10)
		)
		(polygon
			(pts
				(xy 182.0575 149.934584) (xy 182.06224 149.889972) (xy 182.075418 149.856575) (xy 182.120201 149.81298)
				(xy 182.16282 149.790148) (xy 182.210662 149.76449) (xy 182.256688 149.727895) (xy 182.0975 149.574)
				(xy 181.876823 149.587437) (xy 181.876683 149.770139) (xy 181.8725 149.934584)
			)
		)
	)
	(zone
		(net 347)
		(net_name "/2xUSB3.0+RJ45/~{GBE0_ACT}")
		(layer "F.Cu")
		(name "$teardrop_padvia$")
		(hatch none 0.1)
		(priority 31778)
		(attr
			(teardrop
				(type padvia)
			)
		)
		(connect_pads yes
			(clearance 0)
		)
		(min_thickness 0.0254)
		(filled_areas_thickness no)
		(fill yes
			(thermal_gap 0.5)
			(thermal_bridge_width 0.5)
			(island_removal_mode 1)
			(island_area_min 10)
		)
		(polygon
			(pts
				(xy 172.4125 126.300677) (xy 172.417318 126.231236) (xy 172.43104 126.179912) (xy 172.477755 126.10437)
				(xy 172.487299 126.092229) (xy 172.537081 126.025003) (xy 172.35 125.899) (xy 172.162919 126.025003)
				(xy 172.212701 126.092231) (xy 172.267106 126.175397) (xy 172.28219 126.228251) (xy 172.2875 126.300677)
			)
		)
	)
	(zone
		(net 551)
		(net_name "Net-(R16-Pad2)")
		(layer "F.Cu")
		(name "$teardrop_padvia$")
		(hatch none 0.1)
		(priority 30430)
		(attr
			(teardrop
				(type padvia)
			)
		)
		(connect_pads yes
			(clearance 0)
		)
		(min_thickness 0.0254)
		(filled_areas_thickness no)
		(fill yes
			(thermal_gap 0.5)
			(thermal_bridge_width 0.5)
			(island_removal_mode 1)
			(island_area_min 10)
		)
		(polygon
			(pts
				(xy 135.42 109.555) (xy 135.370167 109.54574) (xy 135.346156 109.529372) (xy 135.326648 109.500919)
				(xy 135.312274 109.43) (xy 134.844 109.655) (xy 135.312274 109.88) (xy 135.318547 109.83239) (xy 135.332162 109.798567)
				(xy 135.372122 109.763408) (xy 135.42 109.755)
			)
		)
	)
	(zone
		(net 716)
		(net_name "Net-(U40-SDA)")
		(layer "F.Cu")
		(name "$teardrop_padvia$")
		(hatch none 0.1)
		(priority 30169)
		(attr
			(teardrop
				(type padvia)
			)
		)
		(connect_pads yes
			(clearance 0)
		)
		(min_thickness 0.0254)
		(filled_areas_thickness no)
		(fill yes
			(thermal_gap 0.5)
			(thermal_bridge_width 0.5)
			(island_removal_mode 1)
			(island_area_min 10)
		)
		(polygon
			(pts
				(xy 196.34152 131.790847) (xy 196.336702 131.834605) (xy 196.322978 131.865089) (xy 196.280447 131.892952)
				(xy 196.204743 131.896847) (xy 196.151873 131.891571) (xy 196.068365 131.884311) (xy 195.984379 131.889744)
				(xy 196.057538 132.258538) (xy 196.425332 132.329042) (xy 196.459103 132.11958) (xy 196.46656 131.93575)
				(xy 196.466573 131.852448) (xy 196.46652 131.790847)
			)
		)
	)
	(zone
		(net 584)
		(net_name "Net-(U21-EN)")
		(layer "F.Cu")
		(name "$teardrop_padvia$")
		(hatch none 0.1)
		(priority 30447)
		(attr
			(teardrop
				(type padvia)
			)
		)
		(connect_pads yes
			(clearance 0)
		)
		(min_thickness 0.0254)
		(filled_areas_thickness no)
		(fill yes
			(thermal_gap 0.5)
			(thermal_bridge_width 0.5)
			(island_removal_mode 1)
			(island_area_min 10)
		)
		(polygon
			(pts
				(xy 312.087549 97.546062) (xy 312.009209 97.596712) (xy 311.886227 97.626914) (xy 311.719818 97.624525)
				(xy 311.697573 97.6215) (xy 311.764792 97.917207) (xy 312.085499 97.987058) (xy 312.086399 97.840171)
				(xy 312.10063 97.772543) (xy 312.12251 97.713597) (xy 312.175937 97.63445)
			)
		)
	)
	(zone
		(net 159)
		(net_name "/2xUSB3.0+RJ45/USBSS_1.RX+")
		(layer "F.Cu")
		(name "$teardrop_padvia$")
		(hatch none 0.1)
		(priority 30286)
		(attr
			(teardrop
				(type padvia)
			)
		)
		(connect_pads yes
			(clearance 0)
		)
		(min_thickness 0.0254)
		(filled_areas_thickness no)
		(fill yes
			(thermal_gap 0.5)
			(thermal_bridge_width 0.5)
			(island_removal_mode 1)
			(island_area_min 10)
		)
		(polygon
			(pts
				(xy 180.5575 157.62) (xy 180.555915 157.607811) (xy 180.557296 157.576262) (xy 180.572069 157.564604)
				(xy 180.604123 157.56) (xy 180.525 156.684) (xy 180.375 156.913685) (xy 180.394285 157.1731) (xy 180.381903 157.446083)
				(xy 180.3725 157.62)
			)
		)
	)
	(zone
		(net 526)
		(net_name "/Backplane/~{PRSNT}")
		(layer "F.Cu")
		(name "$teardrop_padvia$")
		(hatch none 0.1)
		(priority 31619)
		(attr
			(teardrop
				(type padvia)
			)
		)
		(connect_pads yes
			(clearance 0)
		)
		(min_thickness 0.0254)
		(filled_areas_thickness no)
		(fill yes
			(thermal_gap 0.5)
			(thermal_bridge_width 0.5)
			(island_removal_mode 1)
			(island_area_min 10)
		)
		(polygon
			(pts
				(xy 221.699323 133.6425) (xy 221.767897 133.647174) (xy 221.820378 133.659892) (xy 221.908052 133.706372)
				(xy 221.957968 133.736927) (xy 222.022288 133.766669) (xy 222.101 133.56) (xy 221.974997 133.372919)
				(xy 221.894672 133.437939) (xy 221.818814 133.494851) (xy 221.768462 133.511493) (xy 221.699323 133.5175)
			)
		)
	)
	(zone
		(net 73)
		(net_name "+3V3_AON")
		(layer "F.Cu")
		(name "$teardrop_padvia$")
		(hatch none 0.1)
		(priority 30786)
		(attr
			(teardrop
				(type padvia)
			)
		)
		(connect_pads yes
			(clearance 0)
		)
		(min_thickness 0.0254)
		(filled_areas_thickness no)
		(fill yes
			(thermal_gap 0.5)
			(thermal_bridge_width 0.5)
			(island_removal_mode 1)
			(island_area_min 10)
		)
		(polygon
			(pts
				(xy 307.050677 153.2) (xy 306.893106 153.193069) (xy 306.779578 153.164549) (xy 306.737778 153.1475)
				(xy 306.649 153.35) (xy 306.737778 153.5525) (xy 306.833817 153.518118) (xy 306.935689 153.5029)
				(xy 307.050677 153.5)
			)
		)
	)
	(zone
		(net 189)
		(net_name "/OCuLink/PCIe_{x4}.RX1-")
		(layer "F.Cu")
		(name "$teardrop_padvia$")
		(hatch none 0.1)
		(priority 32053)
		(attr
			(teardrop
				(type padvia)
			)
		)
		(connect_pads yes
			(clearance 0)
		)
		(min_thickness 0.0254)
		(filled_areas_thickness no)
		(fill yes
			(thermal_gap 0.5)
			(thermal_bridge_width 0.5)
			(island_removal_mode 1)
			(island_area_min 10)
		)
		(polygon
			(pts
				(xy 98.601 151.797) (xy 98.593802 151.776352) (xy 98.584208 151.744016) (xy 98.591035 151.729993)
				(xy 98.6125 151.720004) (xy 98.5 151.471) (xy 98.3875 151.720004) (xy 98.408676 151.729729) (xy 98.415731 151.743357)
				(xy 98.406198 151.776352) (xy 98.399 151.797)
			)
		)
	)
	(zone
		(net 710)
		(net_name "Net-(U37-SDAT)")
		(layer "F.Cu")
		(name "$teardrop_padvia$")
		(hatch none 0.1)
		(priority 31626)
		(attr
			(teardrop
				(type padvia)
			)
		)
		(connect_pads yes
			(clearance 0)
		)
		(min_thickness 0.0254)
		(filled_areas_thickness no)
		(fill yes
			(thermal_gap 0.5)
			(thermal_bridge_width 0.5)
			(island_removal_mode 1)
			(island_area_min 10)
		)
		(polygon
			(pts
				(xy 213.9405 125.974675) (xy 213.945153 125.865831) (xy 213.957722 125.789244) (xy 213.968537 125.744445)
				(xy 213.991508 125.644102) (xy 213.770831 125.599207) (xy 213.601185 125.742645) (xy 213.667892 125.798114)
				(xy 213.707292 125.819734) (xy 213.748833 125.842956) (xy 213.783293 125.871713) (xy 213.806804 125.913215)
				(xy 213.8155 125.974675)
			)
		)
	)
	(zone
		(net 931)
		(net_name "/2xSFP+/SFP0_LEDG")
		(layer "F.Cu")
		(name "$teardrop_padvia$")
		(hatch none 0.1)
		(priority 30948)
		(attr
			(teardrop
				(type padvia)
			)
		)
		(connect_pads yes
			(clearance 0)
		)
		(min_thickness 0.0254)
		(filled_areas_thickness no)
		(fill yes
			(thermal_gap 0.5)
			(thermal_bridge_width 0.5)
			(island_removal_mode 1)
			(island_area_min 10)
		)
		(polygon
			(pts
				(xy 154.8815 159.548) (xy 154.901469 159.485134) (xy 154.927921 159.453156) (xy 154.965332 159.424642)
				(xy 155.012527 159.402118) (xy 155.070167 159.386907) (xy 155.070798 159.386798) (xy 154.819 159.109)
				(xy 154.567202 159.386798) (xy 154.622635 159.401095) (xy 154.66852 159.422175) (xy 154.706201 159.44954)
				(xy 154.733434 159.480448) (xy 154.750472 159.513735) (xy 154.756489 159.546566) (xy 154.7565 159.548)
			)
		)
	)
	(zone
		(net 1)
		(net_name "GND")
		(layer "F.Cu")
		(name "$teardrop_padvia$")
		(hatch none 0.1)
		(priority 31387)
		(attr
			(teardrop
				(type padvia)
			)
		)
		(connect_pads yes
			(clearance 0)
		)
		(min_thickness 0.0254)
		(filled_areas_thickness no)
		(fill yes
			(thermal_gap 0.5)
			(thermal_bridge_width 0.5)
			(island_removal_mode 1)
			(island_area_min 10)
		)
		(polygon
			(pts
				(xy 176.125 155.867082) (xy 176.119727 155.705177) (xy 176.120677 155.519078) (xy 175.9 155.499)
				(xy 175.737166 155.64925) (xy 175.80577 155.702892) (xy 175.823323 155.713273) (xy 175.862212 155.737497)
				(xy 175.894608 155.766765) (xy 175.91678 155.80774) (xy 175.925 155.867082)
			)
		)
	)
	(zone
		(net 584)
		(net_name "Net-(U21-EN)")
		(layer "F.Cu")
		(name "$teardrop_padvia$")
		(hatch none 0.1)
		(priority 31462)
		(attr
			(teardrop
				(type padvia)
			)
		)
		(connect_pads yes
			(clearance 0)
		)
		(min_thickness 0.0254)
		(filled_areas_thickness no)
		(fill yes
			(thermal_gap 0.5)
			(thermal_bridge_width 0.5)
			(island_removal_mode 1)
			(island_area_min 10)
		)
		(polygon
			(pts
				(xy 312.677465 96.605853) (xy 312.680953 96.626084) (xy 312.672871 96.64394) (xy 312.623693 96.673672)
				(xy 312.488701 96.704702) (xy 312.766206 96.957207) (xy 313.001907 96.677714) (xy 312.907836 96.653552)
				(xy 312.823487 96.596182) (xy 312.765853 96.517465)
			)
		)
	)
	(zone
		(net 56)
		(net_name "/USB-C console/USB_D-")
		(layer "F.Cu")
		(name "$teardrop_padvia$")
		(hatch none 0.1)
		(priority 30426)
		(attr
			(teardrop
				(type padvia)
			)
		)
		(connect_pads yes
			(clearance 0)
		)
		(min_thickness 0.0254)
		(filled_areas_thickness no)
		(fill yes
			(thermal_gap 0.5)
			(thermal_bridge_width 0.5)
			(island_removal_mode 1)
			(island_area_min 10)
		)
		(polygon
			(pts
				(xy 110.129279 75.923501) (xy 110.012991 75.953365) (xy 109.86532 75.991554) (xy 109.78655 76.002123)
				(xy 109.706818 76.001) (xy 109.756 76.296) (xy 110.077 76.387107) (xy 110.062993 76.269549) (xy 110.066299 76.184299)
				(xy 110.078313 76.146377) (xy 110.098599 76.121265) (xy 110.129279 76.108501)
			)
		)
	)
	(zone
		(net 487)
		(net_name "/2xSFP+/I2C_{SFP1}.SCL")
		(layer "F.Cu")
		(name "$teardrop_padvia$")
		(hatch none 0.1)
		(priority 31071)
		(attr
			(teardrop
				(type padvia)
			)
		)
		(connect_pads yes
			(clearance 0)
		)
		(min_thickness 0.0254)
		(filled_areas_thickness no)
		(fill yes
			(thermal_gap 0.5)
			(thermal_bridge_width 0.5)
			(island_removal_mode 1)
			(island_area_min 10)
		)
		(polygon
			(pts
				(xy 179.293 147.9375) (xy 179.233588 147.917727) (xy 179.177503 147.854453) (xy 179.155801 147.805828)
				(xy 179.141127 147.746468) (xy 179.139347 147.7345) (xy 178.879 148) (xy 179.139347 148.2655) (xy 179.152197 148.205361)
				(xy 179.172131 148.155477) (xy 179.198056 148.115358) (xy 179.227876 148.086345) (xy 179.259294 148.068854)
				(xy 179.291105 148.062521) (xy 179.293 148.0625)
			)
		)
	)
	(zone
		(net 125)
		(net_name "/2xUSB3.0+RJ45/P2_D-")
		(layer "F.Cu")
		(name "$teardrop_padvia$")
		(hatch none 0.1)
		(priority 31482)
		(attr
			(teardrop
				(type padvia)
			)
		)
		(connect_pads yes
			(clearance 0)
		)
		(min_thickness 0.0254)
		(filled_areas_thickness no)
		(fill yes
			(thermal_gap 0.5)
			(thermal_bridge_width 0.5)
			(island_removal_mode 1)
			(island_area_min 10)
		)
		(polygon
			(pts
				(xy 113.9125 107.459584) (xy 113.91724 107.414972) (xy 113.930418 107.381575) (xy 113.975201 107.33798)
				(xy 114.01782 107.315148) (xy 114.065662 107.28949) (xy 114.111688 107.252895) (xy 113.9525 107.099)
				(xy 113.731823 107.112437) (xy 113.731683 107.295139) (xy 113.7275 107.459584)
			)
		)
	)
	(zone
		(net 159)
		(net_name "/2xUSB3.0+RJ45/USBSS_1.RX+")
		(layer "F.Cu")
		(name "$teardrop_padvia$")
		(hatch none 0.1)
		(priority 31503)
		(attr
			(teardrop
				(type padvia)
			)
		)
		(connect_pads yes
			(clearance 0)
		)
		(min_thickness 0.0254)
		(filled_areas_thickness no)
		(fill yes
			(thermal_gap 0.5)
			(thermal_bridge_width 0.5)
			(island_removal_mode 1)
			(island_area_min 10)
		)
		(polygon
			(pts
				(xy 180.3725 157.990416) (xy 180.376684 158.154858) (xy 180.376823 158.337562) (xy 180.5975 158.351)
				(xy 180.756688 158.197104) (xy 180.689162 158.148225) (xy 180.662819 158.134851) (xy 180.622556 158.113476)
				(xy 180.588998 158.086768) (xy 180.56602 158.047992) (xy 180.5575 157.990416)
			)
		)
	)
	(zone
		(net 186)
		(net_name "/OCuLink/PCIe_{x4}.RX0+")
		(layer "F.Cu")
		(name "$teardrop_padvia$")
		(hatch none 0.1)
		(priority 31382)
		(attr
			(teardrop
				(type padvia)
			)
		)
		(connect_pads yes
			(clearance 0)
		)
		(min_thickness 0.0254)
		(filled_areas_thickness no)
		(fill yes
			(thermal_gap 0.5)
			(thermal_bridge_width 0.5)
			(island_removal_mode 1)
			(island_area_min 10)
		)
		(polygon
			(pts
				(xy 98.662504 166.1505) (xy 98.70929 166.155235) (xy 98.744742 166.168379) (xy 98.792939 166.213387)
				(xy 98.817116 166.251608) (xy 98.844485 166.294773) (xy 98.881147 166.336731) (xy 99.031 166.1735)
				(xy 99.01014 165.952823) (xy 98.909466 165.957452) (xy 98.826096 165.954019) (xy 98.824035 165.953895)
				(xy 98.662504 165.9485)
			)
		)
	)
	(zone
		(net 311)
		(net_name "Net-(J12D-~{THRMTRIP})")
		(layer "F.Cu")
		(name "$teardrop_padvia$")
		(hatch none 0.1)
		(priority 31609)
		(attr
			(teardrop
				(type padvia)
			)
		)
		(connect_pads yes
			(clearance 0)
		)
		(min_thickness 0.0254)
		(filled_areas_thickness no)
		(fill yes
			(thermal_gap 0.5)
			(thermal_bridge_width 0.5)
			(island_removal_mode 1)
			(island_area_min 10)
		)
		(polygon
			(pts
				(xy 192.9625 169.749323) (xy 192.957747 169.810452) (xy 192.94448 169.856552) (xy 192.899229 169.923244)
				(xy 192.88137 169.942341) (xy 192.812919 170.024997) (xy 193 170.151) (xy 193.207644 170.074641)
				(xy 193.149334 169.959581) (xy 193.105855 169.87547) (xy 193.092451 169.821061) (xy 193.0875 169.749323)
			)
		)
	)
	(zone
		(net 119)
		(net_name "/2xSFP+/10GKR_SFP1.TX+")
		(layer "F.Cu")
		(name "$teardrop_padvia$")
		(hatch none 0.1)
		(priority 30904)
		(attr
			(teardrop
				(type padvia)
			)
		)
		(connect_pads yes
			(clearance 0)
		)
		(min_thickness 0.0254)
		(filled_areas_thickness no)
		(fill yes
			(thermal_gap 0.5)
			(thermal_bridge_width 0.5)
			(island_removal_mode 1)
			(island_area_min 10)
		)
		(polygon
			(pts
				(xy 196.665 152.07) (xy 196.659583 152.052612) (xy 196.652109 152.024257) (xy 196.657669 152.014015)
				(xy 196.675 152.01) (xy 196.525 151.134) (xy 196.445877 152.01) (xy 196.479579 152.014497) (xy 196.497541 152.025975)
				(xy 196.505255 152.062548) (xy 196.505 152.07)
			)
		)
	)
	(zone
		(net 717)
		(net_name "Net-(U40-SCL)")
		(layer "F.Cu")
		(name "$teardrop_padvia$")
		(hatch none 0.1)
		(priority 31673)
		(attr
			(teardrop
				(type padvia)
			)
		)
		(connect_pads yes
			(clearance 0)
		)
		(min_thickness 0.0254)
		(filled_areas_thickness no)
		(fill yes
			(thermal_gap 0.5)
			(thermal_bridge_width 0.5)
			(island_removal_mode 1)
			(island_area_min 10)
		)
		(polygon
			(pts
				(xy 196.8625 132.289427) (xy 196.867281 132.253984) (xy 196.880747 132.231383) (xy 196.922214 132.215228)
				(xy 196.998889 132.220567) (xy 197.059468 132.226945) (xy 197.119667 132.223656) (xy 197.075772 132.001979)
				(xy 196.855095 131.959084) (xy 196.819782 132.057072) (xy 196.795922 132.096917) (xy 196.75547 132.173691)
				(xy 196.742413 132.224026) (xy 196.7375 132.289427)
			)
		)
	)
	(zone
		(net 541)
		(net_name "Net-(Q9-B)")
		(layer "F.Cu")
		(name "$teardrop_padvia$")
		(hatch none 0.1)
		(priority 30188)
		(attr
			(teardrop
				(type padvia)
			)
		)
		(connect_pads yes
			(clearance 0)
		)
		(min_thickness 0.0254)
		(filled_areas_thickness no)
		(fill yes
			(thermal_gap 0.5)
			(thermal_bridge_width 0.5)
			(island_removal_mode 1)
			(island_area_min 10)
		)
		(polygon
			(pts
				(xy 121.17 142.711) (xy 121.131486 142.705325) (xy 121.092381 142.685597) (xy 121.065531 142.658719)
				(xy 121.043718 142.619611) (xy 121.026072 142.541) (xy 120.549 142.811) (xy 121.026072 143.081)
				(xy 121.035617 143.026394) (xy 121.052225 142.984158) (xy 121.099911 142.931193) (xy 121.160814 142.911316)
				(xy 121.17 142.911)
			)
		)
	)
	(zone
		(net 541)
		(net_name "Net-(Q9-B)")
		(layer "F.Cu")
		(name "$teardrop_padvia$")
		(hatch none 0.1)
		(priority 31772)
		(attr
			(teardrop
				(type padvia)
			)
		)
		(connect_pads yes
			(clearance 0)
		)
		(min_thickness 0.0254)
		(filled_areas_thickness no)
		(fill yes
			(thermal_gap 0.5)
			(thermal_bridge_width 0.5)
			(island_removal_mode 1)
			(island_area_min 10)
		)
		(polygon
			(pts
				(xy 255.849323 84.522499) (xy 255.918763 84.527317) (xy 255.970087 84.541039) (xy 256.045628 84.587754)
				(xy 256.057769 84.597298) (xy 256.124997 84.647081) (xy 256.251 84.46) (xy 256.124997 84.272919)
				(xy 256.057769 84.322701) (xy 255.974603 84.377105) (xy 255.921748 84.392189) (xy 255.849323 84.397499)
			)
		)
	)
	(zone
		(net 73)
		(net_name "+3V3_AON")
		(layer "F.Cu")
		(name "$teardrop_padvia$")
		(hatch none 0.1)
		(priority 30329)
		(attr
			(teardrop
				(type padvia)
			)
		)
		(connect_pads yes
			(clearance 0)
		)
		(min_thickness 0.0254)
		(filled_areas_thickness no)
		(fill yes
			(thermal_gap 0.5)
			(thermal_bridge_width 0.5)
			(island_removal_mode 1)
			(island_area_min 10)
		)
		(polygon
			(pts
				(xy 244.875 127.32) (xy 244.880039 127.349625) (xy 244.886013 127.380503) (xy 244.88426 127.411696)
				(xy 244.866012 127.439095) (xy 244.8225 127.45859) (xy 245.025 127.961) (xy 245.2275 127.45859)
				(xy 245.193474 127.44566) (xy 245.173601 127.428103) (xy 245.163449 127.386673) (xy 245.169961 127.349625)
				(xy 245.175 127.32)
			)
		)
	)
	(zone
		(net 1)
		(net_name "GND")
		(layer "F.Cu")
		(name "$teardrop_padvia$")
		(hatch none 0.1)
		(priority 30051)
		(attr
			(teardrop
				(type padvia)
			)
		)
		(connect_pads yes
			(clearance 0)
		)
		(min_thickness 0.0254)
		(filled_areas_thickness no)
		(fill yes
			(thermal_gap 0.5)
			(thermal_bridge_width 0.5)
			(island_removal_mode 1)
			(island_area_min 10)
		)
		(polygon
			(pts
				(xy 225.639792 160.57234) (xy 225.69289 160.52251) (xy 225.759027 160.47218) (xy 225.839128 160.429428)
				(xy 225.934115 160.402334) (xy 226.054697 160.4) (xy 226.000707 159.899293) (xy 225.6 159.819548)
				(xy 225.603463 159.913755) (xy 225.597417 159.999729) (xy 225.559732 160.153646) (xy 225.492139 160.282878)
				(xy 225.42766 160.360208)
			)
		)
	)
	(zone
		(net 333)
		(net_name "/Com Express 7 Interfaces/SDIO.DAT3")
		(layer "F.Cu")
		(name "$teardrop_padvia$")
		(hatch none 0.1)
		(priority 31467)
		(attr
			(teardrop
				(type padvia)
			)
		)
		(connect_pads yes
			(clearance 0)
		)
		(min_thickness 0.0254)
		(filled_areas_thickness no)
		(fill yes
			(thermal_gap 0.5)
			(thermal_bridge_width 0.5)
			(island_removal_mode 1)
			(island_area_min 10)
		)
		(polygon
			(pts
				(xy 217.934 169.499323) (xy 217.929194 169.569237) (xy 217.915555 169.62142) (xy 217.868902 169.699106)
				(xy 217.858229 169.713003) (xy 217.812919 169.774997) (xy 218 169.901) (xy 218.207644 169.824641)
				(xy 218.168232 169.731564) (xy 218.13093 169.636314) (xy 218.116 169.499323)
			)
		)
	)
	(zone
		(net 254)
		(net_name "/Com Express 7 Interfaces/PCIe_{B2Bx4}.RX1+")
		(layer "F.Cu")
		(name "$teardrop_padvia$")
		(hatch none 0.1)
		(priority 31374)
		(attr
			(teardrop
				(type padvia)
			)
		)
		(connect_pads yes
			(clearance 0)
		)
		(min_thickness 0.0254)
		(filled_areas_thickness no)
		(fill yes
			(thermal_gap 0.5)
			(thermal_bridge_width 0.5)
			(island_removal_mode 1)
			(island_area_min 10)
		)
		(polygon
			(pts
				(xy 186.432504 124.5955) (xy 186.47929 124.600235) (xy 186.514742 124.613379) (xy 186.562939 124.658387)
				(xy 186.587116 124.696608) (xy 186.614485 124.739773) (xy 186.651147 124.781731) (xy 186.801 124.6185)
				(xy 186.78014 124.397823) (xy 186.679466 124.402452) (xy 186.596096 124.399019) (xy 186.594035 124.398895)
				(xy 186.432504 124.3935)
			)
		)
	)
	(zone
		(net 2)
		(net_name "+3V3")
		(layer "F.Cu")
		(name "$teardrop_padvia$")
		(hatch none 0.1)
		(priority 31741)
		(attr
			(teardrop
				(type padvia)
			)
		)
		(connect_pads yes
			(clearance 0)
		)
		(min_thickness 0.0254)
		(filled_areas_thickness no)
		(fill yes
			(thermal_gap 0.5)
			(thermal_bridge_width 0.5)
			(island_removal_mode 1)
			(island_area_min 10)
		)
		(polygon
			(pts
				(xy 178.449323 159.6125) (xy 178.518764 159.617318) (xy 178.570088 159.63104) (xy 178.645629 159.677755)
				(xy 178.657769 159.687299) (xy 178.724997 159.737081) (xy 178.851 159.55) (xy 178.724997 159.362919)
				(xy 178.657768 159.412702) (xy 178.574602 159.467106) (xy 178.521748 159.48219) (xy 178.449323 159.4875)
			)
		)
	)
	(zone
		(net 2)
		(net_name "+3V3")
		(layer "F.Cu")
		(name "$teardrop_padvia$")
		(hatch none 0.1)
		(priority 30090)
		(attr
			(teardrop
				(type padvia)
			)
		)
		(connect_pads yes
			(clearance 0)
		)
		(min_thickness 0.0254)
		(filled_areas_thickness no)
		(fill yes
			(thermal_gap 0.5)
			(thermal_bridge_width 0.5)
			(island_removal_mode 1)
			(island_area_min 10)
		)
		(polygon
			(pts
				(xy 145.8525 169.1) (xy 145.871771 169.035503) (xy 145.934063 168.970102) (xy 146.044612 168.915249)
				(xy 146.143137 168.893137) (xy 145.79 168.439) (xy 145.436863 168.893137) (xy 145.50994 168.907665)
				(xy 145.574089 168.929812) (xy 145.629344 168.958799) (xy 145.673288 168.992751) (xy 145.703725 169.028382)
				(xy 145.722066 169.065867) (xy 145.7275 169.1)
			)
		)
	)
	(zone
		(net 1)
		(net_name "GND")
		(layer "F.Cu")
		(name "$teardrop_padvia$")
		(hatch none 0.1)
		(priority 31935)
		(attr
			(teardrop
				(type padvia)
			)
		)
		(connect_pads yes
			(clearance 0)
		)
		(min_thickness 0.0254)
		(filled_areas_thickness no)
		(fill yes
			(thermal_gap 0.5)
			(thermal_bridge_width 0.5)
			(island_removal_mode 1)
			(island_area_min 10)
		)
		(polygon
			(pts
				(xy 110.6 152.23) (xy 110.600153 152.240115) (xy 110.59954 152.270832) (xy 110.591218 152.30332)
				(xy 110.567325 152.332475) (xy 110.52 152.353191) (xy 110.7 152.586) (xy 110.88 152.353191) (xy 110.844099 152.339833)
				(xy 110.820801 152.321601) (xy 110.801101 152.276276) (xy 110.799847 152.240115) (xy 110.8 152.23)
			)
		)
	)
	(zone
		(net 344)
		(net_name "/Com Express 7 MGMT/SER0.TX")
		(layer "F.Cu")
		(name "$teardrop_padvia$")
		(hatch none 0.1)
		(priority 31845)
		(attr
			(teardrop
				(type padvia)
			)
		)
		(connect_pads yes
			(clearance 0)
		)
		(min_thickness 0.0254)
		(filled_areas_thickness no)
		(fill yes
			(thermal_gap 0.5)
			(thermal_bridge_width 0.5)
			(island_removal_mode 1)
			(island_area_min 10)
		)
		(polygon
			(pts
				(xy 224.439127 169.972485) (xy 224.386618 170.018181) (xy 224.340623 170.044768) (xy 224.254174 170.065152)
				(xy 224.238841 170.066988) (xy 224.156105 170.079323) (xy 224.199293 170.300707) (xy 224.420677 170.343895)
				(xy 224.433011 170.26116) (xy 224.453349 170.163881) (xy 224.480057 170.115841) (xy 224.527515 170.060873)
			)
		)
	)
	(zone
		(net 3)
		(net_name "/M.2 key E/WIFI_BT_USB_D_P")
		(layer "F.Cu")
		(name "$teardrop_padvia$")
		(hatch none 0.1)
		(priority 30492)
		(attr
			(teardrop
				(type padvia)
			)
		)
		(connect_pads yes
			(clearance 0)
		)
		(min_thickness 0.0254)
		(filled_areas_thickness no)
		(fill yes
			(thermal_gap 0.5)
			(thermal_bridge_width 0.5)
			(island_removal_mode 1)
			(island_area_min 10)
		)
		(polygon
			(pts
				(xy 155.630722 71.711) (xy 155.692823 71.676007) (xy 155.770273 71.645338) (xy 155.848044 71.626284)
				(xy 155.931051 71.618944) (xy 156.028584 71.63) (xy 155.996 71.31) (xy 155.7 71.212471) (xy 155.70303 71.341749)
				(xy 155.689828 71.437562) (xy 155.672424 71.480558) (xy 155.646914 71.513226) (xy 155.630722 71.526)
			)
		)
	)
	(zone
		(net 401)
		(net_name "/Com Express 7 MGMT/FAM_TACH")
		(layer "F.Cu")
		(name "$teardrop_padvia$")
		(hatch none 0.1)
		(priority 31585)
		(attr
			(teardrop
				(type padvia)
			)
		)
		(connect_pads yes
			(clearance 0)
		)
		(min_thickness 0.0254)
		(filled_areas_thickness no)
		(fill yes
			(thermal_gap 0.5)
			(thermal_bridge_width 0.5)
			(island_removal_mode 1)
			(island_area_min 10)
		)
		(polygon
			(pts
				(xy 236.321385 79.0095) (xy 236.247682 79.004843) (xy 236.19174 78.99224) (xy 236.107031 78.953002)
				(xy 235.990202 78.899926) (xy 235.919708 79.11) (xy 236.045711 79.297081) (xy 236.133306 79.220118)
				(xy 236.204717 79.159381) (xy 236.253668 79.141155) (xy 236.321385 79.1345)
			)
		)
	)
	(zone
		(net 1)
		(net_name "GND")
		(layer "F.Cu")
		(name "$teardrop_padvia$")
		(hatch none 0.1)
		(priority 30751)
		(attr
			(teardrop
				(type padvia)
			)
		)
		(connect_pads yes
			(clearance 0)
		)
		(min_thickness 0.0254)
		(filled_areas_thickness no)
		(fill yes
			(thermal_gap 0.5)
			(thermal_bridge_width 0.5)
			(island_removal_mode 1)
			(island_area_min 10)
		)
		(polygon
			(pts
				(xy 304.296323 75.19) (xy 304.4539 75.196932) (xy 304.567434 75.225456) (xy 304.609222 75.2425)
				(xy 304.698 75.04) (xy 304.609222 74.8375) (xy 304.513177 74.871883) (xy 304.411296 74.887101) (xy 304.296323 74.89)
			)
		)
	)
	(zone
		(net 86)
		(net_name "/Com Express 7 Interfaces/PCIe_{B2Ax4}.RX0-")
		(layer "F.Cu")
		(name "$teardrop_padvia$")
		(hatch none 0.1)
		(priority 31421)
		(attr
			(teardrop
				(type padvia)
			)
		)
		(connect_pads yes
			(clearance 0)
		)
		(min_thickness 0.0254)
		(filled_areas_thickness no)
		(fill yes
			(thermal_gap 0.5)
			(thermal_bridge_width 0.5)
			(island_removal_mode 1)
			(island_area_min 10)
		)
		(polygon
			(pts
				(xy 296.542 75.019852) (xy 296.547395 75.181383) (xy 296.550945 75.265794) (xy 296.546323 75.367488)
				(xy 296.767 75.388348) (xy 296.930231 75.238495) (xy 296.861562 75.184355) (xy 296.845108 75.174464)
				(xy 296.806435 75.149964) (xy 296.774221 75.120457) (xy 296.752173 75.079301) (xy 296.744 75.019852)
			)
		)
	)
	(zone
		(net 1)
		(net_name "GND")
		(layer "F.Cu")
		(name "$teardrop_padvia$")
		(hatch none 0.1)
		(priority 30978)
		(attr
			(teardrop
				(type padvia)
			)
		)
		(connect_pads yes
			(clearance 0)
		)
		(min_thickness 0.0254)
		(filled_areas_thickness no)
		(fill yes
			(thermal_gap 0.5)
			(thermal_bridge_width 0.5)
			(island_removal_mode 1)
			(island_area_min 10)
		)
		(polygon
			(pts
				(xy 112.962 144.9025) (xy 113.024866 144.922469) (xy 113.056844 144.948921) (xy 113.085358 144.986332)
				(xy 113.107882 145.033527) (xy 113.123093 145.091167) (xy 113.123202 145.091798) (xy 113.401 144.84)
				(xy 113.123202 144.588202) (xy 113.108905 144.643635) (xy 113.087825 144.68952) (xy 113.06046 144.727201)
				(xy 113.029552 144.754434) (xy 112.996265 144.771472) (xy 112.963434 144.777489) (xy 112.962 144.7775)
			)
		)
	)
	(zone
		(net 563)
		(net_name "/2xSFP+/~{LED0_1}")
		(layer "F.Cu")
		(name "$teardrop_padvia$")
		(hatch none 0.1)
		(priority 30477)
		(attr
			(teardrop
				(type padvia)
			)
		)
		(connect_pads yes
			(clearance 0)
		)
		(min_thickness 0.0254)
		(filled_areas_thickness no)
		(fill yes
			(thermal_gap 0.5)
			(thermal_bridge_width 0.5)
			(island_removal_mode 1)
			(island_area_min 10)
		)
		(polygon
			(pts
				(xy 156.168444 159.411056) (xy 156.113065 159.327713) (xy 156.076846 159.197724) (xy 156.070483 159.117134)
				(xy 156.074 159.029526) (xy 155.778293 159.109293) (xy 155.723526 159.43) (xy 155.874684 159.420982)
				(xy 155.942215 159.430826) (xy 156.001026 159.449091) (xy 156.080056 159.499444)
			)
		)
	)
	(zone
		(net 977)
		(net_name "/PCIe redriver/RX_EQ1")
		(layer "F.Cu")
		(name "$teardrop_padvia$")
		(hatch none 0.1)
		(priority 31536)
		(attr
			(teardrop
				(type padvia)
			)
		)
		(connect_pads yes
			(clearance 0)
		)
		(min_thickness 0.0254)
		(filled_areas_thickness no)
		(fill yes
			(thermal_gap 0.5)
			(thermal_bridge_width 0.5)
			(island_removal_mode 1)
			(island_area_min 10)
		)
		(polygon
			(pts
				(xy 189.516368 139.416154) (xy 189.529945 139.401889) (xy 189.54942 139.397497) (xy 189.606196 139.419098)
				(xy 189.676729 139.47407) (xy 189.715497 139.110524) (xy 189.348993 139.130396) (xy 189.397782 139.216767)
				(xy 189.414263 139.316588) (xy 189.408976 139.366597) (xy 189.395358 139.408341) (xy 189.391368 139.416154)
			)
		)
	)
	(zone
		(net 216)
		(net_name "/Com Express 7 Interfaces/PCIe_{B1x4}.TX2+")
		(layer "F.Cu")
		(name "$teardrop_padvia$")
		(hatch none 0.1)
		(priority 30252)
		(attr
			(teardrop
				(type padvia)
			)
		)
		(connect_pads yes
			(clearance 0)
		)
		(min_thickness 0.0254)
		(filled_areas_thickness no)
		(fill yes
			(thermal_gap 0.5)
			(thermal_bridge_width 0.5)
			(island_removal_mode 1)
			(island_area_min 10)
		)
		(polygon
			(pts
				(xy 205.9795 167.75) (xy 205.98258 167.764227) (xy 205.984749 167.794527) (xy 205.971877 167.805628)
				(xy 205.941705 167.81) (xy 206.025 168.686) (xy 206.175 168.437021) (xy 206.155644 168.195818) (xy 206.170401 167.923112)
				(xy 206.1815 167.75)
			)
		)
	)
	(zone
		(net 2)
		(net_name "+3V3")
		(layer "F.Cu")
		(name "$teardrop_padvia$")
		(hatch none 0.1)
		(priority 30842)
		(attr
			(teardrop
				(type padvia)
			)
		)
		(connect_pads yes
			(clearance 0)
		)
		(min_thickness 0.0254)
		(filled_areas_thickness no)
		(fill yes
			(thermal_gap 0.5)
			(thermal_bridge_width 0.5)
			(island_removal_mode 1)
			(island_area_min 10)
		)
		(polygon
			(pts
				(xy 238.562001 78.12) (xy 238.608212 78.12621) (xy 238.656611 78.149677) (xy 238.684967 78.177584)
				(xy 238.708013 78.21781) (xy 238.723203 78.271798) (xy 239.001001 78.02) (xy 238.723203 77.768202)
				(xy 238.71007 77.817054) (xy 238.690666 77.854564) (xy 238.638056 77.901987) (xy 238.571555 77.919743)
				(xy 238.562001 77.92)
			)
		)
	)
	(zone
		(net 84)
		(net_name "/Com Express 7 MGMT/PWRBTN")
		(layer "F.Cu")
		(name "$teardrop_padvia$")
		(hatch none 0.1)
		(priority 30483)
		(attr
			(teardrop
				(type padvia)
			)
		)
		(connect_pads yes
			(clearance 0)
		)
		(min_thickness 0.0254)
		(filled_areas_thickness no)
		(fill yes
			(thermal_gap 0.5)
			(thermal_bridge_width 0.5)
			(island_removal_mode 1)
			(island_area_min 10)
		)
		(polygon
			(pts
				(xy 246.048944 129.179444) (xy 246.132287 129.124065) (xy 246.262276 129.087846) (xy 246.342866 129.081483)
				(xy 246.430474 129.085) (xy 246.350707 128.789293) (xy 246.03 128.734526) (xy 246.039018 128.885684)
				(xy 246.029174 128.953215) (xy 246.010909 129.012026) (xy 245.960556 129.091056)
			)
		)
	)
	(zone
		(net 322)
		(net_name "/Com Express 7 Interfaces/SDIO.DAT1")
		(layer "F.Cu")
		(name "$teardrop_padvia$")
		(hatch none 0.1)
		(priority 30049)
		(attr
			(teardrop
				(type padvia)
			)
		)
		(connect_pads yes
			(clearance 0)
		)
		(min_thickness 0.0254)
		(filled_areas_thickness no)
		(fill yes
			(thermal_gap 0.5)
			(thermal_bridge_width 0.5)
			(island_removal_mode 1)
			(island_area_min 10)
		)
		(polygon
			(pts
				(xy 110.657882 131.249189) (xy 110.586067 131.227834) (xy 110.545978 131.20015) (xy 110.509569 131.16187)
				(xy 110.48195 131.117402) (xy 110.462914 131.064757) (xy 110.455 130.997993) (xy 109.504293 131.309293)
				(xy 110.455 131.627999) (xy 110.463771 131.461686) (xy 110.478977 131.410383) (xy 110.505168 131.38257)
				(xy 110.529189 131.377882)
			)
		)
	)
	(zone
		(net 719)
		(net_name "Net-(U40-~{I2C_{RESET}})")
		(layer "F.Cu")
		(name "$teardrop_padvia$")
		(hatch none 0.1)
		(priority 30101)
		(attr
			(teardrop
				(type padvia)
			)
		)
		(connect_pads yes
			(clearance 0)
		)
		(min_thickness 0.0254)
		(filled_areas_thickness no)
		(fill yes
			(thermal_gap 0.5)
			(thermal_bridge_width 0.5)
			(island_removal_mode 1)
			(island_area_min 10)
		)
		(polygon
			(pts
				(xy 194.647282 131.577576) (xy 194.729342 131.582391) (xy 194.794688 131.596095) (xy 194.887955 131.642652)
				(xy 194.966417 131.710862) (xy 195.027917 131.767018) (xy 195.106737 131.826877) (xy 195.316076 131.515076)
				(xy 195.106737 131.203275) (xy 194.986559 131.300295) (xy 194.966417 131.31929) (xy 194.907534 131.372442)
				(xy 194.843451 131.414668) (xy 194.761067 131.442526) (xy 194.647282 131.452576)
			)
		)
	)
	(zone
		(net 372)
		(net_name "/Com Express 7 MGMT/I2C.SDA")
		(layer "F.Cu")
		(name "$teardrop_padvia$")
		(hatch none 0.1)
		(priority 32149)
		(attr
			(teardrop
				(type padvia)
			)
		)
		(connect_pads yes
			(clearance 0)
		)
		(min_thickness 0.0254)
		(filled_areas_thickness no)
		(fill yes
			(thermal_gap 0.5)
			(thermal_bridge_width 0.5)
			(island_removal_mode 1)
			(island_area_min 10)
		)
		(polygon
			(pts
				(xy 305.2375 151.199323) (xy 305.232764 151.171184) (xy 305.219615 151.150239) (xy 305.173158 151.127664)
				(xy 305.096044 151.132043) (xy 305.049681 151.148623) (xy 305.009927 151.173459) (xy 304.984691 151.200944)
				(xy 304.972903 151.232268) (xy 304.9725 151.239) (xy 305.175 151.239) (xy 304.9725 151.239) (xy 304.977082 151.250036)
				(xy 304.989541 151.248577) (xy 305.035632 151.218082) (xy 305.087991 151.183768) (xy 305.105711 151.182013)
				(xy 305.1125 151.199323)
			)
		)
	)
	(zone
		(net 757)
		(net_name "Net-(U45B-LOSB)")
		(layer "F.Cu")
		(name "$teardrop_padvia$")
		(hatch none 0.1)
		(priority 30123)
		(attr
			(teardrop
				(type padvia)
			)
		)
		(connect_pads yes
			(clearance 0)
		)
		(min_thickness 0.0254)
		(filled_areas_thickness no)
		(fill yes
			(thermal_gap 0.5)
			(thermal_bridge_width 0.5)
			(island_removal_mode 1)
			(island_area_min 10)
		)
		(polygon
			(pts
				(xy 128.5025 129.377794) (xy 128.507315 129.295733) (xy 128.521019 129.230388) (xy 128.567576 129.13712)
				(xy 128.635787 129.058657) (xy 128.691942 128.997158) (xy 128.751801 128.918339) (xy 128.44 128.709)
				(xy 128.128199 128.918339) (xy 128.225219 129.038517) (xy 128.244214 129.058658) (xy 128.297366 129.117541)
				(xy 128.339591 129.181624) (xy 128.367449 129.264008) (xy 128.3775 129.377794)
			)
		)
	)
	(zone
		(net 347)
		(net_name "/2xUSB3.0+RJ45/~{GBE0_ACT}")
		(layer "F.Cu")
		(name "$teardrop_padvia$")
		(hatch none 0.1)
		(priority 31843)
		(attr
			(teardrop
				(type padvia)
			)
		)
		(connect_pads yes
			(clearance 0)
		)
		(min_thickness 0.0254)
		(filled_areas_thickness no)
		(fill yes
			(thermal_gap 0.5)
			(thermal_bridge_width 0.5)
			(island_removal_mode 1)
			(island_area_min 10)
		)
		(polygon
			(pts
				(xy 124.119127 97.532485) (xy 124.066618 97.578181) (xy 124.020623 97.604768) (xy 123.934174 97.625152)
				(xy 123.918841 97.626988) (xy 123.836105 97.639323) (xy 123.879293 97.860707) (xy 124.100677 97.903895)
				(xy 124.113011 97.82116) (xy 124.133349 97.723881) (xy 124.160057 97.675841) (xy 124.207515 97.620873)
			)
		)
	)
	(zone
		(net 401)
		(net_name "/Com Express 7 MGMT/FAM_TACH")
		(layer "F.Cu")
		(name "$teardrop_padvia$")
		(hatch none 0.1)
		(priority 31587)
		(attr
			(teardrop
				(type padvia)
			)
		)
		(connect_pads yes
			(clearance 0)
		)
		(min_thickness 0.0254)
		(filled_areas_thickness no)
		(fill yes
			(thermal_gap 0.5)
			(thermal_bridge_width 0.5)
			(island_removal_mode 1)
			(island_area_min 10)
		)
		(polygon
			(pts
				(xy 226.5875 162.087793) (xy 226.59224 162.036431) (xy 226.605419 161.997426) (xy 226.650294 161.943864)
				(xy 226.685714 161.917855) (xy 226.733726 161.881814) (xy 226.780694 161.831389) (xy 226.6 161.699)
				(xy 226.383268 161.753421) (xy 226.421603 161.870931) (xy 226.450489 161.959583) (xy 226.4625 162.087793)
			)
		)
	)
	(zone
		(net 1)
		(net_name "GND")
		(layer "F.Cu")
		(name "$teardrop_padvia$")
		(hatch none 0.1)
		(priority 31182)
		(attr
			(teardrop
				(type padvia)
			)
		)
		(connect_pads yes
			(clearance 0)
		)
		(min_thickness 0.0254)
		(filled_areas_thickness no)
		(fill yes
			(thermal_gap 0.5)
			(thermal_bridge_width 0.5)
			(island_removal_mode 1)
			(island_area_min 10)
		)
		(polygon
			(pts
				(xy 197.625 156.000677) (xy 197.62972 155.931353) (xy 197.642756 155.878449) (xy 197.694658 155.78586)
				(xy 197.746458 155.702363) (xy 197.55 155.599) (xy 197.342355 155.675358) (xy 197.374583 155.755861)
				(xy 197.410965 155.857318) (xy 197.425 156.000677)
			)
		)
	)
	(zone
		(net 558)
		(net_name "Net-(U5-SDA)")
		(layer "F.Cu")
		(name "$teardrop_padvia$")
		(hatch none 0.1)
		(priority 30482)
		(attr
			(teardrop
				(type padvia)
			)
		)
		(connect_pads yes
			(clearance 0)
		)
		(min_thickness 0.0254)
		(filled_areas_thickness no)
		(fill yes
			(thermal_gap 0.5)
			(thermal_bridge_width 0.5)
			(island_removal_mode 1)
			(island_area_min 10)
		)
		(polygon
			(pts
				(xy 160.248944 157.679444) (xy 160.332287 157.624065) (xy 160.462276 157.587846) (xy 160.542866 157.581483)
				(xy 160.630474 157.585) (xy 160.550707 157.289293) (xy 160.23 157.234526) (xy 160.239018 157.385684)
				(xy 160.229174 157.453215) (xy 160.210909 157.512026) (xy 160.160556 157.591056)
			)
		)
	)
	(zone
		(net 1)
		(net_name "GND")
		(layer "F.Cu")
		(name "$teardrop_padvia$")
		(hatch none 0.1)
		(priority 31197)
		(attr
			(teardrop
				(type padvia)
			)
		)
		(connect_pads yes
			(clearance 0)
		)
		(min_thickness 0.0254)
		(filled_areas_thickness no)
		(fill yes
			(thermal_gap 0.5)
			(thermal_bridge_width 0.5)
			(island_removal_mode 1)
			(island_area_min 10)
		)
		(polygon
			(pts
				(xy 175.925 169.599323) (xy 175.92028 169.668646) (xy 175.907244 169.721549) (xy 175.855344 169.814135)
				(xy 175.803541 169.897636) (xy 176 170.001) (xy 176.207644 169.924641) (xy 176.175418 169.844142)
				(xy 176.139035 169.742683) (xy 176.125 169.599323)
			)
		)
	)
	(zone
		(net 1)
		(net_name "GND")
		(layer "F.Cu")
		(name "$teardrop_padvia$")
		(hatch none 0.1)
		(priority 31932)
		(attr
			(teardrop
				(type padvia)
			)
		)
		(connect_pads yes
			(clearance 0)
		)
		(min_thickness 0.0254)
		(filled_areas_thickness no)
		(fill yes
			(thermal_gap 0.5)
			(thermal_bridge_width 0.5)
			(island_removal_mode 1)
			(island_area_min 10)
		)
		(polygon
			(pts
				(xy 314.78 164.06) (xy 314.790115 164.059847) (xy 314.820832 164.06046) (xy 314.85332 164.068782)
				(xy 314.882475 164.092675) (xy 314.903191 164.14) (xy 315.136 163.96) (xy 314.903191 163.78) (xy 314.889833 163.815901)
				(xy 314.871601 163.839199) (xy 314.826276 163.858899) (xy 314.790115 163.860153) (xy 314.78 163.86)
			)
		)
	)
	(zone
		(net 80)
		(net_name "Net-(Q6-D)")
		(layer "F.Cu")
		(name "$teardrop_padvia$")
		(hatch none 0.1)
		(priority 30311)
		(attr
			(teardrop
				(type padvia)
			)
		)
		(connect_pads yes
			(clearance 0)
		)
		(min_thickness 0.0254)
		(filled_areas_thickness no)
		(fill yes
			(thermal_gap 0.5)
			(thermal_bridge_width 0.5)
			(island_removal_mode 1)
			(island_area_min 10)
		)
		(polygon
			(pts
				(xy 261.106476 87.789999) (xy 261.226144 87.769537) (xy 261.367868 87.743687) (xy 261.44204 87.745163)
				(xy 261.515685 87.764999) (xy 261.541 87.469999) (xy 261.22259 87.309475) (xy 261.218296 87.378566)
				(xy 261.205758 87.427468) (xy 261.188823 87.457265) (xy 261.168066 87.47583) (xy 261.117036 87.489769)
				(xy 261.106476 87.489999)
			)
		)
	)
	(zone
		(net 85)
		(net_name "/Com Express 7 MGMT/MAFS_POWER")
		(layer "F.Cu")
		(name "$teardrop_padvia$")
		(hatch none 0.1)
		(priority 30469)
		(attr
			(teardrop
				(type padvia)
			)
		)
		(connect_pads yes
			(clearance 0)
		)
		(min_thickness 0.0254)
		(filled_areas_thickness no)
		(fill yes
			(thermal_gap 0.5)
			(thermal_bridge_width 0.5)
			(island_removal_mode 1)
			(island_area_min 10)
		)
		(polygon
			(pts
				(xy 258.682 161.71) (xy 258.69887 161.709662) (xy 258.743826 161.710241) (xy 258.791169 161.722059)
				(xy 258.833573 161.756638) (xy 258.863708 161.8255) (xy 259.121 161.56) (xy 258.863708 161.2945)
				(xy 258.848151 161.339269) (xy 258.827435 161.370885) (xy 258.776299 161.403619) (xy 258.69887 161.410338)
				(xy 258.682 161.41)
			)
		)
	)
	(zone
		(net 606)
		(net_name "Net-(U37-~{OE4})")
		(layer "F.Cu")
		(name "$teardrop_padvia$")
		(hatch none 0.1)
		(priority 31132)
		(attr
			(teardrop
				(type padvia)
			)
		)
		(connect_pads yes
			(clearance 0)
		)
		(min_thickness 0.0254)
		(filled_areas_thickness no)
		(fill yes
			(thermal_gap 0.5)
			(thermal_bridge_width 0.5)
			(island_removal_mode 1)
			(island_area_min 10)
		)
		(polygon
			(pts
				(xy 221.787 128.2625) (xy 221.846412 128.282273) (xy 221.902497 128.345547) (xy 221.924199 128.394172)
				(xy 221.938873 128.453531) (xy 221.940653 128.4655) (xy 222.201 128.2) (xy 221.940653 127.9345)
				(xy 221.927804 127.994638) (xy 221.90787 128.044522) (xy 221.881945 128.084641) (xy 221.852125 128.113654)
				(xy 221.820707 128.131146) (xy 221.788896 128.137479) (xy 221.787 128.1375)
			)
		)
	)
	(zone
		(net 758)
		(net_name "Net-(U45B-LS_OK_{IN_B})")
		(layer "F.Cu")
		(name "$teardrop_padvia$")
		(hatch none 0.1)
		(priority 31739)
		(attr
			(teardrop
				(type padvia)
			)
		)
		(connect_pads yes
			(clearance 0)
		)
		(min_thickness 0.0254)
		(filled_areas_thickness no)
		(fill yes
			(thermal_gap 0.5)
			(thermal_bridge_width 0.5)
			(island_removal_mode 1)
			(island_area_min 10)
		)
		(polygon
			(pts
				(xy 127.7275 130.109323) (xy 127.722682 130.178763) (xy 127.70896 130.230087) (xy 127.662245 130.305628)
				(xy 127.652702 130.317768) (xy 127.602919 130.384997) (xy 127.79 130.511) (xy 127.977081 130.384997)
				(xy 127.927299 130.317769) (xy 127.872894 130.234603) (xy 127.85781 130.181748) (xy 127.8525 130.109323)
			)
		)
	)
	(zone
		(net 542)
		(net_name "Net-(Q9-E)")
		(layer "F.Cu")
		(name "$teardrop_padvia$")
		(hatch none 0.1)
		(priority 30190)
		(attr
			(teardrop
				(type padvia)
			)
		)
		(connect_pads yes
			(clearance 0)
		)
		(min_thickness 0.0254)
		(filled_areas_thickness no)
		(fill yes
			(thermal_gap 0.5)
			(thermal_bridge_width 0.5)
			(island_removal_mode 1)
			(island_area_min 10)
		)
		(polygon
			(pts
				(xy 121.17 140.811) (xy 121.131486 140.805325) (xy 121.092381 140.785597) (xy 121.065531 140.758719)
				(xy 121.043718 140.719611) (xy 121.026072 140.641) (xy 120.549 140.911) (xy 121.026072 141.181)
				(xy 121.035617 141.126394) (xy 121.052225 141.084158) (xy 121.099911 141.031193) (xy 121.160814 141.011316)
				(xy 121.17 141.011)
			)
		)
	)
	(zone
		(net 1)
		(net_name "GND")
		(layer "F.Cu")
		(name "$teardrop_padvia$")
		(hatch none 0.1)
		(priority 31940)
		(attr
			(teardrop
				(type padvia)
			)
		)
		(connect_pads yes
			(clearance 0)
		)
		(min_thickness 0.0254)
		(filled_areas_thickness no)
		(fill yes
			(thermal_gap 0.5)
			(thermal_bridge_width 0.5)
			(island_removal_mode 1)
			(island_area_min 10)
		)
		(polygon
			(pts
				(xy 107.5 151.458) (xy 107.500153 151.468115) (xy 107.49954 151.498832) (xy 107.491218 151.53132)
				(xy 107.467325 151.560475) (xy 107.42 151.581191) (xy 107.6 151.814) (xy 107.78 151.581191) (xy 107.744099 151.567833)
				(xy 107.720801 151.549601) (xy 107.701101 151.504276) (xy 107.699847 151.468115) (xy 107.7 151.458)
			)
		)
	)
	(zone
		(net 929)
		(net_name "/2xSFP+/SFP1_LEDG")
		(layer "F.Cu")
		(name "$teardrop_padvia$")
		(hatch none 0.1)
		(priority 31060)
		(attr
			(teardrop
				(type padvia)
			)
		)
		(connect_pads yes
			(clearance 0)
		)
		(min_thickness 0.0254)
		(filled_areas_thickness no)
		(fill yes
			(thermal_gap 0.5)
			(thermal_bridge_width 0.5)
			(island_removal_mode 1)
			(island_area_min 10)
		)
		(polygon
			(pts
				(xy 156.192 168.2975) (xy 156.132588 168.277727) (xy 156.076503 168.214453) (xy 156.054801 168.165828)
				(xy 156.040127 168.106468) (xy 156.038347 168.0945) (xy 155.778 168.36) (xy 156.038347 168.6255)
				(xy 156.051197 168.565361) (xy 156.071131 168.515477) (xy 156.097056 168.475358) (xy 156.126876 168.446345)
				(xy 156.158294 168.428854) (xy 156.190105 168.422521) (xy 156.192 168.4225)
			)
		)
	)
	(zone
		(net 1)
		(net_name "GND")
		(layer "F.Cu")
		(name "$teardrop_padvia$")
		(hatch none 0.1)
		(priority 30569)
		(attr
			(teardrop
				(type padvia)
			)
		)
		(connect_pads yes
			(clearance 0)
		)
		(min_thickness 0.0254)
		(filled_areas_thickness no)
		(fill yes
			(thermal_gap 0.5)
			(thermal_bridge_width 0.5)
			(island_removal_mode 1)
			(island_area_min 10)
		)
		(polygon
			(pts
				(xy 214.925 162.2) (xy 214.928333 162.214486) (xy 214.93119 162.24461) (xy 214.919036 162.255651)
				(xy 214.89 162.26) (xy 215.025 163.136) (xy 215.16 162.26) (xy 215.130666 162.255525) (xy 215.118642 162.244199)
				(xy 215.121667 162.214486) (xy 215.125 162.2)
			)
		)
	)
	(zone
		(net 613)
		(net_name "/PCIe misc/DIF1+")
		(layer "F.Cu")
		(name "$teardrop_padvia$")
		(hatch none 0.1)
		(priority 30413)
		(attr
			(teardrop
				(type padvia)
			)
		)
		(connect_pads yes
			(clearance 0)
		)
		(min_thickness 0.0254)
		(filled_areas_thickness no)
		(fill yes
			(thermal_gap 0.5)
			(thermal_bridge_width 0.5)
			(island_removal_mode 1)
			(island_area_min 10)
		)
		(polygon
			(pts
				(xy 212.126065 129.619) (xy 212.09849 129.604933) (xy 212.077463 129.582207) (xy 212.053293 129.509527)
				(xy 212.051599 129.364838) (xy 212.055 129.322271) (xy 211.759 129.425) (xy 211.733348 129.745)
				(xy 211.843763 129.740489) (xy 211.97628 129.768997) (xy 212.066549 129.800138) (xy 212.126065 129.821)
			)
		)
	)
	(zone
		(net 365)
		(net_name "/Com Express 7 MGMT/PWR_OK")
		(layer "F.Cu")
		(name "$teardrop_padvia$")
		(hatch none 0.1)
		(priority 31887)
		(attr
			(teardrop
				(type padvia)
			)
		)
		(connect_pads yes
			(clearance 0)
		)
		(min_thickness 0.0254)
		(filled_areas_thickness no)
		(fill yes
			(thermal_gap 0.5)
			(thermal_bridge_width 0.5)
			(island_removal_mode 1)
			(island_area_min 10)
		)
		(polygon
			(pts
				(xy 203.277515 112.289127) (xy 203.231819 112.236618) (xy 203.205231 112.190623) (xy 203.184847 112.104175)
				(xy 203.183011 112.08884) (xy 203.170677 112.006105) (xy 202.949293 112.049293) (xy 202.906105 112.270677)
				(xy 202.98884 112.283011) (xy 203.086119 112.303349) (xy 203.134159 112.330057) (xy 203.189127 112.377515)
			)
		)
	)
	(zone
		(net 2)
		(net_name "+3V3")
		(layer "F.Cu")
		(name "$teardrop_padvia$")
		(hatch none 0.1)
		(priority 30394)
		(attr
			(teardrop
				(type padvia)
			)
		)
		(connect_pads yes
			(clearance 0)
		)
		(min_thickness 0.0254)
		(filled_areas_thickness no)
		(fill yes
			(thermal_gap 0.5)
			(thermal_bridge_width 0.5)
			(island_removal_mode 1)
			(island_area_min 10)
		)
		(polygon
			(pts
				(xy 195.148906 137.148596) (xy 195.10291 137.131454) (xy 195.065882 137.121039) (xy 195.036865 137.104146)
				(xy 195.027947 137.07529) (xy 195.051217 137.028986) (xy 194.679387 137.03263) (xy 194.675743 137.40446)
				(xy 194.709622 137.384468) (xy 194.734493 137.381387) (xy 194.760882 137.403541) (xy 194.778211 137.456153)
				(xy 194.795353 137.502149)
			)
		)
	)
	(zone
		(net 289)
		(net_name "/2xUSB3.0+RJ45/GbE.MDI2-")
		(layer "F.Cu")
		(name "$teardrop_padvia$")
		(hatch none 0.1)
		(priority 30305)
		(attr
			(teardrop
				(type padvia)
			)
		)
		(connect_pads yes
			(clearance 0)
		)
		(min_thickness 0.0254)
		(filled_areas_thickness no)
		(fill yes
			(thermal_gap 0.5)
			(thermal_bridge_width 0.5)
			(island_removal_mode 1)
			(island_area_min 10)
		)
		(polygon
			(pts
				(xy 178.525 167.75) (xy 178.525035 167.754084) (xy 178.517242 167.790449) (xy 178.497831 167.804416)
				(xy 178.459759 167.81) (xy 178.525 168.686) (xy 178.675 168.504204) (xy 178.658334 168.198008) (xy 178.667809 167.932252)
				(xy 178.675 167.75)
			)
		)
	)
	(zone
		(net 1)
		(net_name "GND")
		(layer "F.Cu")
		(name "$teardrop_padvia$")
		(hatch none 0.1)
		(priority 30800)
		(attr
			(teardrop
				(type padvia)
			)
		)
		(connect_pads yes
			(clearance 0)
		)
		(min_thickness 0.0254)
		(filled_areas_thickness no)
		(fill yes
			(thermal_gap 0.5)
			(thermal_bridge_width 0.5)
			(island_removal_mode 1)
			(island_area_min 10)
		)
		(polygon
			(pts
				(xy 253.25 165.129323) (xy 253.243069 165.286893) (xy 253.214549 165.400421) (xy 253.1975 165.442221)
				(xy 253.4 165.531) (xy 253.6025 165.442221) (xy 253.568117 165.346179) (xy 253.5529 165.244304)
				(xy 253.55 165.129323)
			)
		)
	)
	(zone
		(net 208)
		(net_name "/Backplane/UART.RX")
		(layer "F.Cu")
		(name "$teardrop_padvia$")
		(hatch none 0.1)
		(priority 31661)
		(attr
			(teardrop
				(type padvia)
			)
		)
		(connect_pads yes
			(clearance 0)
		)
		(min_thickness 0.0254)
		(filled_areas_thickness no)
		(fill yes
			(thermal_gap 0.5)
			(thermal_bridge_width 0.5)
			(island_removal_mode 1)
			(island_area_min 10)
		)
		(polygon
			(pts
				(xy 230.882166 170.5625) (xy 230.999484 170.557989) (xy 231.082232 170.546415) (xy 231.113865 170.540415)
				(xy 231.230279 170.520677) (xy 231.201 170.3) (xy 231.010713 170.18032) (xy 230.985172 170.25076)
				(xy 230.978648 170.31241) (xy 230.973903 170.360686) (xy 230.961525 170.400493) (xy 230.933587 170.427532)
				(xy 230.882166 170.4375)
			)
		)
	)
	(zone
		(net 588)
		(net_name "/Misc/~{ADDREN}")
		(layer "F.Cu")
		(name "$teardrop_padvia$")
		(hatch none 0.1)
		(priority 31056)
		(attr
			(teardrop
				(type padvia)
			)
		)
		(connect_pads yes
			(clearance 0)
		)
		(min_thickness 0.0254)
		(filled_areas_thickness no)
		(fill yes
			(thermal_gap 0.5)
			(thermal_bridge_width 0.5)
			(island_removal_mode 1)
			(island_area_min 10)
		)
		(polygon
			(pts
				(xy 253.507999 81.112499) (xy 253.448587 81.092726) (xy 253.392502 81.029452) (xy 253.3708 80.980827)
				(xy 253.356126 80.921467) (xy 253.354346 80.909499) (xy 253.093999 81.174999) (xy 253.354346 81.440499)
				(xy 253.367196 81.38036) (xy 253.38713 81.330476) (xy 253.413055 81.290357) (xy 253.442875 81.261344)
				(xy 253.474293 81.243853) (xy 253.506104 81.23752) (xy 253.507999 81.237499)
			)
		)
	)
	(zone
		(net 648)
		(net_name "/2xSFP+/KR to SFI #1/MDIO_R")
		(layer "F.Cu")
		(name "$teardrop_padvia$")
		(hatch none 0.1)
		(priority 31517)
		(attr
			(teardrop
				(type padvia)
			)
		)
		(connect_pads yes
			(clearance 0)
		)
		(min_thickness 0.0254)
		(filled_areas_thickness no)
		(fill yes
			(thermal_gap 0.5)
			(thermal_bridge_width 0.5)
			(island_removal_mode 1)
			(island_area_min 10)
		)
		(polygon
			(pts
				(xy 141.523537 144.099851) (xy 141.545047 144.103721) (xy 141.563401 144.117253) (xy 141.592233 144.177231)
				(xy 141.606228 144.278946) (xy 141.890707 144.049293) (xy 141.628435 143.787818) (xy 141.598153 143.884294)
				(xy 141.536777 143.963352) (xy 141.497977 143.991311) (xy 141.458923 144.007634) (xy 141.435149 144.011463)
			)
		)
	)
	(zone
		(net 894)
		(net_name "Net-(J2B-MOD_{ABS})")
		(layer "F.Cu")
		(name "$teardrop_padvia$")
		(hatch none 0.1)
		(priority 31834)
		(attr
			(teardrop
				(type padvia)
			)
		)
		(connect_pads yes
			(clearance 0)
		)
		(min_thickness 0.0254)
		(filled_areas_thickness no)
		(fill yes
			(thermal_gap 0.5)
			(thermal_bridge_width 0.5)
			(island_removal_mode 1)
			(island_area_min 10)
		)
		(polygon
			(pts
				(xy 176.400677 145.9375) (xy 176.331236 145.932682) (xy 176.279913 145.91896) (xy 176.204371 145.872246)
				(xy 176.192231 145.862701) (xy 176.125003 145.812919) (xy 175.999 146) (xy 176.125003 146.187081)
				(xy 176.192229 146.137299) (xy 176.275396 146.082894) (xy 176.328251 146.06781) (xy 176.400677 146.0625)
			)
		)
	)
	(zone
		(net 354)
		(net_name "Net-(J12D-~{LPC_DRQ1}{slash}~{ESPI_ALERT1})")
		(layer "F.Cu")
		(name "$teardrop_padvia$")
		(hatch none 0.1)
		(priority 30663)
		(attr
			(teardrop
				(type padvia)
			)
		)
		(connect_pads yes
			(clearance 0)
		)
		(min_thickness 0.0254)
		(filled_areas_thickness no)
		(fill yes
			(thermal_gap 0.5)
			(thermal_bridge_width 0.5)
			(island_removal_mode 1)
			(island_area_min 10)
		)
		(polygon
			(pts
				(xy 180.0875 164.07) (xy 180.098438 164.031177) (xy 180.120195 164.016067) (xy 180.16 164.01) (xy 180.025 163.134)
				(xy 179.89 164.01) (xy 179.925281 164.014517) (xy 179.946797 164.026138) (xy 179.961995 164.058961)
				(xy 179.9625 164.07)
			)
		)
	)
	(zone
		(net 128)
		(net_name "/USB-C console/FTDI_LED_TX")
		(layer "F.Cu")
		(name "$teardrop_padvia$")
		(hatch none 0.1)
		(priority 31633)
		(attr
			(teardrop
				(type padvia)
			)
		)
		(connect_pads yes
			(clearance 0)
		)
		(min_thickness 0.0254)
		(filled_areas_thickness no)
		(fill yes
			(thermal_gap 0.5)
			(thermal_bridge_width 0.5)
			(island_removal_mode 1)
			(island_area_min 10)
		)
		(polygon
			(pts
				(xy 112.779999 74.9125) (xy 112.807071 74.918022) (xy 112.83261 74.936678) (xy 112.848779 74.963297)
				(xy 112.858398 75.002038) (xy 112.859999 75.03) (xy 113.260999 74.85) (xy 112.859999 74.67) (xy 112.855386 74.7155)
				(xy 112.843099 74.748468) (xy 112.804944 74.782844) (xy 112.779999 74.7875)
			)
		)
	)
	(zone
		(net 193)
		(net_name "/OCuLink/PCIe_{REF0}.CK-")
		(layer "F.Cu")
		(name "$teardrop_padvia$")
		(hatch none 0.1)
		(priority 32070)
		(attr
			(teardrop
				(type padvia)
			)
		)
		(connect_pads yes
			(clearance 0)
		)
		(min_thickness 0.0254)
		(filled_areas_thickness no)
		(fill yes
			(thermal_gap 0.5)
			(thermal_bridge_width 0.5)
			(island_removal_mode 1)
			(island_area_min 10)
		)
		(polygon
			(pts
				(xy 111.099 152.26) (xy 111.106198 152.280648) (xy 111.115792 152.312984) (xy 111.108965 152.327007)
				(xy 111.0875 152.336995) (xy 111.2 152.586) (xy 111.3125 152.336995) (xy 111.291324 152.327271)
				(xy 111.284269 152.313643) (xy 111.293802 152.280648) (xy 111.301 152.26)
			)
		)
	)
	(zone
		(net 422)
		(net_name "/2xSFP+/I2C_{LED}.SDA")
		(layer "F.Cu")
		(name "$teardrop_padvia$")
		(hatch none 0.1)
		(priority 30693)
		(attr
			(teardrop
				(type padvia)
			)
		)
		(connect_pads yes
			(clearance 0)
		)
		(min_thickness 0.0254)
		(filled_areas_thickness no)
		(fill yes
			(thermal_gap 0.5)
			(thermal_bridge_width 0.5)
			(island_removal_mode 1)
			(island_area_min 10)
		)
		(polygon
			(pts
				(xy 193.4625 155.75) (xy 193.451563 155.788823) (xy 193.429805 155.803933) (xy 193.39 155.81) (xy 193.525 156.686)
				(xy 193.66 155.81) (xy 193.624719 155.805483) (xy 193.603203 155.793862) (xy 193.588005 155.761039)
				(xy 193.5875 155.75)
			)
		)
	)
	(zone
		(net 371)
		(net_name "/Com Express 7 MGMT/I2C.SCL")
		(layer "F.Cu")
		(name "$teardrop_padvia$")
		(hatch none 0.1)
		(priority 31745)
		(attr
			(teardrop
				(type padvia)
			)
		)
		(connect_pads yes
			(clearance 0)
		)
		(min_thickness 0.0254)
		(filled_areas_thickness no)
		(fill yes
			(thermal_gap 0.5)
			(thermal_bridge_width 0.5)
			(island_removal_mode 1)
			(island_area_min 10)
		)
		(polygon
			(pts
				(xy 239.774323 153.1625) (xy 239.843764 153.167318) (xy 239.895088 153.18104) (xy 239.970629 153.227755)
				(xy 239.982769 153.237299) (xy 240.049997 153.287081) (xy 240.176 153.1) (xy 240.049997 152.912919)
				(xy 239.982768 152.962702) (xy 239.899602 153.017106) (xy 239.846748 153.03219) (xy 239.774323 153.0375)
			)
		)
	)
	(zone
		(net 282)
		(net_name "/Misc/PWM_{B5V}")
		(layer "F.Cu")
		(name "$teardrop_padvia$")
		(hatch none 0.1)
		(priority 30357)
		(attr
			(teardrop
				(type padvia)
			)
		)
		(connect_pads yes
			(clearance 0)
		)
		(min_thickness 0.0254)
		(filled_areas_thickness no)
		(fill yes
			(thermal_gap 0.5)
			(thermal_bridge_width 0.5)
			(island_removal_mode 1)
			(island_area_min 10)
		)
		(polygon
			(pts
				(xy 245.737709 77.1855) (xy 245.771572 77.191281) (xy 245.806193 77.211745) (xy 245.828015 77.23881)
				(xy 245.843709 77.27815) (xy 245.846998 77.293711) (xy 246.553709 77.123) (xy 245.846998 76.952289)
				(xy 245.835409 76.99251) (xy 245.817825 77.021984) (xy 245.770243 77.055173) (xy 245.737709 77.0605)
			)
		)
	)
	(zone
		(net 533)
		(net_name "/Com Express 7 MGMT/PSON")
		(layer "F.Cu")
		(name "$teardrop_padvia$")
		(hatch none 0.1)
		(priority 30208)
		(attr
			(teardrop
				(type padvia)
			)
		)
		(connect_pads yes
			(clearance 0)
		)
		(min_thickness 0.0254)
		(filled_areas_thickness no)
		(fill yes
			(thermal_gap 0.5)
			(thermal_bridge_width 0.5)
			(island_removal_mode 1)
			(island_area_min 10)
		)
		(polygon
			(pts
				(xy 258.187 131.03) (xy 258.206721 130.97274) (xy 258.269533 130.920216) (xy 258.318153 130.900449)
				(xy 258.377451 130.887923) (xy 258.3945 130.886072) (xy 258.1245 130.409) (xy 257.8545 130.886072)
				(xy 257.915744 130.896248) (xy 257.966671 130.913925) (xy 258.007514 130.937823) (xy 258.037197 130.966022)
				(xy 258.05513 130.996012) (xy 258.061941 131.026862) (xy 258.062 131.03)
			)
		)
	)
	(zone
		(net 50)
		(net_name "Net-(C12-Pad2)")
		(layer "F.Cu")
		(name "$teardrop_padvia$")
		(hatch none 0.1)
		(priority 30875)
		(attr
			(teardrop
				(type padvia)
			)
		)
		(connect_pads yes
			(clearance 0)
		)
		(min_thickness 0.0254)
		(filled_areas_thickness no)
		(fill yes
			(thermal_gap 0.5)
			(thermal_bridge_width 0.5)
			(island_removal_mode 1)
			(island_area_min 10)
		)
		(polygon
			(pts
				(xy 137.493 101.31) (xy 137.452263 101.304228) (xy 137.410348 101.283824) (xy 137.382047 101.256649)
				(xy 137.358618 101.217103) (xy 137.339347 101.1445) (xy 137.079 101.41) (xy 137.339347 101.6755)
				(xy 137.351214 101.622358) (xy 137.369662 101.581319) (xy 137.420336 101.529618) (xy 137.483905 101.510282)
				(xy 137.493 101.51)
			)
		)
	)
	(zone
		(net 532)
		(net_name "/Backplane/PCIe_{x2}.RX0+")
		(layer "F.Cu")
		(name "$teardrop_padvia$")
		(hatch none 0.1)
		(priority 32091)
		(attr
			(teardrop
				(type padvia)
			)
		)
		(connect_pads yes
			(clearance 0)
		)
		(min_thickness 0.0254)
		(filled_areas_thickness no)
		(fill yes
			(thermal_gap 0.5)
			(thermal_bridge_width 0.5)
			(island_removal_mode 1)
			(island_area_min 10)
		)
		(polygon
			(pts
				(xy 314.688 159.809) (xy 314.667352 159.816199) (xy 314.635017 159.825792) (xy 314.620994 159.818965)
				(xy 314.611005 159.7975) (xy 314.362 159.91) (xy 314.611005 160.0225) (xy 314.62073 160.001324)
				(xy 314.634358 159.994269) (xy 314.667352 160.003801) (xy 314.688 160.011)
			)
		)
	)
	(zone
		(net 2)
		(net_name "+3V3")
		(layer "F.Cu")
		(name "$teardrop_padvia$")
		(hatch none 0.1)
		(priority 31300)
		(attr
			(teardrop
				(type padvia)
			)
		)
		(connect_pads yes
			(clearance 0)
		)
		(min_thickness 0.0254)
		(filled_areas_thickness no)
		(fill yes
			(thermal_gap 0.5)
			(thermal_bridge_width 0.5)
			(island_removal_mode 1)
			(island_area_min 10)
		)
		(polygon
			(pts
				(xy 131 82.640676) (xy 131.004712 82.562765) (xy 131.017699 82.503981) (xy 131.059801 82.412948)
				(xy 131.1025 82.327777) (xy 130.9 82.239001) (xy 130.6975 82.327778) (xy 130.740199 82.412949) (xy 130.782867 82.505783)
				(xy 130.795444 82.563922) (xy 130.800001 82.640677)
			)
		)
	)
	(zone
		(net 589)
		(net_name "/Misc/~{ADDRSEL}")
		(layer "F.Cu")
		(name "$teardrop_padvia$")
		(hatch none 0.1)
		(priority 31046)
		(attr
			(teardrop
				(type padvia)
			)
		)
		(connect_pads yes
			(clearance 0)
		)
		(min_thickness 0.0254)
		(filled_areas_thickness no)
		(fill yes
			(thermal_gap 0.5)
			(thermal_bridge_width 0.5)
			(island_removal_mode 1)
			(island_area_min 10)
		)
		(polygon
			(pts
				(xy 253.508 83.127499) (xy 253.4504 83.107789) (xy 253.397111 83.044883) (xy 253.376468 82.995766)
				(xy 253.362828 82.935807) (xy 253.360687 82.918987) (xy 253.094 83.174999) (xy 253.348079 83.449879)
				(xy 253.36224 83.391771) (xy 253.383263 83.343593) (xy 253.410355 83.304434) (xy 253.441106 83.27611)
				(xy 253.473703 83.258745) (xy 253.506259 83.252516) (xy 253.508 83.252499)
			)
		)
	)
	(zone
		(net 1)
		(net_name "GND")
		(layer "F.Cu")
		(name "$teardrop_padvia$")
		(hatch none 0.1)
		(priority 30602)
		(attr
			(teardrop
				(type padvia)
			)
		)
		(connect_pads yes
			(clearance 0)
		)
		(min_thickness 0.0254)
		(filled_areas_thickness no)
		(fill yes
			(thermal_gap 0.5)
			(thermal_bridge_width 0.5)
			(island_removal_mode 1)
			(island_area_min 10)
		)
		(polygon
			(pts
				(xy 230.625 157.62) (xy 230.621667 157.605514) (xy 230.61881 157.57539) (xy 230.630964 157.564349)
				(xy 230.66 157.56) (xy 230.525 156.684) (xy 230.39 157.56) (xy 230.419334 157.564475) (xy 230.431358 157.575801)
				(xy 230.428333 157.605514) (xy 230.425 157.62)
			)
		)
	)
	(zone
		(net 2)
		(net_name "+3V3")
		(layer "F.Cu")
		(name "$teardrop_padvia$")
		(hatch none 0.1)
		(priority 31512)
		(attr
			(teardrop
				(type padvia)
			)
		)
		(connect_pads yes
			(clearance 0)
		)
		(min_thickness 0.0254)
		(filled_areas_thickness no)
		(fill yes
			(thermal_gap 0.5)
			(thermal_bridge_width 0.5)
			(island_removal_mode 1)
			(island_area_min 10)
		)
		(polygon
			(pts
				(xy 212.949905 126.826) (xy 212.870191 126.830518) (xy 212.809107 126.842146) (xy 212.740723 126.864374)
				(xy 212.679403 126.884789) (xy 212.602212 126.900323) (xy 212.629 127.121) (xy 212.818374 127.24288)
				(xy 212.844362 127.174612) (xy 212.850851 127.138767) (xy 212.859206 127.095636) (xy 212.873923 127.059707)
				(xy 212.901867 127.035116) (xy 212.949905 127.026)
			)
		)
	)
	(zone
		(net 87)
		(net_name "/Com Express 7 Interfaces/PCIe_{B2Ax4}.RX1-")
		(layer "F.Cu")
		(name "$teardrop_padvia$")
		(hatch none 0.1)
		(priority 31424)
		(attr
			(teardrop
				(type padvia)
			)
		)
		(connect_pads yes
			(clearance 0)
		)
		(min_thickness 0.0254)
		(filled_areas_thickness no)
		(fill yes
			(thermal_gap 0.5)
			(thermal_bridge_width 0.5)
			(island_removal_mode 1)
			(island_area_min 10)
		)
		(polygon
			(pts
				(xy 293.543 75.019852) (xy 293.548395 75.181383) (xy 293.551945 75.265794) (xy 293.547323 75.367488)
				(xy 293.768 75.388348) (xy 293.931231 75.238495) (xy 293.862562 75.184355) (xy 293.846108 75.174464)
				(xy 293.807435 75.149964) (xy 293.775221 75.120457) (xy 293.753173 75.079301) (xy 293.745 75.019852)
			)
		)
	)
	(zone
		(net 370)
		(net_name "Net-(J12D-SPKR)")
		(layer "F.Cu")
		(name "$teardrop_padvia$")
		(hatch none 0.1)
		(priority 31601)
		(attr
			(teardrop
				(type padvia)
			)
		)
		(connect_pads yes
			(clearance 0)
		)
		(min_thickness 0.0254)
		(filled_areas_thickness no)
		(fill yes
			(thermal_gap 0.5)
			(thermal_bridge_width 0.5)
			(island_removal_mode 1)
			(island_area_min 10)
		)
		(polygon
			(pts
				(xy 191.4625 163.899323) (xy 191.457831 163.969201) (xy 191.445144 164.022579) (xy 191.400666 164.109579)
				(xy 191.342355 164.224641) (xy 191.55 164.301) (xy 191.737081 164.174997) (xy 191.66863 164.092342)
				(xy 191.610755 164.017857) (xy 191.593685 163.967955) (xy 191.5875 163.899323)
			)
		)
	)
	(zone
		(net 1)
		(net_name "GND")
		(layer "F.Cu")
		(name "$teardrop_padvia$")
		(hatch none 0.1)
		(priority 31475)
		(attr
			(teardrop
				(type padvia)
			)
		)
		(connect_pads yes
			(clearance 0)
		)
		(min_thickness 0.0254)
		(filled_areas_thickness no)
		(fill yes
			(thermal_gap 0.5)
			(thermal_bridge_width 0.5)
			(island_removal_mode 1)
			(island_area_min 10)
		)
		(polygon
			(pts
				(xy 189.425 157.592521) (xy 189.420244 157.628191) (xy 189.406956 157.652354) (xy 189.364009 157.675101)
				(xy 189.304664 157.681887) (xy 189.246614 157.687751) (xy 189.191538 157.706067) (xy 189.3 157.901)
				(xy 189.520677 157.942084) (xy 189.556383 157.834598) (xy 189.571583 157.804075) (xy 189.608524 157.718227)
				(xy 189.620491 157.663061) (xy 189.625 157.592521)
			)
		)
	)
	(zone
		(net 1)
		(net_name "GND")
		(layer "F.Cu")
		(name "$teardrop_padvia$")
		(hatch none 0.1)
		(priority 31289)
		(attr
			(teardrop
				(type padvia)
			)
		)
		(connect_pads yes
			(clearance 0)
		)
		(min_thickness 0.0254)
		(filled_areas_thickness no)
		(fill yes
			(thermal_gap 0.5)
			(thermal_bridge_width 0.5)
			(island_removal_mode 1)
			(island_area_min 10)
		)
		(polygon
			(pts
				(xy 197.60861 77.701486) (xy 197.603897 77.779397) (xy 197.59091 77.838181) (xy 197.548809 77.929211)
				(xy 197.50611 78.014384) (xy 197.70861 78.103163) (xy 197.91111 78.014384) (xy 197.868411 77.929213)
				(xy 197.825743 77.83638) (xy 197.813166 77.778241) (xy 197.80861 77.701486)
			)
		)
	)
	(zone
		(net 92)
		(net_name "/Com Express 7 Interfaces/PCIe_{B2Ax4}.RX2+")
		(layer "F.Cu")
		(name "$teardrop_padvia$")
		(hatch none 0.1)
		(priority 30260)
		(attr
			(teardrop
				(type padvia)
			)
		)
		(connect_pads yes
			(clearance 0)
		)
		(min_thickness 0.0254)
		(filled_areas_thickness no)
		(fill yes
			(thermal_gap 0.5)
			(thermal_bridge_width 0.5)
			(island_removal_mode 1)
			(island_area_min 10)
		)
		(polygon
			(pts
				(xy 213.9795 162.2) (xy 213.98258 162.214227) (xy 213.984749 162.244527) (xy 213.971877 162.255628)
				(xy 213.941705 162.26) (xy 214.025 163.136) (xy 214.175 162.887021) (xy 214.155644 162.645818) (xy 214.170401 162.373112)
				(xy 214.1815 162.2)
			)
		)
	)
	(zone
		(net 537)
		(net_name "/Backplane/PCIe_{x2}.RX0-")
		(layer "F.Cu")
		(name "$teardrop_padvia$")
		(hatch none 0.1)
		(priority 32090)
		(attr
			(teardrop
				(type padvia)
			)
		)
		(connect_pads yes
			(clearance 0)
		)
		(min_thickness 0.0254)
		(filled_areas_thickness no)
		(fill yes
			(thermal_gap 0.5)
			(thermal_bridge_width 0.5)
			(island_removal_mode 1)
			(island_area_min 10)
		)
		(polygon
			(pts
				(xy 314.81 160.511) (xy 314.830648 160.503802) (xy 314.862984 160.494208) (xy 314.877007 160.501035)
				(xy 314.886995 160.5225) (xy 315.136 160.41) (xy 314.886995 160.2975) (xy 314.877271 160.318676)
				(xy 314.863643 160.325731) (xy 314.830648 160.316198) (xy 314.81 160.309)
			)
		)
	)
	(zone
		(net 264)
		(net_name "/Com Express 7 Interfaces/PCIe_{B2Bx4}.RX0+")
		(layer "F.Cu")
		(name "$teardrop_padvia$")
		(hatch none 0.1)
		(priority 31404)
		(attr
			(teardrop
				(type padvia)
			)
		)
		(connect_pads yes
			(clearance 0)
		)
		(min_thickness 0.0254)
		(filled_areas_thickness no)
		(fill yes
			(thermal_gap 0.5)
			(thermal_bridge_width 0.5)
			(island_removal_mode 1)
			(island_area_min 10)
		)
		(polygon
			(pts
				(xy 173.232504 103.0165) (xy 173.394035 103.011105) (xy 173.478445 103.007554) (xy 173.58014 103.012177)
				(xy 173.601 102.7915) (xy 173.451147 102.628268) (xy 173.397007 102.696935) (xy 173.387115 102.713393)
				(xy 173.362615 102.752065) (xy 173.333109 102.784279) (xy 173.291953 102.806327) (xy 173.232504 102.8145)
			)
		)
	)
	(zone
		(net 556)
		(net_name "/2xUSB3.0+RJ45/EN_2B")
		(layer "F.Cu")
		(name "$teardrop_padvia$")
		(hatch none 0.1)
		(priority 31136)
		(attr
			(teardrop
				(type padvia)
			)
		)
		(connect_pads yes
			(clearance 0)
		)
		(min_thickness 0.0254)
		(filled_areas_thickness no)
		(fill yes
			(thermal_gap 0.5)
			(thermal_bridge_width 0.5)
			(island_removal_mode 1)
			(island_area_min 10)
		)
		(polygon
			(pts
				(xy 121.157 91.0225) (xy 121.216412 91.042273) (xy 121.272497 91.105547) (xy 121.294199 91.154172)
				(xy 121.308873 91.213531) (xy 121.310653 91.2255) (xy 121.571 90.96) (xy 121.310653 90.6945) (xy 121.297804 90.754638)
				(xy 121.27787 90.804522) (xy 121.251945 90.844641) (xy 121.222125 90.873654) (xy 121.190707 90.891146)
				(xy 121.158896 90.897479) (xy 121.157 90.8975)
			)
		)
	)
	(zone
		(net 1)
		(net_name "GND")
		(layer "F.Cu")
		(name "$teardrop_padvia$")
		(hatch none 0.1)
		(priority 30565)
		(attr
			(teardrop
				(type padvia)
			)
		)
		(connect_pads yes
			(clearance 0)
		)
		(min_thickness 0.0254)
		(filled_areas_thickness no)
		(fill yes
			(thermal_gap 0.5)
			(thermal_bridge_width 0.5)
			(island_removal_mode 1)
			(island_area_min 10)
		)
		(polygon
			(pts
				(xy 208.425 167.75) (xy 208.428333 167.764486) (xy 208.43119 167.79461) (xy 208.419036 167.805651)
				(xy 208.39 167.81) (xy 208.525 168.686) (xy 208.66 167.81) (xy 208.630666 167.805525) (xy 208.618642 167.794199)
				(xy 208.621667 167.764486) (xy 208.625 167.75)
			)
		)
	)
	(zone
		(net 46)
		(net_name "Net-(U34-OFFT)")
		(layer "F.Cu")
		(name "$teardrop_padvia$")
		(hatch none 0.1)
		(priority 30498)
		(attr
			(teardrop
				(type padvia)
			)
		)
		(connect_pads yes
			(clearance 0)
		)
		(min_thickness 0.0254)
		(filled_areas_thickness no)
		(fill yes
			(thermal_gap 0.5)
			(thermal_bridge_width 0.5)
			(island_removal_mode 1)
			(island_area_min 10)
		)
		(polygon
			(pts
				(xy 244.410556 131.572944) (xy 244.460409 131.650761) (xy 244.488529 131.772204) (xy 244.489743 131.846476)
				(xy 244.480492 131.926762) (xy 244.48 131.929474) (xy 244.800707 131.874707) (xy 244.880474 131.579)
				(xy 244.794034 131.582538) (xy 244.714401 131.576454) (xy 244.641862 131.561419) (xy 244.579048 131.538456)
				(xy 244.498944 131.484556)
			)
		)
	)
	(zone
		(net 534)
		(net_name "Net-(Q1-D)")
		(layer "F.Cu")
		(name "$teardrop_padvia$")
		(hatch none 0.1)
		(priority 30838)
		(attr
			(teardrop
				(type padvia)
			)
		)
		(connect_pads yes
			(clearance 0)
		)
		(min_thickness 0.0254)
		(filled_areas_thickness no)
		(fill yes
			(thermal_gap 0.5)
			(thermal_bridge_width 0.5)
			(island_removal_mode 1)
			(island_area_min 10)
		)
		(polygon
			(pts
				(xy 307.67 140.398) (xy 307.67621 140.351789) (xy 307.699677 140.30339) (xy 307.727584 140.275034)
				(xy 307.76781 140.251988) (xy 307.821798 140.236798) (xy 307.57 139.959) (xy 307.318202 140.236798)
				(xy 307.367054 140.249931) (xy 307.404564 140.269335) (xy 307.451987 140.321945) (xy 307.469743 140.388446)
				(xy 307.47 140.398)
			)
		)
	)
	(zone
		(net 2)
		(net_name "+3V3")
		(layer "F.Cu")
		(name "$teardrop_padvia$")
		(hatch none 0.1)
		(priority 30788)
		(attr
			(teardrop
				(type padvia)
			)
		)
		(connect_pads yes
			(clearance 0)
		)
		(min_thickness 0.0254)
		(filled_areas_thickness no)
		(fill yes
			(thermal_gap 0.5)
			(thermal_bridge_width 0.5)
			(island_removal_mode 1)
			(island_area_min 10)
		)
		(polygon
			(pts
				(xy 262.400676 93.187) (xy 262.243105 93.180069) (xy 262.129577 93.151549) (xy 262.087777 93.1345)
				(xy 261.998999 93.337) (xy 262.087777 93.5395) (xy 262.183816 93.505118) (xy 262.285688 93.4899)
				(xy 262.400676 93.487)
			)
		)
	)
	(zone
		(net 1)
		(net_name "GND")
		(layer "F.Cu")
		(name "$teardrop_padvia$")
		(hatch none 0.1)
		(priority 30793)
		(attr
			(teardrop
				(type padvia)
			)
		)
		(connect_pads yes
			(clearance 0)
		)
		(min_thickness 0.0254)
		(filled_areas_thickness no)
		(fill yes
			(thermal_gap 0.5)
			(thermal_bridge_width 0.5)
			(island_removal_mode 1)
			(island_area_min 10)
		)
		(polygon
			(pts
				(xy 152.969177 72.4095) (xy 152.811606 72.402569) (xy 152.698078 72.374049) (xy 152.656278 72.357)
				(xy 152.5675 72.5595) (xy 152.656278 72.762) (xy 152.752317 72.727618) (xy 152.854189 72.7124) (xy 152.969177 72.7095)
			)
		)
	)
	(zone
		(net 1)
		(net_name "GND")
		(layer "F.Cu")
		(name "$teardrop_padvia$")
		(hatch none 0.1)
		(priority 30327)
		(attr
			(teardrop
				(type padvia)
			)
		)
		(connect_pads yes
			(clearance 0)
		)
		(min_thickness 0.0254)
		(filled_areas_thickness no)
		(fill yes
			(thermal_gap 0.5)
			(thermal_bridge_width 0.5)
			(island_removal_mode 1)
			(island_area_min 10)
		)
		(polygon
			(pts
				(xy 242.927 127.32) (xy 242.931984 127.349145) (xy 242.937907 127.379666) (xy 242.936086 127.410446)
				(xy 242.917736 127.437348) (xy 242.874073 127.456234) (xy 243.075 127.961) (xy 243.279061 127.460926)
				(xy 243.24528 127.447631) (xy 243.225503 127.429808) (xy 243.215314 127.387831) (xy 243.221903 127.350108)
				(xy 243.227 127.32)
			)
		)
	)
	(zone
		(net 1)
		(net_name "GND")
		(layer "F.Cu")
		(name "$teardrop_padvia$")
		(hatch none 0.1)
		(priority 31232)
		(attr
			(teardrop
				(type padvia)
			)
		)
		(connect_pads yes
			(clearance 0)
		)
		(min_thickness 0.0254)
		(filled_areas_thickness no)
		(fill yes
			(thermal_gap 0.5)
			(thermal_bridge_width 0.5)
			(island_removal_mode 1)
			(island_area_min 10)
		)
		(polygon
			(pts
				(xy 213.625 155.900677) (xy 213.629737 155.809676) (xy 213.642896 155.742587) (xy 213.675418 155.655855)
				(xy 213.707644 155.575358) (xy 213.5 155.499) (xy 213.303541 155.602363) (xy 213.355343 155.685863)
				(xy 213.404833 155.771955) (xy 213.419614 155.82716) (xy 213.425 155.900677)
			)
		)
	)
	(zone
		(net 294)
		(net_name "/2xUSB3.0+RJ45/GbE.MDI0-")
		(layer "F.Cu")
		(name "$teardrop_padvia$")
		(hatch none 0.1)
		(priority 31653)
		(attr
			(teardrop
				(type padvia)
			)
		)
		(connect_pads yes
			(clearance 0)
		)
		(min_thickness 0.0254)
		(filled_areas_thickness no)
		(fill yes
			(thermal_gap 0.5)
			(thermal_bridge_width 0.5)
			(island_removal_mode 1)
			(island_area_min 10)
		)
		(polygon
			(pts
				(xy 164.3 149.457916) (xy 164.302203 149.6633) (xy 164.304323 149.801757) (xy 164.525 149.801) (xy 164.650003 149.612919)
				(xy 164.573862 149.579004) (xy 164.557261 149.573949) (xy 164.515719 149.560156) (xy 164.481601 149.540737)
				(xy 164.458499 149.508917) (xy 164.45 149.457916)
			)
		)
	)
	(zone
		(net 755)
		(net_name "Net-(U45A-LS_OK_{IN_A})")
		(layer "F.Cu")
		(name "$teardrop_padvia$")
		(hatch none 0.1)
		(priority 31731)
		(attr
			(teardrop
				(type padvia)
			)
		)
		(connect_pads yes
			(clearance 0)
		)
		(min_thickness 0.0254)
		(filled_areas_thickness no)
		(fill yes
			(thermal_gap 0.5)
			(thermal_bridge_width 0.5)
			(island_removal_mode 1)
			(island_area_min 10)
		)
		(polygon
			(pts
				(xy 137.4775 129.739323) (xy 137.472682 129.808763) (xy 137.45896 129.860087) (xy 137.412245 129.935628)
				(xy 137.402702 129.947768) (xy 137.352919 130.014997) (xy 137.54 130.141) (xy 137.727081 130.014997)
				(xy 137.677299 129.947769) (xy 137.622894 129.864603) (xy 137.60781 129.811748) (xy 137.6025 129.739323)
			)
		)
	)
	(zone
		(net 642)
		(net_name "Net-(U41-IO0_3)")
		(layer "F.Cu")
		(name "$teardrop_padvia$")
		(hatch none 0.1)
		(priority 31081)
		(attr
			(teardrop
				(type padvia)
			)
		)
		(connect_pads yes
			(clearance 0)
		)
		(min_thickness 0.0254)
		(filled_areas_thickness no)
		(fill yes
			(thermal_gap 0.5)
			(thermal_bridge_width 0.5)
			(island_removal_mode 1)
			(island_area_min 10)
		)
		(polygon
			(pts
				(xy 127.318 85.997501) (xy 127.258588 85.977728) (xy 127.202503 85.914454) (xy 127.180801 85.865829)
				(xy 127.166127 85.806469) (xy 127.164347 85.794501) (xy 126.904 86.060001) (xy 127.164347 86.325501)
				(xy 127.177197 86.265362) (xy 127.197131 86.215478) (xy 127.223056 86.175359) (xy 127.252876 86.146346)
				(xy 127.284294 86.128855) (xy 127.316105 86.122522) (xy 127.318 86.122501)
			)
		)
	)
	(zone
		(net 610)
		(net_name "Net-(Y1-EN)")
		(layer "F.Cu")
		(name "$teardrop_padvia$")
		(hatch none 0.1)
		(priority 30170)
		(attr
			(teardrop
				(type padvia)
			)
		)
		(connect_pads yes
			(clearance 0)
		)
		(min_thickness 0.0254)
		(filled_areas_thickness no)
		(fill yes
			(thermal_gap 0.5)
			(thermal_bridge_width 0.5)
			(island_removal_mode 1)
			(island_area_min 10)
		)
		(polygon
			(pts
				(xy 307.5599 76.83568) (xy 307.503672 76.91174) (xy 307.423121 76.989736) (xy 307.364717 77.028454)
				(xy 307.298824 77.056366) (xy 307.244338 77.067684) (xy 307.549293 77.483707) (xy 307.891421 77.091579)
				(xy 307.789749 77.069169) (xy 307.725817 77.043732) (xy 307.701463 77.023871) (xy 307.693173 77.002532)
				(xy 307.701322 76.977102)
			)
		)
	)
	(zone
		(net 726)
		(net_name "/2xSFP+/KR to SFI #1/~{TRST}")
		(layer "F.Cu")
		(name "$teardrop_padvia$")
		(hatch none 0.1)
		(priority 30119)
		(attr
			(teardrop
				(type padvia)
			)
		)
		(connect_pads yes
			(clearance 0)
		)
		(min_thickness 0.0254)
		(filled_areas_thickness no)
		(fill yes
			(thermal_gap 0.5)
			(thermal_bridge_width 0.5)
			(island_removal_mode 1)
			(island_area_min 10)
		)
		(polygon
			(pts
				(xy 151.2125 130.227794) (xy 151.217315 130.145733) (xy 151.231019 130.080388) (xy 151.277576 129.98712)
				(xy 151.345787 129.908657) (xy 151.401942 129.847158) (xy 151.461801 129.768339) (xy 151.15 129.559)
				(xy 150.838199 129.768339) (xy 150.935219 129.888517) (xy 150.954214 129.908658) (xy 151.007366 129.967541)
				(xy 151.049591 130.031624) (xy 151.077449 130.114008) (xy 151.0875 130.227794)
			)
		)
	)
	(zone
		(net 325)
		(net_name "/Com Express 7 Interfaces/PCIe_{B2Ax4}.TX0-")
		(layer "F.Cu")
		(name "$teardrop_padvia$")
		(hatch none 0.1)
		(priority 31444)
		(attr
			(teardrop
				(type padvia)
			)
		)
		(connect_pads yes
			(clearance 0)
		)
		(min_thickness 0.0254)
		(filled_areas_thickness no)
		(fill yes
			(thermal_gap 0.5)
			(thermal_bridge_width 0.5)
			(island_removal_mode 1)
			(island_area_min 10)
		)
		(polygon
			(pts
				(xy 228.5955 143.763584) (xy 228.600235 143.717781) (xy 228.613381 143.6832) (xy 228.658329 143.63671)
				(xy 228.697581 143.613183) (xy 228.741576 143.586771) (xy 228.784165 143.550918) (xy 228.623 143.399)
				(xy 228.402323 143.415931) (xy 228.400471 143.59335) (xy 228.3935 143.763584)
			)
		)
	)
	(zone
		(net 197)
		(net_name "/OCuLink/PCIe_{x4}.RX3-")
		(layer "F.Cu")
		(name "$teardrop_padvia$")
		(hatch none 0.1)
		(priority 32084)
		(attr
			(teardrop
				(type padvia)
			)
		)
		(connect_pads yes
			(clearance 0)
		)
		(min_thickness 0.0254)
		(filled_areas_thickness no)
		(fill yes
			(thermal_gap 0.5)
			(thermal_bridge_width 0.5)
			(island_removal_mode 1)
			(island_area_min 10)
		)
		(polygon
			(pts
				(xy 106.501 152.26) (xy 106.508198 152.280648) (xy 106.517792 152.312984) (xy 106.510965 152.327007)
				(xy 106.4895 152.336995) (xy 106.602 152.586) (xy 106.7145 152.336995) (xy 106.693324 152.327271)
				(xy 106.686269 152.313643) (xy 106.695802 152.280648) (xy 106.703 152.26)
			)
		)
	)
	(zone
		(net 1)
		(net_name "GND")
		(layer "F.Cu")
		(name "$teardrop_padvia$")
		(hatch none 0.1)
		(priority 30574)
		(attr
			(teardrop
				(type padvia)
			)
		)
		(connect_pads yes
			(clearance 0)
		)
		(min_thickness 0.0254)
		(filled_areas_thickness no)
		(fill yes
			(thermal_gap 0.5)
			(thermal_bridge_width 0.5)
			(island_removal_mode 1)
			(island_area_min 10)
		)
		(polygon
			(pts
				(xy 184.625 157.62) (xy 184.621667 157.605514) (xy 184.61881 157.57539) (xy 184.630964 157.564349)
				(xy 184.66 157.56) (xy 184.525 156.684) (xy 184.39 157.56) (xy 184.419334 157.564475) (xy 184.431358 157.575801)
				(xy 184.428333 157.605514) (xy 184.425 157.62)
			)
		)
	)
	(zone
		(net 2)
		(net_name "+3V3")
		(layer "F.Cu")
		(name "$teardrop_padvia$")
		(hatch none 0.1)
		(priority 30222)
		(attr
			(teardrop
				(type padvia)
			)
		)
		(connect_pads yes
			(clearance 0)
		)
		(min_thickness 0.0254)
		(filled_areas_thickness no)
		(fill yes
			(thermal_gap 0.5)
			(thermal_bridge_width 0.5)
			(island_removal_mode 1)
			(island_area_min 10)
		)
		(polygon
			(pts
				(xy 121.188 74.943) (xy 121.19635 74.973608) (xy 121.206961 75.026593) (xy 121.193956 75.049725)
				(xy 121.158 75.066191) (xy 121.338 75.759) (xy 121.518 75.066191) (xy 121.488041 75.054257) (xy 121.472728 75.037936)
				(xy 121.470892 75.000262) (xy 121.47965 74.973608) (xy 121.488 74.943)
			)
		)
	)
	(zone
		(net 2)
		(net_name "+3V3")
		(layer "F.Cu")
		(name "$teardrop_padvia$")
		(hatch none 0.1)
		(priority 30235)
		(attr
			(teardrop
				(type padvia)
			)
		)
		(connect_pads yes
			(clearance 0)
		)
		(min_thickness 0.0254)
		(filled_areas_thickness no)
		(fill yes
			(thermal_gap 0.5)
			(thermal_bridge_width 0.5)
			(island_removal_mode 1)
			(island_area_min 10)
		)
		(polygon
			(pts
				(xy 263.010815 93.368316) (xy 263.030147 93.348499) (xy 263.081235 93.298257) (xy 263.145443 93.250809)
				(xy 263.227085 93.218081) (xy 263.330474 93.212) (xy 263.250707 92.916293) (xy 262.93 92.861526)
				(xy 262.93506 92.915253) (xy 262.930542 92.962707) (xy 262.897112 93.046203) (xy 262.83289 93.12297)
				(xy 262.816695 93.138657) (xy 262.798684 93.156185)
			)
		)
	)
	(zone
		(net 1)
		(net_name "GND")
		(layer "F.Cu")
		(name "$teardrop_padvia$")
		(hatch none 0.1)
		(priority 31788)
		(attr
			(teardrop
				(type padvia)
			)
		)
		(connect_pads yes
			(clearance 0)
		)
		(min_thickness 0.0254)
		(filled_areas_thickness no)
		(fill yes
			(thermal_gap 0.5)
			(thermal_bridge_width 0.5)
			(island_removal_mode 1)
			(island_area_min 10)
		)
		(polygon
			(pts
				(xy 306.7125 154.710677) (xy 306.717318 154.641236) (xy 306.73104 154.589912) (xy 306.777755 154.51437)
				(xy 306.787299 154.502229) (xy 306.837081 154.435003) (xy 306.65 154.309) (xy 306.462919 154.435003)
				(xy 306.512701 154.502231) (xy 306.567106 154.585397) (xy 306.58219 154.638251) (xy 306.5875 154.710677)
			)
		)
	)
	(zone
		(net 1)
		(net_name "GND")
		(layer "F.Cu")
		(name "$teardrop_padvia$")
		(hatch none 0.1)
		(priority 30577)
		(attr
			(teardrop
				(type padvia)
			)
		)
		(connect_pads yes
			(clearance 0)
		)
		(min_thickness 0.0254)
		(filled_areas_thickness no)
		(fill yes
			(thermal_gap 0.5)
			(thermal_bridge_width 0.5)
			(island_removal_mode 1)
			(island_area_min 10)
		)
		(polygon
			(pts
				(xy 217.425 150.2) (xy 217.428333 150.214486) (xy 217.43119 150.24461) (xy 217.419036 150.255651)
				(xy 217.39 150.26) (xy 217.525 151.136) (xy 217.66 150.26) (xy 217.630666 150.255525) (xy 217.618642 150.244199)
				(xy 217.621667 150.214486) (xy 217.625 150.2)
			)
		)
	)
	(zone
		(net 345)
		(net_name "/Com Express 7 MGMT/SER0.RX")
		(layer "F.Cu")
		(name "$teardrop_padvia$")
		(hatch none 0.1)
		(priority 31862)
		(attr
			(teardrop
				(type padvia)
			)
		)
		(connect_pads yes
			(clearance 0)
		)
		(min_thickness 0.0254)
		(filled_areas_thickness no)
		(fill yes
			(thermal_gap 0.5)
			(thermal_bridge_width 0.5)
			(island_removal_mode 1)
			(island_area_min 10)
		)
		(polygon
			(pts
				(xy 225.022485 170.060873) (xy 225.068181 170.113382) (xy 225.094768 170.159376) (xy 225.115152 170.245825)
				(xy 225.116988 170.261158) (xy 225.129323 170.343895) (xy 225.350707 170.300707) (xy 225.393895 170.079323)
				(xy 225.311158 170.066988) (xy 225.21388 170.046651) (xy 225.16584 170.019943) (xy 225.110873 169.972485)
			)
		)
	)
	(zone
		(net 14)
		(net_name "/Com Express 7 Interfaces/PCIe_{B1x2}.RX0+")
		(layer "F.Cu")
		(name "$teardrop_padvia$")
		(hatch none 0.1)
		(priority 31441)
		(attr
			(teardrop
				(type padvia)
			)
		)
		(connect_pads yes
			(clearance 0)
		)
		(min_thickness 0.0254)
		(filled_areas_thickness no)
		(fill yes
			(thermal_gap 0.5)
			(thermal_bridge_width 0.5)
			(island_removal_mode 1)
			(island_area_min 10)
		)
		(polygon
			(pts
				(xy 205.7045 131.036416) (xy 205.699765 131.082219) (xy 205.686619 131.116799) (xy 205.641671 131.163288)
				(xy 205.602419 131.186815) (xy 205.558424 131.213227) (xy 205.515834 131.249081) (xy 205.677 131.401)
				(xy 205.897677 131.384068) (xy 205.899528 131.206646) (xy 205.9065 131.036416)
			)
		)
	)
	(zone
		(net 2)
		(net_name "+3V3")
		(layer "F.Cu")
		(name "$teardrop_padvia$")
		(hatch none 0.1)
		(priority 30922)
		(attr
			(teardrop
				(type padvia)
			)
		)
		(connect_pads yes
			(clearance 0)
		)
		(min_thickness 0.0254)
		(filled_areas_thickness no)
		(fill yes
			(thermal_gap 0.5)
			(thermal_bridge_width 0.5)
			(island_removal_mode 1)
			(island_area_min 10)
		)
		(polygon
			(pts
				(xy 220.2725 125.338) (xy 220.292469 125.275134) (xy 220.318921 125.243156) (xy 220.356332 125.214642)
				(xy 220.403527 125.192118) (xy 220.461167 125.176907) (xy 220.461798 125.176798) (xy 220.21 124.899)
				(xy 219.958202 125.176798) (xy 220.013635 125.191095) (xy 220.05952 125.212175) (xy 220.097201 125.23954)
				(xy 220.124434 125.270448) (xy 220.141472 125.303735) (xy 220.147489 125.336566) (xy 220.1475 125.338)
			)
		)
	)
	(zone
		(net 1)
		(net_name "GND")
		(layer "F.Cu")
		(hatch edge 0.5)
		(priority 45)
		(connect_pads yes
			(clearance 0.15)
		)
		(min_thickness 0.25)
		(filled_areas_thickness no)
		(fill yes
			(thermal_gap 0.5)
			(thermal_bridge_width 0.5)
		)
		(polygon
			(pts
				(xy 310.76 119.61) (xy 312.36 119.61) (xy 312.36 121.51) (xy 310.76 121.51)
			)
		)
	)
	(zone
		(net 2)
		(net_name "+3V3")
		(layer "F.Cu")
		(name "$teardrop_padvia$")
		(hatch none 0.1)
		(priority 30396)
		(attr
			(teardrop
				(type padvia)
			)
		)
		(connect_pads yes
			(clearance 0)
		)
		(min_thickness 0.0254)
		(filled_areas_thickness no)
		(fill yes
			(thermal_gap 0.5)
			(thermal_bridge_width 0.5)
			(island_removal_mode 1)
			(island_area_min 10)
		)
		(polygon
			(pts
				(xy 193.027585 139.269916) (xy 192.981589 139.252774) (xy 192.944562 139.242359) (xy 192.915544 139.225466)
				(xy 192.906626 139.196609) (xy 192.929896 139.150305) (xy 192.558066 139.15395) (xy 192.554422 139.525779)
				(xy 192.588301 139.505787) (xy 192.613172 139.502706) (xy 192.639561 139.52486) (xy 192.65689 139.577472)
				(xy 192.674032 139.623468)
			)
		)
	)
	(zone
		(net 979)
		(net_name "Net-(D26-C)")
		(layer "F.Cu")
		(name "$teardrop_padvia$")
		(hatch none 0.1)
		(priority 30152)
		(attr
			(teardrop
				(type padvia)
			)
		)
		(connect_pads yes
			(clearance 0)
		)
		(min_thickness 0.0254)
		(filled_areas_thickness no)
		(fill yes
			(thermal_gap 0.5)
			(thermal_bridge_width 0.5)
			(island_removal_mode 1)
			(island_area_min 10)
		)
		(polygon
			(pts
				(xy 201.80861 76.062163) (xy 201.81367 76.028644) (xy 201.829091 75.995738) (xy 201.854873 75.965425)
				(xy 201.891483 75.938919) (xy 201.938658 75.918016) (xy 201.997093 75.90393) (xy 202.06861 75.898184)
				(xy 201.70861 75.501163) (xy 201.34861 75.898184) (xy 201.418681 75.903704) (xy 201.477217 75.917567)
				(xy 201.524564 75.938253) (xy 201.561037 75.964231) (xy 201.58712 75.9942) (xy 201.602852 76.026426)
				(xy 201.60861 76.062163)
			)
		)
	)
	(zone
		(net 117)
		(net_name "/2xSFP+/KR to SFI #2/CLK-")
		(layer "F.Cu")
		(name "$teardrop_padvia$")
		(hatch none 0.1)
		(priority 30633)
		(attr
			(teardrop
				(type padvia)
			)
		)
		(connect_pads yes
			(clearance 0)
		)
		(min_thickness 0.0254)
		(filled_areas_thickness no)
		(fill yes
			(thermal_gap 0.5)
			(thermal_bridge_width 0.5)
			(island_removal_mode 1)
			(island_area_min 10)
		)
		(polygon
			(pts
				(xy 123.996343 141.25) (xy 124.113255 141.194698) (xy 124.188837 141.175971) (xy 124.270757 141.167603)
				(xy 124.394492 141.18) (xy 124.361 140.86) (xy 124.065 140.76316) (xy 124.068301 140.900081) (xy 124.05378 141.003261)
				(xy 124.03574 141.046666) (xy 124.009365 141.079712) (xy 123.996343 141.09)
			)
		)
	)
	(zone
		(net 113)
		(net_name "/2xSFP+/10GKR_SFP0.TX-")
		(layer "F.Cu")
		(name "$teardrop_padvia$")
		(hatch none 0.1)
		(priority 30906)
		(attr
			(teardrop
				(type padvia)
			)
		)
		(connect_pads yes
			(clearance 0)
		)
		(min_thickness 0.0254)
		(filled_areas_thickness no)
		(fill yes
			(thermal_gap 0.5)
			(thermal_bridge_width 0.5)
			(island_removal_mode 1)
			(island_area_min 10)
		)
		(polygon
			(pts
				(xy 200.545 152.07) (xy 200.544745 152.062548) (xy 200.550791 152.028161) (xy 200.568548 152.015168)
				(xy 200.604123 152.01) (xy 200.525 151.134) (xy 200.375 152.01) (xy 200.392936 152.014466) (xy 200.397965 152.025729)
				(xy 200.390417 152.052612) (xy 200.385 152.07)
			)
		)
	)
	(zone
		(net 1)
		(net_name "GND")
		(layer "F.Cu")
		(name "$teardrop_padvia$")
		(hatch none 0.1)
		(priority 31234)
		(attr
			(teardrop
				(type padvia)
			)
		)
		(connect_pads yes
			(clearance 0)
		)
		(min_thickness 0.0254)
		(filled_areas_thickness no)
		(fill yes
			(thermal_gap 0.5)
			(thermal_bridge_width 0.5)
			(island_removal_mode 1)
			(island_area_min 10)
		)
		(polygon
			(pts
				(xy 212.125 161.850677) (xy 212.129737 161.759676) (xy 212.142896 161.692587) (xy 212.175418 161.605855)
				(xy 212.207644 161.525358) (xy 212 161.449) (xy 211.803541 161.552363) (xy 211.855343 161.635863)
				(xy 211.904833 161.721955) (xy 211.919614 161.77716) (xy 211.925 161.850677)
			)
		)
	)
	(zone
		(net 11)
		(net_name "/Com Express 7 Interfaces/PCIe_{B1x2}.TX0-")
		(layer "F.Cu")
		(name "$teardrop_padvia$")
		(hatch none 0.1)
		(priority 30277)
		(attr
			(teardrop
				(type padvia)
			)
		)
		(connect_pads yes
			(clearance 0)
		)
		(min_thickness 0.0254)
		(filled_areas_thickness no)
		(fill yes
			(thermal_gap 0.5)
			(thermal_bridge_width 0.5)
			(island_removal_mode 1)
			(island_area_min 10)
		)
		(polygon
			(pts
				(xy 203.3685 167.75) (xy 203.379599 167.923112) (xy 203.394216 168.15051) (xy 203.391181 168.285138)
				(xy 203.375 168.437021) (xy 203.525 168.686) (xy 203.608295 167.81) (xy 203.577864 167.805523) (xy 203.565097 167.794185)
				(xy 203.56742 167.764227) (xy 203.5705 167.75)
			)
		)
	)
	(zone
		(net 56)
		(net_name "/USB-C console/USB_D-")
		(layer "F.Cu")
		(name "$teardrop_padvia$")
		(hatch none 0.1)
		(priority 30446)
		(attr
			(teardrop
				(type padvia)
			)
		)
		(connect_pads yes
			(clearance 0)
		)
		(min_thickness 0.0254)
		(filled_areas_thickness no)
		(fill yes
			(thermal_gap 0.5)
			(thermal_bridge_width 0.5)
			(island_removal_mode 1)
			(island_area_min 10)
		)
		(polygon
			(pts
				(xy 110.367146 76.108501) (xy 110.393775 76.127156) (xy 110.413671 76.153611) (xy 110.436054 76.23466)
				(xy 110.431998 76.421732) (xy 110.727998 76.326) (xy 110.76294 76.006) (xy 110.644881 76.011134)
				(xy 110.509666 75.98243) (xy 110.367146 75.923501)
			)
		)
	)
	(zone
		(net 372)
		(net_name "/Com Express 7 MGMT/I2C.SDA")
		(layer "F.Cu")
		(name "$teardrop_padvia$")
		(hatch none 0.1)
		(priority 31833)
		(attr
			(teardrop
				(type padvia)
			)
		)
		(connect_pads yes
			(clearance 0)
		)
		(min_thickness 0.0254)
		(filled_areas_thickness no)
		(fill yes
			(thermal_gap 0.5)
			(thermal_bridge_width 0.5)
			(island_removal_mode 1)
			(island_area_min 10)
		)
		(polygon
			(pts
				(xy 259.050677 89.477499) (xy 258.981236 89.472681) (xy 258.929913 89.458959) (xy 258.854371 89.412245)
				(xy 258.842231 89.4027) (xy 258.775003 89.352918) (xy 258.649 89.539999) (xy 258.775003 89.72708)
				(xy 258.842229 89.677298) (xy 258.925396 89.622893) (xy 258.978251 89.607809) (xy 259.050677 89.602499)
			)
		)
	)
	(zone
		(net 1)
		(net_name "GND")
		(layer "F.Cu")
		(name "$teardrop_padvia$")
		(hatch none 0.1)
		(priority 31190)
		(attr
			(teardrop
				(type padvia)
			)
		)
		(connect_pads yes
			(clearance 0)
		)
		(min_thickness 0.0254)
		(filled_areas_thickness no)
		(fill yes
			(thermal_gap 0.5)
			(thermal_bridge_width 0.5)
			(island_removal_mode 1)
			(island_area_min 10)
		)
		(polygon
			(pts
				(xy 205.625 162.321677) (xy 205.62972 162.252353) (xy 205.642756 162.199449) (xy 205.694658 162.10686)
				(xy 205.746458 162.023363) (xy 205.55 161.92) (xy 205.342355 161.996358) (xy 205.374583 162.076861)
				(xy 205.410965 162.178318) (xy 205.425 162.321677)
			)
		)
	)
	(zone
		(net 188)
		(net_name "/OCuLink/PCIe_{x4}.RX1+")
		(layer "F.Cu")
		(name "$teardrop_padvia$")
		(hatch none 0.1)
		(priority 31406)
		(attr
			(teardrop
				(type padvia)
			)
		)
		(connect_pads yes
			(clearance 0)
		)
		(min_thickness 0.0254)
		(filled_areas_thickness no)
		(fill yes
			(thermal_gap 0.5)
			(thermal_bridge_width 0.5)
			(island_removal_mode 1)
			(island_area_min 10)
		)
		(polygon
			(pts
				(xy 99.232504 149.2065) (xy 99.394035 149.201105) (xy 99.478445 149.197554) (xy 99.58014 149.202177)
				(xy 99.601 148.9815) (xy 99.451147 148.818268) (xy 99.397007 148.886935) (xy 99.387115 148.903393)
				(xy 99.362615 148.942065) (xy 99.333109 148.974279) (xy 99.291953 148.996327) (xy 99.232504 149.0045)
			)
		)
	)
	(zone
		(net 133)
		(net_name "Net-(D18-C_{G})")
		(layer "F.Cu")
		(name "$teardrop_padvia$")
		(hatch none 0.1)
		(priority 31793)
		(attr
			(teardrop
				(type padvia)
			)
		)
		(connect_pads yes
			(clearance 0)
		)
		(min_thickness 0.0254)
		(filled_areas_thickness no)
		(fill yes
			(thermal_gap 0.5)
			(thermal_bridge_width 0.5)
			(island_removal_mode 1)
			(island_area_min 10)
		)
		(polygon
			(pts
				(xy 100.180677 74.7475) (xy 100.111236 74.742682) (xy 100.059913 74.72896) (xy 99.984371 74.682246)
				(xy 99.972231 74.672701) (xy 99.905003 74.622919) (xy 99.779 74.81) (xy 99.905003 74.997081) (xy 99.972229 74.947299)
				(xy 100.055396 74.892894) (xy 100.108251 74.87781) (xy 100.180677 74.8725)
			)
		)
	)
	(zone
		(net 895)
		(net_name "Net-(J2B-RS0)")
		(layer "F.Cu")
		(name "$teardrop_padvia$")
		(hatch none 0.1)
		(priority 31856)
		(attr
			(teardrop
				(type padvia)
			)
		)
		(connect_pads yes
			(clearance 0)
		)
		(min_thickness 0.0254)
		(filled_areas_thickness no)
		(fill yes
			(thermal_gap 0.5)
			(thermal_bridge_width 0.5)
			(island_removal_mode 1)
			(island_area_min 10)
		)
		(polygon
			(pts
				(xy 139.289127 166.682485) (xy 139.236618 166.728181) (xy 139.190623 166.754768) (xy 139.104174 166.775152)
				(xy 139.088841 166.776988) (xy 139.006105 166.789323) (xy 139.049293 167.010707) (xy 139.270677 167.053895)
				(xy 139.283011 166.97116) (xy 139.303349 166.873881) (xy 139.330057 166.825841) (xy 139.377515 166.770873)
			)
		)
	)
	(zone
		(net 222)
		(net_name "/Com Express 7 Interfaces/PCIe_{B1x4}.RX0+")
		(layer "F.Cu")
		(name "$teardrop_padvia$")
		(hatch none 0.1)
		(priority 31393)
		(attr
			(teardrop
				(type padvia)
			)
		)
		(connect_pads yes
			(clearance 0)
		)
		(min_thickness 0.0254)
		(filled_areas_thickness no)
		(fill yes
			(thermal_gap 0.5)
			(thermal_bridge_width 0.5)
			(island_removal_mode 1)
			(island_area_min 10)
		)
		(polygon
			(pts
				(xy 209.6815 159.617496) (xy 209.676105 159.455964) (xy 209.672555 159.371553) (xy 209.677177 159.269859)
				(xy 209.4565 159.249) (xy 209.293268 159.398852) (xy 209.361936 159.452992) (xy 209.378392 159.462884)
				(xy 209.417064 159.487384) (xy 209.449279 159.51689) (xy 209.471327 159.558046) (xy 209.4795 159.617496)
			)
		)
	)
	(zone
		(net 93)
		(net_name "/Com Express 7 Interfaces/PCIe_{B2Ax4}.RX3+")
		(layer "F.Cu")
		(name "$teardrop_padvia$")
		(hatch none 0.1)
		(priority 30261)
		(attr
			(teardrop
				(type padvia)
			)
		)
		(connect_pads yes
			(clearance 0)
		)
		(min_thickness 0.0254)
		(filled_areas_thickness no)
		(fill yes
			(thermal_gap 0.5)
			(thermal_bridge_width 0.5)
			(island_removal_mode 1)
			(island_area_min 10)
		)
		(polygon
			(pts
				(xy 216.1815 164.07) (xy 216.170401 163.896888) (xy 216.155784 163.66949) (xy 216.158819 163.534862)
				(xy 216.175 163.382978) (xy 216.025 163.134) (xy 215.941705 164.01) (xy 215.972136 164.014477) (xy 215.984903 164.025815)
				(xy 215.98258 164.055773) (xy 215.9795 164.07)
			)
		)
	)
	(zone
		(net 531)
		(net_name "/Com Express 7 Interfaces/SD_CD")
		(layer "F.Cu")
		(name "$teardrop_padvia$")
		(hatch none 0.1)
		(priority 32095)
		(attr
			(teardrop
				(type padvia)
			)
		)
		(connect_pads yes
			(clearance 0)
		)
		(min_thickness 0.0254)
		(filled_areas_thickness no)
		(fill yes
			(thermal_gap 0.5)
			(thermal_bridge_width 0.5)
			(island_removal_mode 1)
			(island_area_min 10)
		)
		(polygon
			(pts
				(xy 112.21 131.51) (xy 112.230449 131.503088) (xy 112.262887 131.4939) (xy 112.276967 131.500902)
				(xy 112.286995 131.5225) (xy 112.536 131.41) (xy 112.286995 131.2975) (xy 112.277243 131.318793)
				(xy 112.263576 131.326027) (xy 112.230449 131.316912) (xy 112.21 131.31)
			)
		)
	)
	(zone
		(net 80)
		(net_name "Net-(Q6-D)")
		(layer "F.Cu")
		(name "$teardrop_padvia$")
		(hatch none 0.1)
		(priority 30832)
		(attr
			(teardrop
				(type padvia)
			)
		)
		(connect_pads yes
			(clearance 0)
		)
		(min_thickness 0.0254)
		(filled_areas_thickness no)
		(fill yes
			(thermal_gap 0.5)
			(thermal_bridge_width 0.5)
			(island_removal_mode 1)
			(island_area_min 10)
		)
		(polygon
			(pts
				(xy 262.078793 87.376662) (xy 262.013644 87.366728) (xy 261.937388 87.345104) (xy 261.866382 87.30572)
				(xy 261.83796 87.277471) (xy 261.816985 87.242504) (xy 261.807484 87.211977) (xy 261.539293 87.469292)
				(xy 261.816798 87.721797) (xy 261.826725 87.660309) (xy 261.840006 87.597783) (xy 261.849932 87.589028)
				(xy 261.866662 87.588793)
			)
		)
	)
	(zone
		(net 1)
		(net_name "GND")
		(layer "F.Cu")
		(name "$teardrop_padvia$")
		(hatch none 0.1)
		(priority 30802)
		(attr
			(teardrop
				(type padvia)
			)
		)
		(connect_pads yes
			(clearance 0)
		)
		(min_thickness 0.0254)
		(filled_areas_thickness no)
		(fill yes
			(thermal_gap 0.5)
			(thermal_bridge_width 0.5)
			(island_removal_mode 1)
			(island_area_min 10)
		)
		(polygon
			(pts
				(xy 120.677255 73.700613) (xy 120.560933 73.807131) (xy 120.460488 73.867242) (xy 120.418879 73.884742)
				(xy 120.499293 74.090707) (xy 120.705257 74.17112) (xy 120.748854 74.078899) (xy 120.810126 73.996107)
				(xy 120.889387 73.912745)
			)
		)
	)
	(zone
		(net 2)
		(net_name "+3V3")
		(layer "F.Cu")
		(name "$teardrop_padvia$")
		(hatch none 0.1)
		(priority 30223)
		(attr
			(teardrop
				(type padvia)
			)
		)
		(connect_pads yes
			(clearance 0)
		)
		(min_thickness 0.0254)
		(filled_areas_thickness no)
		(fill yes
			(thermal_gap 0.5)
			(thermal_bridge_width 0.5)
			(island_removal_mode 1)
			(island_area_min 10)
		)
		(polygon
			(pts
				(xy 143.04 150.594) (xy 143.04835 150.624608) (xy 143.058961 150.677593) (xy 143.045956 150.700725)
				(xy 143.01 150.717191) (xy 143.19 151.41) (xy 143.37 150.717191) (xy 143.340041 150.705257) (xy 143.324728 150.688936)
				(xy 143.322892 150.651262) (xy 143.33165 150.624608) (xy 143.34 150.594)
			)
		)
	)
	(zone
		(net 1)
		(net_name "GND")
		(layer "F.Cu")
		(name "$teardrop_padvia$")
		(hatch none 0.1)
		(priority 30500)
		(attr
			(teardrop
				(type padvia)
			)
		)
		(connect_pads yes
			(clearance 0)
		)
		(min_thickness 0.0254)
		(filled_areas_thickness no)
		(fill yes
			(thermal_gap 0.5)
			(thermal_bridge_width 0.5)
			(island_removal_mode 1)
			(island_area_min 10)
		)
		(polygon
			(pts
				(xy 121.010556 147.539944) (xy 121.060409 147.617761) (xy 121.088529 147.739204) (xy 121.089743 147.813476)
				(xy 121.080492 147.893762) (xy 121.08 147.896474) (xy 121.400707 147.841707) (xy 121.480474 147.546)
				(xy 121.394034 147.549538) (xy 121.314401 147.543454) (xy 121.241862 147.528419) (xy 121.179048 147.505456)
				(xy 121.098944 147.451556)
			)
		)
	)
	(zone
		(net 244)
		(net_name "/Com Express 7 Interfaces/PCIe_{B2Bx4}.RX2+")
		(layer "F.Cu")
		(name "$teardrop_padvia$")
		(hatch none 0.1)
		(priority 31438)
		(attr
			(teardrop
				(type padvia)
			)
		)
		(connect_pads yes
			(clearance 0)
		)
		(min_thickness 0.0254)
		(filled_areas_thickness no)
		(fill yes
			(thermal_gap 0.5)
			(thermal_bridge_width 0.5)
			(island_removal_mode 1)
			(island_area_min 10)
		)
		(polygon
			(pts
				(xy 186.436416 126.0955) (xy 186.482219 126.100235) (xy 186.5168 126.113381) (xy 186.563288 126.158329)
				(xy 186.586815 126.19758) (xy 186.613227 126.241575) (xy 186.649081 126.284165) (xy 186.801 126.123)
				(xy 186.784069 125.902323) (xy 186.606649 125.900471) (xy 186.436416 125.8935)
			)
		)
	)
	(zone
		(net 349)
		(net_name "Net-(J12D-LPC_AD0{slash}ESPI_IO_0)")
		(layer "F.Cu")
		(name "$teardrop_padvia$")
		(hatch none 0.1)
		(priority 31776)
		(attr
			(teardrop
				(type padvia)
			)
		)
		(connect_pads yes
			(clearance 0)
		)
		(min_thickness 0.0254)
		(filled_areas_thickness no)
		(fill yes
			(thermal_gap 0.5)
			(thermal_bridge_width 0.5)
			(island_removal_mode 1)
			(island_area_min 10)
		)
		(polygon
			(pts
				(xy 174.0625 164.250677) (xy 174.067318 164.181236) (xy 174.08104 164.129912) (xy 174.127755 164.05437)
				(xy 174.137299 164.042229) (xy 174.187081 163.975003) (xy 174 163.849) (xy 173.812919 163.975003)
				(xy 173.862701 164.042231) (xy 173.917106 164.125397) (xy 173.93219 164.178251) (xy 173.9375 164.250677)
			)
		)
	)
	(zone
		(net 1)
		(net_name "GND")
		(layer "F.Cu")
		(name "$teardrop_padvia$")
		(hatch none 0.1)
		(priority 31020)
		(attr
			(teardrop
				(type padvia)
			)
		)
		(connect_pads yes
			(clearance 0)
		)
		(min_thickness 0.0254)
		(filled_areas_thickness no)
		(fill yes
			(thermal_gap 0.5)
			(thermal_bridge_width 0.5)
			(island_removal_mode 1)
			(island_area_min 10)
		)
		(polygon
			(pts
				(xy 190.041119 137.991113) (xy 190.010787 137.93254) (xy 190.00688 137.891224) (xy 190.013171 137.844608)
				(xy 190.030616 137.795309) (xy 190.060618 137.743796) (xy 190.060987 137.743273) (xy 189.686506 137.724888)
				(xy 189.704891 138.099369) (xy 189.754197 138.070281) (xy 189.801548 138.052742) (xy 189.847543 138.045447)
				(xy 189.888655 138.048046) (xy 189.92424 138.059535) (xy 189.951709 138.078495) (xy 189.952731 138.079501)
			)
		)
	)
	(zone
		(net 742)
		(net_name "/2xSFP+/KR to SFI #2/TDI")
		(layer "F.Cu")
		(name "$teardrop_padvia$")
		(hatch none 0.1)
		(priority 30120)
		(attr
			(teardrop
				(type padvia)
			)
		)
		(connect_pads yes
			(clearance 0)
		)
		(min_thickness 0.0254)
		(filled_areas_thickness no)
		(fill yes
			(thermal_gap 0.5)
			(thermal_bridge_width 0.5)
			(island_removal_mode 1)
			(island_area_min 10)
		)
		(polygon
			(pts
				(xy 135.0025 129.377794) (xy 135.007315 129.295733) (xy 135.021019 129.230388) (xy 135.067576 129.13712)
				(xy 135.135787 129.058657) (xy 135.191942 128.997158) (xy 135.251801 128.918339) (xy 134.94 128.709)
				(xy 134.628199 128.918339) (xy 134.725219 129.038517) (xy 134.744214 129.058658) (xy 134.797366 129.117541)
				(xy 134.839591 129.181624) (xy 134.867449 129.264008) (xy 134.8775 129.377794)
			)
		)
	)
	(zone
		(net 1)
		(net_name "GND")
		(layer "F.Cu")
		(name "$teardrop_padvia$")
		(hatch none 0.1)
		(priority 30571)
		(attr
			(teardrop
				(type padvia)
			)
		)
		(connect_pads yes
			(clearance 0)
		)
		(min_thickness 0.0254)
		(filled_areas_thickness no)
		(fill yes
			(thermal_gap 0.5)
			(thermal_bridge_width 0.5)
			(island_removal_mode 1)
			(island_area_min 10)
		)
		(polygon
			(pts
				(xy 182.425 150.2) (xy 182.428333 150.214486) (xy 182.43119 150.24461) (xy 182.419036 150.255651)
				(xy 182.39 150.26) (xy 182.525 151.136) (xy 182.66 150.26) (xy 182.630666 150.255525) (xy 182.618642 150.244199)
				(xy 182.621667 150.214486) (xy 182.625 150.2)
			)
		)
	)
	(zone
		(net 206)
		(net_name "/Backplane/USB.D+")
		(layer "F.Cu")
		(name "$teardrop_padvia$")
		(hatch none 0.1)
		(priority 31502)
		(attr
			(teardrop
				(type padvia)
			)
		)
		(connect_pads yes
			(clearance 0)
		)
		(min_thickness 0.0254)
		(filled_areas_thickness no)
		(fill yes
			(thermal_gap 0.5)
			(thermal_bridge_width 0.5)
			(island_removal_mode 1)
			(island_area_min 10)
		)
		(polygon
			(pts
				(xy 198.3725 170.140416) (xy 198.376684 170.304858) (xy 198.376823 170.487562) (xy 198.5975 170.501)
				(xy 198.756688 170.347104) (xy 198.689162 170.298225) (xy 198.662819 170.284851) (xy 198.622556 170.263476)
				(xy 198.588998 170.236768) (xy 198.56602 170.197992) (xy 198.5575 170.140416)
			)
		)
	)
	(zone
		(net 782)
		(net_name "/Misc/PWM_{A3V3}")
		(layer "F.Cu")
		(name "$teardrop_padvia$")
		(hatch none 0.1)
		(priority 30743)
		(attr
			(teardrop
				(type padvia)
			)
		)
		(connect_pads yes
			(clearance 0)
		)
		(min_thickness 0.0254)
		(filled_areas_thickness no)
		(fill yes
			(thermal_gap 0.5)
			(thermal_bridge_width 0.5)
			(island_removal_mode 1)
			(island_area_min 10)
		)
		(polygon
			(pts
				(xy 258.060707 79.0225) (xy 258.004256 79.002455) (xy 257.977446 78.976276) (xy 257.954655 78.939267)
				(xy 257.928772 78.8375) (xy 257.549707 79.085) (xy 257.928772 79.3325) (xy 257.938581 79.275174)
				(xy 257.955735 79.228495) (xy 257.978881 79.191945) (xy 258.005972 79.166305) (xy 258.060707 79.1475)
			)
		)
	)
	(zone
		(net 1)
		(net_name "GND")
		(layer "F.Cu")
		(name "$teardrop_padvia$")
		(hatch none 0.1)
		(priority 31273)
		(attr
			(teardrop
				(type padvia)
			)
		)
		(connect_pads yes
			(clearance 0)
		)
		(min_thickness 0.0254)
		(filled_areas_thickness no)
		(fill yes
			(thermal_gap 0.5)
			(thermal_bridge_width 0.5)
			(island_removal_mode 1)
			(island_area_min 10)
		)
		(polygon
			(pts
				(xy 200.925 157.549323) (xy 200.920287 157.627234) (xy 200.9073 157.686018) (xy 200.865199 157.777048)
				(xy 200.8225 157.862221) (xy 201.025 157.951) (xy 201.2275 157.862221) (xy 201.184801 157.77705)
				(xy 201.142133 157.684217) (xy 201.129556 157.626078) (xy 201.125 157.549323)
			)
		)
	)
	(zone
		(net 2)
		(net_name "+3V3")
		(layer "F.Cu")
		(name "$teardrop_padvia$")
		(hatch none 0.1)
		(priority 30402)
		(attr
			(teardrop
				(type padvia)
			)
		)
		(connect_pads yes
			(clearance 0)
		)
		(min_thickness 0.0254)
		(filled_areas_thickness no)
		(fill yes
			(thermal_gap 0.5)
			(thermal_bridge_width 0.5)
			(island_removal_mode 1)
			(island_area_min 10)
		)
		(polygon
			(pts
				(xy 116.15 149.314) (xy 116.129597 149.269355) (xy 116.110779 149.235808) (xy 116.102205 149.203345)
				(xy 116.116303 149.176635) (xy 116.1655 149.160347) (xy 115.9 148.9) (xy 115.6345 149.160347) (xy 115.672593 149.170167)
				(xy 115.692358 149.185574) (xy 115.695352 149.2199) (xy 115.670403 149.269355) (xy 115.65 149.314)
			)
		)
	)
	(zone
		(net 136)
		(net_name "/Com Express 7 MGMT/~{TYPE0}")
		(layer "F.Cu")
		(name "$teardrop_padvia$")
		(hatch none 0.1)
		(priority 30697)
		(attr
			(teardrop
				(type padvia)
			)
		)
		(connect_pads yes
			(clearance 0)
		)
		(min_thickness 0.0254)
		(filled_areas_thickness no)
		(fill yes
			(thermal_gap 0.5)
			(thermal_bridge_width 0.5)
			(island_removal_mode 1)
			(island_area_min 10)
		)
		(polygon
			(pts
				(xy 202.4625 155.75) (xy 202.451563 155.788823) (xy 202.429805 155.803933) (xy 202.39 155.81) (xy 202.525 156.686)
				(xy 202.66 155.81) (xy 202.624719 155.805483) (xy 202.603203 155.793862) (xy 202.588005 155.761039)
				(xy 202.5875 155.75)
			)
		)
	)
	(zone
		(net 1)
		(net_name "GND")
		(layer "F.Cu")
		(name "$teardrop_padvia$")
		(hatch none 0.1)
		(priority 30798)
		(attr
			(teardrop
				(type padvia)
			)
		)
		(connect_pads yes
			(clearance 0)
		)
		(min_thickness 0.0254)
		(filled_areas_thickness no)
		(fill yes
			(thermal_gap 0.5)
			(thermal_bridge_width 0.5)
			(island_removal_mode 1)
			(island_area_min 10)
		)
		(polygon
			(pts
				(xy 309.107 155.359323) (xy 309.100069 155.516893) (xy 309.071549 155.630421) (xy 309.0545 155.672221)
				(xy 309.257 155.761) (xy 309.4595 155.672221) (xy 309.425117 155.576179) (xy 309.4099 155.474304)
				(xy 309.407 155.359323)
			)
		)
	)
	(zone
		(net 562)
		(net_name "/2xSFP+/~{LED0_0}")
		(layer "F.Cu")
		(name "$teardrop_padvia$")
		(hatch none 0.1)
		(priority 31053)
		(attr
			(teardrop
				(type padvia)
			)
		)
		(connect_pads yes
			(clearance 0)
		)
		(min_thickness 0.0254)
		(filled_areas_thickness no)
		(fill yes
			(thermal_gap 0.5)
			(thermal_bridge_width 0.5)
			(island_removal_mode 1)
			(island_area_min 10)
		)
		(polygon
			(pts
				(xy 156.192 158.0475) (xy 156.132588 158.027727) (xy 156.076503 157.964453) (xy 156.054801 157.915828)
				(xy 156.040127 157.856468) (xy 156.038347 157.8445) (xy 155.778 158.11) (xy 156.038347 158.3755)
				(xy 156.051197 158.315361) (xy 156.071131 158.265477) (xy 156.097056 158.225358) (xy 156.126876 158.196345)
				(xy 156.158294 158.178854) (xy 156.190105 158.172521) (xy 156.192 158.1725)
			)
		)
	)
	(zone
		(net 2)
		(net_name "+3V3")
		(layer "F.Cu")
		(name "$teardrop_padvia$")
		(hatch none 0.1)
		(priority 30301)
		(attr
			(teardrop
				(type padvia)
			)
		)
		(connect_pads yes
			(clearance 0)
		)
		(min_thickness 0.0254)
		(filled_areas_thickness no)
		(fill yes
			(thermal_gap 0.5)
			(thermal_bridge_width 0.5)
			(island_removal_mode 1)
			(island_area_min 10)
		)
		(polygon
			(pts
				(xy 245.429857 78.273) (xy 245.336792 78.288624) (xy 245.296535 78.299668) (xy 245.156016 78.331494)
				(xy 245.082548 78.33422) (xy 245.009234 78.32) (xy 244.999709 78.615) (xy 245.320709 78.762466)
				(xy 245.323498 78.689188) (xy 245.335044 78.637488) (xy 245.351197 78.606571) (xy 245.371454 78.58731)
				(xy 245.421317 78.573178) (xy 245.429857 78.573)
			)
		)
	)
	(zone
		(net 538)
		(net_name "Net-(Q5-D)")
		(layer "F.Cu")
		(name "$teardrop_padvia$")
		(hatch none 0.1)
		(priority 31218)
		(attr
			(teardrop
				(type padvia)
			)
		)
		(connect_pads yes
			(clearance 0)
		)
		(min_thickness 0.0254)
		(filled_areas_thickness no)
		(fill yes
			(thermal_gap 0.5)
			(thermal_bridge_width 0.5)
			(island_removal_mode 1)
			(island_area_min 10)
		)
		(polygon
			(pts
				(xy 260.820149 93.945537) (xy 260.816401 93.969173) (xy 260.803122 93.990132) (xy 260.743522 94.027604)
				(xy 260.618202 94.060202) (xy 260.870707 94.337707) (xy 261.121798 94.060202) (xy 261.030117 94.0264)
				(xy 260.954407 93.961216) (xy 260.927323 93.920113) (xy 260.911821 93.879447) (xy 260.908537 93.857149)
			)
		)
	)
	(zone
		(net 556)
		(net_name "/2xUSB3.0+RJ45/EN_2B")
		(layer "F.Cu")
		(name "$teardrop_padvia$")
		(hatch none 0.1)
		(priority 31033)
		(attr
			(teardrop
				(type padvia)
			)
		)
		(connect_pads yes
			(clearance 0)
		)
		(min_thickness 0.0254)
		(filled_areas_thickness no)
		(fill yes
			(thermal_gap 0.5)
			(thermal_bridge_width 0.5)
			(island_removal_mode 1)
			(island_area_min 10)
		)
		(polygon
			(pts
				(xy 121.632499 90.397999) (xy 121.652468 90.335134) (xy 121.67892 90.303156) (xy 121.716331 90.274642)
				(xy 121.763526 90.252118) (xy 121.821166 90.236907) (xy 121.821798 90.236798) (xy 121.57 89.959001)
				(xy 121.318202 90.236798) (xy 121.373635 90.251095) (xy 121.41952 90.272175) (xy 121.457201 90.29954)
				(xy 121.484434 90.330448) (xy 121.501472 90.363735) (xy 121.507489 90.396566) (xy 121.5075 90.398)
			)
		)
	)
	(zone
		(net 1)
		(net_name "GND")
		(layer "F.Cu")
		(name "$teardrop_padvia$")
		(hatch none 0.1)
		(priority 30803)
		(attr
			(teardrop
				(type padvia)
			)
		)
		(connect_pads yes
			(clearance 0)
		)
		(min_thickness 0.0254)
		(filled_areas_thickness no)
		(fill yes
			(thermal_gap 0.5)
			(thermal_bridge_width 0.5)
			(island_removal_mode 1)
			(island_area_min 10)
		)
		(polygon
			(pts
				(xy 220.210613 160.322745) (xy 220.317133 160.439068) (xy 220.377244 160.539517) (xy 220.394742 160.58112)
				(xy 220.600707 160.500707) (xy 220.68112 160.294742) (xy 220.588895 160.251142) (xy 220.506097 160.189865)
				(xy 220.422745 160.110613)
			)
		)
	)
	(zone
		(net 1)
		(net_name "GND")
		(layer "F.Cu")
		(name "$teardrop_padvia$")
		(hatch none 0.1)
		(priority 31924)
		(attr
			(teardrop
				(type padvia)
			)
		)
		(connect_pads yes
			(clearance 0)
		)
		(min_thickness 0.0254)
		(filled_areas_thickness no)
		(fill yes
			(thermal_gap 0.5)
			(thermal_bridge_width 0.5)
			(island_removal_mode 1)
			(island_area_min 10)
		)
		(polygon
			(pts
				(xy 112.89 137.81) (xy 112.879885 137.810153) (xy 112.849169 137.80954) (xy 112.81668 137.801218)
				(xy 112.787526 137.777325) (xy 112.766809 137.73) (xy 112.534 137.91) (xy 112.766809 138.09) (xy 112.780168 138.054099)
				(xy 112.798399 138.030801) (xy 112.843725 138.011101) (xy 112.879885 138.009847) (xy 112.89 138.01)
			)
		)
	)
	(zone
		(net 92)
		(net_name "/Com Express 7 Interfaces/PCIe_{B2Ax4}.RX2+")
		(layer "F.Cu")
		(name "$teardrop_padvia$")
		(hatch none 0.1)
		(priority 30375)
		(attr
			(teardrop
				(type padvia)
			)
		)
		(connect_pads yes
			(clearance 0)
		)
		(min_thickness 0.0254)
		(filled_areas_thickness no)
		(fill yes
			(thermal_gap 0.5)
			(thermal_bridge_width 0.5)
			(island_removal_mode 1)
			(island_area_min 10)
		)
		(polygon
			(pts
				(xy 290.355 74.87) (xy 290.343784 74.713526) (xy 290.329025 74.508886) (xy 290.331958 74.388472)
				(xy 290.348 74.253414) (xy 290.198 74.034) (xy 290.114678 74.81) (xy 290.145281 74.814477) (xy 290.158183 74.825818)
				(xy 290.15602 74.855836) (xy 290.153 74.87)
			)
		)
	)
	(zone
		(net 217)
		(net_name "/Com Express 7 Interfaces/PCIe_{B1x4}.RX1-")
		(layer "F.Cu")
		(name "$teardrop_padvia$")
		(hatch none 0.1)
		(priority 30514)
		(attr
			(teardrop
				(type padvia)
			)
		)
		(connect_pads yes
			(clearance 0)
		)
		(min_thickness 0.0254)
		(filled_areas_thickness no)
		(fill yes
			(thermal_gap 0.5)
			(thermal_bridge_width 0.5)
			(island_removal_mode 1)
			(island_area_min 10)
		)
		(polygon
			(pts
				(xy 207.924 162.2) (xy 207.927537 162.214678) (xy 207.930808 162.244685) (xy 207.918857 162.255673)
				(xy 207.89 162.26) (xy 208.025 163.136) (xy 208.16 162.26) (xy 208.130796 162.255525) (xy 208.119003 162.244203)
				(xy 208.122463 162.214678) (xy 208.126 162.2)
			)
		)
	)
	(zone
		(net 2)
		(net_name "+3V3")
		(layer "F.Cu")
		(name "$teardrop_padvia$")
		(hatch none 0.1)
		(priority 30168)
		(attr
			(teardrop
				(type padvia)
			)
		)
		(connect_pads yes
			(clearance 0)
		)
		(min_thickness 0.0254)
		(filled_areas_thickness no)
		(fill yes
			(thermal_gap 0.5)
			(thermal_bridge_width 0.5)
			(island_removal_mode 1)
			(island_area_min 10)
		)
		(polygon
			(pts
				(xy 308.848092 76.976516) (xy 308.855986 76.998934) (xy 308.850159 77.019914) (xy 308.804161 77.053007)
				(xy 308.656579 77.091579) (xy 308.998707 77.483707) (xy 309.304706 77.068382) (xy 309.203253 77.038698)
				(xy 309.105541 76.97328) (xy 309.015996 76.87433) (xy 308.989514 76.835094)
			)
		)
	)
	(zone
		(net 112)
		(net_name "/2xSFP+/KR to SFI #1/KR_C.TX+")
		(layer "F.Cu")
		(name "$teardrop_padvia$")
		(hatch none 0.1)
		(priority 31175)
		(attr
			(teardrop
				(type padvia)
			)
		)
		(connect_pads yes
			(clearance 0)
		)
		(min_thickness 0.0254)
		(filled_areas_thickness no)
		(fill yes
			(thermal_gap 0.5)
			(thermal_bridge_width 0.5)
			(island_removal_mode 1)
			(island_area_min 10)
		)
		(polygon
			(pts
				(xy 155.84 143.17679) (xy 155.835347 143.112802) (xy 155.822777 143.062121) (xy 155.778645 142.980204)
				(xy 155.767609 142.964616) (xy 155.726024 142.899819) (xy 155.695196 142.811227) (xy 155.45 142.859)
				(xy 155.401227 143.105196) (xy 155.488185 143.107002) (xy 155.531073 143.101889) (xy 155.588443 143.095867)
				(xy 155.635848 143.099993) (xy 155.668097 143.123792) (xy 155.68 143.17679)
			)
		)
	)
	(zone
		(net 526)
		(net_name "/Backplane/~{PRSNT}")
		(layer "F.Cu")
		(name "$teardrop_padvia$")
		(hatch none 0.1)
		(priority 31759)
		(attr
			(teardrop
				(type padvia)
			)
		)
		(connect_pads yes
			(clearance 0)
		)
		(min_thickness 0.0254)
		(filled_areas_thickness no)
		(fill yes
			(thermal_gap 0.5)
			(thermal_bridge_width 0.5)
			(island_removal_mode 1)
			(island_area_min 10)
		)
		(polygon
			(pts
				(xy 208.299323 126.5625) (xy 208.368764 126.567318) (xy 208.420088 126.58104) (xy 208.495629 126.627755)
				(xy 208.507769 126.637299) (xy 208.574997 126.687081) (xy 208.701 126.5) (xy 208.574997 126.312919)
				(xy 208.507768 126.362702) (xy 208.424602 126.417106) (xy 208.371748 126.43219) (xy 208.299323 126.4375)
			)
		)
	)
	(zone
		(net 382)
		(net_name "Net-(J12D-~{CB_RESET})")
		(layer "F.Cu")
		(name "$teardrop_padvia$")
		(hatch none 0.1)
		(priority 30653)
		(attr
			(teardrop
				(type padvia)
			)
		)
		(connect_pads yes
			(clearance 0)
		)
		(min_thickness 0.0254)
		(filled_areas_thickness no)
		(fill yes
			(thermal_gap 0.5)
			(thermal_bridge_width 0.5)
			(island_removal_mode 1)
			(island_area_min 10)
		)
		(polygon
			(pts
				(xy 200.5875 164.07) (xy 200.598438 164.031177) (xy 200.620195 164.016067) (xy 200.66 164.01) (xy 200.525 163.134)
				(xy 200.39 164.01) (xy 200.425281 164.014517) (xy 200.446797 164.026138) (xy 200.461995 164.058961)
				(xy 200.4625 164.07)
			)
		)
	)
	(zone
		(net 554)
		(net_name "/2xUSB3.0+RJ45/FLG_2B")
		(layer "F.Cu")
		(name "$teardrop_padvia$")
		(hatch none 0.1)
		(priority 30993)
		(attr
			(teardrop
				(type padvia)
			)
		)
		(connect_pads yes
			(clearance 0)
		)
		(min_thickness 0.0254)
		(filled_areas_thickness no)
		(fill yes
			(thermal_gap 0.5)
			(thermal_bridge_width 0.5)
			(island_removal_mode 1)
			(island_area_min 10)
		)
		(polygon
			(pts
				(xy 121.5075 92.522) (xy 121.487531 92.584866) (xy 121.461079 92.616844) (xy 121.423668 92.645358)
				(xy 121.376473 92.667882) (xy 121.318833 92.683093) (xy 121.318202 92.683202) (xy 121.57 92.961)
				(xy 121.821798 92.683202) (xy 121.766365 92.668905) (xy 121.72048 92.647825) (xy 121.682799 92.62046)
				(xy 121.655566 92.589552) (xy 121.638528 92.556265) (xy 121.632511 92.523434) (xy 121.6325 92.522)
			)
		)
	)
	(zone
		(net 1)
		(net_name "GND")
		(layer "F.Cu")
		(name "$teardrop_padvia$")
		(hatch none 0.1)
		(priority 31918)
		(attr
			(teardrop
				(type padvia)
			)
		)
		(connect_pads yes
			(clearance 0)
		)
		(min_thickness 0.0254)
		(filled_areas_thickness no)
		(fill yes
			(thermal_gap 0.5)
			(thermal_bridge_width 0.5)
			(island_removal_mode 1)
			(island_area_min 10)
		)
		(polygon
			(pts
				(xy 110.8 152.168) (xy 110.799847 152.157885) (xy 110.80046 152.127168) (xy 110.808782 152.09468)
				(xy 110.832675 152.065525) (xy 110.88 152.044808) (xy 110.7 151.812) (xy 110.52 152.044808) (xy 110.555901 152.058167)
				(xy 110.579199 152.076398) (xy 110.598899 152.121724) (xy 110.600153 152.157885) (xy 110.6 152.168)
			)
		)
	)
	(zone
		(net 740)
		(net_name "Net-(U45C-REFCLK1+)")
		(layer "F.Cu")
		(name "$teardrop_padvia$")
		(hatch none 0.1)
		(priority 31583)
		(attr
			(teardrop
				(type padvia)
			)
		)
		(connect_pads yes
			(clearance 0)
		)
		(min_thickness 0.0254)
		(filled_areas_thickness no)
		(fill yes
			(thermal_gap 0.5)
			(thermal_bridge_width 0.5)
			(island_removal_mode 1)
			(island_area_min 10)
		)
		(polygon
			(pts
				(xy 127.0775 129.759323) (xy 127.072844 129.833678) (xy 127.060255 129.890048) (xy 127.021827 129.974329)
				(xy 126.969565 130.091377) (xy 127.18 130.161) (xy 127.367081 130.034997) (xy 127.288849 129.946758)
				(xy 127.227636 129.875771) (xy 127.209228 129.826942) (xy 127.2025 129.759323)
			)
		)
	)
	(zone
		(net 1)
		(net_name "GND")
		(layer "F.Cu")
		(name "$teardrop_padvia$")
		(hatch none 0.1)
		(priority 30316)
		(attr
			(teardrop
				(type padvia)
			)
		)
		(connect_pads yes
			(clearance 0)
		)
		(min_thickness 0.0254)
		(filled_areas_thickness no)
		(fill yes
			(thermal_gap 0.5)
			(thermal_bridge_width 0.5)
			(island_removal_mode 1)
			(island_area_min 10)
		)
		(polygon
			(pts
				(xy 261.104487 88.419999) (xy 261.162301 88.4311) (xy 261.188211 88.451839) (xy 261.208693 88.488804)
				(xy 261.223779 88.596498) (xy 261.540999 88.429999) (xy 261.507642 88.134999) (xy 261.413625 88.160086)
				(xy 261.301041 88.154578) (xy 261.217705 88.137903) (xy 261.104486 88.12)
			)
		)
	)
	(zone
		(net 608)
		(net_name "Net-(U37-~{OE5})")
		(layer "F.Cu")
		(name "$teardrop_padvia$")
		(hatch none 0.1)
		(priority 31041)
		(attr
			(teardrop
				(type padvia)
			)
		)
		(connect_pads yes
			(clearance 0)
		)
		(min_thickness 0.0254)
		(filled_areas_thickness no)
		(fill yes
			(thermal_gap 0.5)
			(thermal_bridge_width 0.5)
			(island_removal_mode 1)
			(island_area_min 10)
		)
		(polygon
			(pts
				(xy 219.2825 126.338) (xy 219.30215 126.279023) (xy 219.365195 126.222993) (xy 219.41498 126.200026)
				(xy 219.475724 126.183605) (xy 219.496911 126.180062) (xy 219.25 125.899) (xy 218.998202 126.176798)
				(xy 219.0824 126.211036) (xy 219.137262 126.269356) (xy 219.1575 126.338)
			)
		)
	)
	(zone
		(net 1)
		(net_name "GND")
		(layer "F.Cu")
		(name "$teardrop_padvia$")
		(hatch none 0.1)
		(priority 30753)
		(attr
			(teardrop
				(type padvia)
			)
		)
		(connect_pads yes
			(clearance 0)
		)
		(min_thickness 0.0254)
		(filled_areas_thickness no)
		(fill yes
			(thermal_gap 0.5)
			(thermal_bridge_width 0.5)
			(island_removal_mode 1)
			(island_area_min 10)
		)
		(polygon
			(pts
				(xy 286.298323 75.11) (xy 286.4559 75.116932) (xy 286.569434 75.145456) (xy 286.611222 75.1625)
				(xy 286.7 74.96) (xy 286.611222 74.7575) (xy 286.515177 74.791883) (xy 286.413296 74.807101) (xy 286.298323 74.81)
			)
		)
	)
	(zone
		(net 5)
		(net_name "/M.2 key E/~{LED_1}")
		(layer "F.Cu")
		(name "$teardrop_padvia$")
		(hatch none 0.1)
		(priority 30180)
		(attr
			(teardrop
				(type padvia)
			)
		)
		(connect_pads yes
			(clearance 0)
		)
		(min_thickness 0.0254)
		(filled_areas_thickness no)
		(fill yes
			(thermal_gap 0.5)
			(thermal_bridge_width 0.5)
			(island_removal_mode 1)
			(island_area_min 10)
		)
		(polygon
			(pts
				(xy 116.501265 71.072877) (xy 116.504983 71.046991) (xy 116.518142 71.024737) (xy 116.574133 70.988633)
				(xy 116.691139 70.962413) (xy 116.814846 70.955057) (xy 116.449293 70.559293) (xy 116.094803 70.956977)
				(xy 116.218545 70.97617) (xy 116.324929 71.028575) (xy 116.365336 71.063806) (xy 116.394235 71.102188)
				(xy 116.412877 71.161265)
			)
		)
	)
	(zone
		(net 358)
		(net_name "/Com Express 7 MGMT/SMBus.SDA")
		(layer "F.Cu")
		(name "$teardrop_padvia$")
		(hatch none 0.1)
		(priority 31844)
		(attr
			(teardrop
				(type padvia)
			)
		)
		(connect_pads yes
			(clearance 0)
		)
		(min_thickness 0.0254)
		(filled_areas_thickness no)
		(fill yes
			(thermal_gap 0.5)
			(thermal_bridge_width 0.5)
			(island_removal_mode 1)
			(island_area_min 10)
		)
		(polygon
			(pts
				(xy 182.439127 164.272485) (xy 182.386618 164.318181) (xy 182.340623 164.344768) (xy 182.254174 164.365152)
				(xy 182.238841 164.366988) (xy 182.156105 164.379323) (xy 182.199293 164.600707) (xy 182.420677 164.643895)
				(xy 182.433011 164.56116) (xy 182.453349 164.463881) (xy 182.480057 164.415841) (xy 182.527515 164.360873)
			)
		)
	)
	(zone
		(net 642)
		(net_name "Net-(U41-IO0_3)")
		(layer "F.Cu")
		(name "$teardrop_padvia$")
		(hatch none 0.1)
		(priority 32027)
		(attr
			(teardrop
				(type padvia)
			)
		)
		(connect_pads yes
			(clearance 0)
		)
		(min_thickness 0.0254)
		(filled_areas_thickness no)
		(fill yes
			(thermal_gap 0.5)
			(thermal_bridge_width 0.5)
			(island_removal_mode 1)
			(island_area_min 10)
		)
		(polygon
			(pts
				(xy 128.2495 85.8705) (xy 128.255821 85.870404) (xy 128.295325 85.875989) (xy 128.313547 85.890922)
				(xy 128.326496 85.9205) (xy 128.712999 85.808) (xy 128.326494 85.6955) (xy 128.315378 85.722494)
				(xy 128.299851 85.737596) (xy 128.255822 85.745597) (xy 128.249501 85.745501)
			)
		)
	)
	(zone
		(net 572)
		(net_name "Net-(U7-A_{2})")
		(layer "F.Cu")
		(name "$teardrop_padvia$")
		(hatch none 0.1)
		(priority 31108)
		(attr
			(teardrop
				(type padvia)
			)
		)
		(connect_pads yes
			(clearance 0)
		)
		(min_thickness 0.0254)
		(filled_areas_thickness no)
		(fill yes
			(thermal_gap 0.5)
			(thermal_bridge_width 0.5)
			(island_removal_mode 1)
			(island_area_min 10)
		)
		(polygon
			(pts
				(xy 123.3175 74.917) (xy 123.297727 74.976412) (xy 123.234453 75.032496) (xy 123.185828 75.054198)
				(xy 123.126469 75.068872) (xy 123.1145 75.070652) (xy 123.38 75.331) (xy 123.6455 75.070652) (xy 123.585362 75.057803)
				(xy 123.535478 75.037869) (xy 123.495358 75.011944) (xy 123.466345 74.982124) (xy 123.448854 74.950706)
				(xy 123.442521 74.918895) (xy 123.4425 74.917)
			)
		)
	)
	(zone
		(net 58)
		(net_name "/USB-C console/VBUS_FTDI")
		(layer "F.Cu")
		(name "$teardrop_padvia$")
		(hatch none 0.1)
		(priority 30893)
		(attr
			(teardrop
				(type padvia)
			)
		)
		(connect_pads yes
			(clearance 0)
		)
		(min_thickness 0.0254)
		(filled_areas_thickness no)
		(fill yes
			(thermal_gap 0.5)
			(thermal_bridge_width 0.5)
			(island_removal_mode 1)
			(island_area_min 10)
		)
		(polygon
			(pts
				(xy 120.537 72.806781) (xy 120.532298 72.842227) (xy 120.519382 72.868222) (xy 120.474745 72.901106)
				(xy 120.437514 72.915236) (xy 120.374997 72.942919) (xy 120.5 73.131) (xy 120.720677 73.153697)
				(xy 120.746026 73.069166) (xy 120.772063 73.02213) (xy 120.816275 72.933657) (xy 120.831257 72.877051)
				(xy 120.837 72.806781)
			)
		)
	)
	(zone
		(net 75)
		(net_name "Net-(U50-IN+)")
		(layer "F.Cu")
		(name "$teardrop_padvia$")
		(hatch none 0.1)
		(priority 30730)
		(attr
			(teardrop
				(type padvia)
			)
		)
		(connect_pads yes
			(clearance 0)
		)
		(min_thickness 0.0254)
		(filled_areas_thickness no)
		(fill yes
			(thermal_gap 0.5)
			(thermal_bridge_width 0.5)
			(island_removal_mode 1)
			(island_area_min 10)
		)
		(polygon
			(pts
				(xy 304.1875 91.9) (xy 304.192821 91.868265) (xy 304.210069 91.835565) (xy 304.236538 91.809374)
				(xy 304.274964 91.788445) (xy 304.31705 91.77705) (xy 304.125 91.259) (xy 303.93295 91.77705) (xy 303.977474 91.789409)
				(xy 304.0116 91.808008) (xy 304.053536 91.858803) (xy 304.0625 91.9)
			)
		)
	)
	(zone
		(net 1)
		(net_name "GND")
		(layer "F.Cu")
		(name "$teardrop_padvia$")
		(hatch none 0.1)
		(priority 31270)
		(attr
			(teardrop
				(type padvia)
			)
		)
		(connect_pads yes
			(clearance 0)
		)
		(min_thickness 0.0254)
		(filled_areas_thickness no)
		(fill yes
			(thermal_gap 0.5)
			(thermal_bridge_width 0.5)
			(island_removal_mode 1)
			(island_area_min 10)
		)
		(polygon
			(pts
				(xy 193.60861 77.701486) (xy 193.603897 77.779397) (xy 193.59091 77.838181) (xy 193.548809 77.929211)
				(xy 193.50611 78.014384) (xy 193.70861 78.103163) (xy 193.91111 78.014384) (xy 193.868411 77.929213)
				(xy 193.825743 77.83638) (xy 193.813166 77.778241) (xy 193.80861 77.701486)
			)
		)
	)
	(zone
		(net 356)
		(net_name "/Com Express 7 MGMT/~{CW_PWRBTN}")
		(layer "F.Cu")
		(name "$teardrop_padvia$")
		(hatch none 0.1)
		(priority 30674)
		(attr
			(teardrop
				(type padvia)
			)
		)
		(connect_pads yes
			(clearance 0)
		)
		(min_thickness 0.0254)
		(filled_areas_thickness no)
		(fill yes
			(thermal_gap 0.5)
			(thermal_bridge_width 0.5)
			(island_removal_mode 1)
			(island_area_min 10)
		)
		(polygon
			(pts
				(xy 181.4625 162.2) (xy 181.451563 162.238823) (xy 181.429805 162.253933) (xy 181.39 162.26) (xy 181.525 163.136)
				(xy 181.66 162.26) (xy 181.624719 162.255483) (xy 181.603203 162.243862) (xy 181.588005 162.211039)
				(xy 181.5875 162.2)
			)
		)
	)
	(zone
		(net 1)
		(net_name "GND")
		(layer "F.Cu")
		(name "$teardrop_padvia$")
		(hatch none 0.1)
		(priority 31263)
		(attr
			(teardrop
				(type padvia)
			)
		)
		(connect_pads yes
			(clearance 0)
		)
		(min_thickness 0.0254)
		(filled_areas_thickness no)
		(fill yes
			(thermal_gap 0.5)
			(thermal_bridge_width 0.5)
			(island_removal_mode 1)
			(island_area_min 10)
		)
		(polygon
			(pts
				(xy 191.125 167.900677) (xy 191.129713 167.822764) (xy 191.1427 167.76398) (xy 191.184802 167.672947)
				(xy 191.2275 167.587778) (xy 191.025 167.499) (xy 190.8225 167.587778) (xy 190.865198 167.672949)
				(xy 190.907867 167.765783) (xy 190.920444 167.823922) (xy 190.925 167.900677)
			)
		)
	)
	(zone
		(net 2)
		(net_name "+3V3")
		(layer "F.Cu")
		(name "$teardrop_padvia$")
		(hatch none 0.1)
		(priority 30159)
		(attr
			(teardrop
				(type padvia)
			)
		)
		(connect_pads yes
			(clearance 0)
		)
		(min_thickness 0.0254)
		(filled_areas_thickness no)
		(fill yes
			(thermal_gap 0.5)
			(thermal_bridge_width 0.5)
			(island_removal_mode 1)
			(island_area_min 10)
		)
		(polygon
			(pts
				(xy 197.60861 73.542163) (xy 197.60355 73.575682) (xy 197.588129 73.608588) (xy 197.562347 73.6389)
				(xy 197.525738 73.665407) (xy 197.478562 73.68631) (xy 197.420127 73.700395) (xy 197.34861 73.706141)
				(xy 197.70861 74.103163) (xy 198.06861 73.706141) (xy 197.998539 73.700621) (xy 197.940004 73.686759)
				(xy 197.892657 73.666073) (xy 197.856184 73.640095) (xy 197.8301 73.610127) (xy 197.814368 73.577901)
				(xy 197.80861 73.542163)
			)
		)
	)
	(zone
		(net 1)
		(net_name "GND")
		(layer "F.Cu")
		(name "$teardrop_padvia$")
		(hatch none 0.1)
		(priority 31255)
		(attr
			(teardrop
				(type padvia)
			)
		)
		(connect_pads yes
			(clearance 0)
		)
		(min_thickness 0.0254)
		(filled_areas_thickness no)
		(fill yes
			(thermal_gap 0.5)
			(thermal_bridge_width 0.5)
			(island_removal_mode 1)
			(island_area_min 10)
		)
		(polygon
			(pts
				(xy 186.125 167.850677) (xy 186.129713 167.772764) (xy 186.1427 167.71398) (xy 186.184802 167.622947)
				(xy 186.2275 167.537778) (xy 186.025 167.449) (xy 185.8225 167.537778) (xy 185.865198 167.622949)
				(xy 185.907867 167.715783) (xy 185.920444 167.773922) (xy 185.925 167.850677)
			)
		)
	)
	(zone
		(net 151)
		(net_name "/2xUSB3.0+RJ45/DB-")
		(layer "F.Cu")
		(name "$teardrop_padvia$")
		(hatch none 0.1)
		(priority 31576)
		(attr
			(teardrop
				(type padvia)
			)
		)
		(connect_pads yes
			(clearance 0)
		)
		(min_thickness 0.0254)
		(filled_areas_thickness no)
		(fill yes
			(thermal_gap 0.5)
			(thermal_bridge_width 0.5)
			(island_removal_mode 1)
			(island_area_min 10)
		)
		(polygon
			(pts
				(xy 125.8575 105.115) (xy 125.894762 105.120773) (xy 125.933367 105.141186) (xy 125.958689 105.168248)
				(xy 125.978392 105.20759) (xy 125.987281 105.242719) (xy 126.291 105.04) (xy 125.987281 104.837281)
				(xy 125.97498 104.881474) (xy 125.956524 104.914766) (xy 125.90635 104.95492) (xy 125.8575 104.965)
			)
		)
	)
	(zone
		(net 1)
		(net_name "GND")
		(layer "F.Cu")
		(name "$teardrop_padvia$")
		(hatch none 0.1)
		(priority 31221)
		(attr
			(teardrop
				(type padvia)
			)
		)
		(connect_pads yes
			(clearance 0)
		)
		(min_thickness 0.0254)
		(filled_areas_thickness no)
		(fill yes
			(thermal_gap 0.5)
			(thermal_bridge_width 0.5)
			(island_removal_mode 1)
			(island_area_min 10)
		)
		(polygon
			(pts
				(xy 210.625 155.900677) (xy 210.629737 155.809676) (xy 210.642896 155.742587) (xy 210.675418 155.655855)
				(xy 210.707644 155.575358) (xy 210.5 155.499) (xy 210.303541 155.602363) (xy 210.355343 155.685863)
				(xy 210.404833 155.771955) (xy 210.419614 155.82716) (xy 210.425 155.900677)
			)
		)
	)
	(zone
		(net 557)
		(net_name "Net-(U5-A0)")
		(layer "F.Cu")
		(name "$teardrop_padvia$")
		(hatch none 0.1)
		(priority 32026)
		(attr
			(teardrop
				(type padvia)
			)
		)
		(connect_pads yes
			(clearance 0)
		)
		(min_thickness 0.0254)
		(filled_areas_thickness no)
		(fill yes
			(thermal_gap 0.5)
			(thermal_bridge_width 0.5)
			(island_removal_mode 1)
			(island_area_min 10)
		)
		(polygon
			(pts
				(xy 161.6995 159.2975) (xy 161.693178 159.297596) (xy 161.653675 159.292011) (xy 161.635453 159.277078)
				(xy 161.622505 159.2475) (xy 161.236 159.36) (xy 161.622505 159.4725) (xy 161.633621 159.445506)
				(xy 161.649148 159.430405) (xy 161.693178 159.422404) (xy 161.6995 159.4225)
			)
		)
	)
	(zone
		(net 580)
		(net_name "Net-(U18-FB)")
		(layer "F.Cu")
		(name "$teardrop_padvia$")
		(hatch none 0.1)
		(priority 31075)
		(attr
			(teardrop
				(type padvia)
			)
		)
		(connect_pads yes
			(clearance 0)
		)
		(min_thickness 0.0254)
		(filled_areas_thickness no)
		(fill yes
			(thermal_gap 0.5)
			(thermal_bridge_width 0.5)
			(island_removal_mode 1)
			(island_area_min 10)
		)
		(polygon
			(pts
				(xy 309.237499 121.053) (xy 309.257272 120.993588) (xy 309.320546 120.937503) (xy 309.369171 120.915801)
				(xy 309.428531 120.901127) (xy 309.440499 120.899347) (xy 309.174999 120.639) (xy 308.909499 120.899347)
				(xy 308.969638 120.912197) (xy 309.019522 120.932131) (xy 309.059641 120.958056) (xy 309.088654 120.987876)
				(xy 309.106145 121.019294) (xy 309.112478 121.051105) (xy 309.112499 121.053)
			)
		)
	)
	(zone
		(net 89)
		(net_name "/Com Express 7 Interfaces/PCIe_{B2Ax4}.RX3-")
		(layer "F.Cu")
		(name "$teardrop_padvia$")
		(hatch none 0.1)
		(priority 31420)
		(attr
			(teardrop
				(type padvia)
			)
		)
		(connect_pads yes
			(clearance 0)
		)
		(min_thickness 0.0254)
		(filled_areas_thickness no)
		(fill yes
			(thermal_gap 0.5)
			(thermal_bridge_width 0.5)
			(island_removal_mode 1)
			(island_area_min 10)
		)
		(polygon
			(pts
				(xy 216.3685 164.332504) (xy 216.373895 164.494035) (xy 216.377445 164.578446) (xy 216.372823 164.68014)
				(xy 216.5935 164.701) (xy 216.756731 164.551147) (xy 216.688062 164.497007) (xy 216.671608 164.487116)
				(xy 216.632935 164.462616) (xy 216.600721 164.433109) (xy 216.578673 164.391953) (xy 216.5705 164.332504)
			)
		)
	)
	(zone
		(net 564)
		(net_name "/2xSFP+/~{LED0_2}")
		(layer "F.Cu")
		(name "$teardrop_padvia$")
		(hatch none 0.1)
		(priority 32018)
		(attr
			(teardrop
				(type padvia)
			)
		)
		(connect_pads yes
			(clearance 0)
		)
		(min_thickness 0.0254)
		(filled_areas_thickness no)
		(fill yes
			(thermal_gap 0.5)
			(thermal_bridge_width 0.5)
			(island_removal_mode 1)
			(island_area_min 10)
		)
		(polygon
			(pts
				(xy 156.8995 160.4225) (xy 156.905822 160.422404) (xy 156.945325 160.427989) (xy 156.963547 160.442922)
				(xy 156.976495 160.4725) (xy 157.363 160.36) (xy 156.976495 160.2475) (xy 156.965379 160.274493)
				(xy 156.949852 160.289595) (xy 156.905822 160.297596) (xy 156.8995 160.2975)
			)
		)
	)
	(zone
		(net 315)
		(net_name "Net-(J12H-VCC_RTC)")
		(layer "F.Cu")
		(name "$teardrop_padvia$")
		(hatch none 0.1)
		(priority 30001)
		(attr
			(teardrop
				(type padvia)
			)
		)
		(connect_pads yes
			(clearance 0)
		)
		(min_thickness 0.0254)
		(filled_areas_thickness no)
		(fill yes
			(thermal_gap 0.5)
			(thermal_bridge_width 0.5)
			(island_removal_mode 1)
			(island_area_min 10)
		)
		(polygon
			(pts
				(xy 219.209 72.123667) (xy 219.213915 71.974822) (xy 219.228319 71.848709) (xy 219.249492 71.749149)
				(xy 219.277855 71.661841) (xy 219.356634 71.507361) (xy 219.490388 71.32268) (xy 219.665749 71.082235)
				(xy 218.959 70.609) (xy 218.252251 71.082235) (xy 218.427613 71.322682) (xy 218.544408 71.481289)
				(xy 218.592508 71.55996) (xy 218.633043 71.644099) (xy 218.665485 71.738122) (xy 218.689309 71.846446)
				(xy 218.70399 71.973489) (xy 218.709 72.123667)
			)
		)
	)
	(zone
		(net 705)
		(net_name "Net-(U24-GPIO1)")
		(layer "F.Cu")
		(name "$teardrop_padvia$")
		(hatch none 0.1)
		(priority 31765)
		(attr
			(teardrop
				(type padvia)
			)
		)
		(connect_pads yes
			(clearance 0)
		)
		(min_thickness 0.0254)
		(filled_areas_thickness no)
		(fill yes
			(thermal_gap 0.5)
			(thermal_bridge_width 0.5)
			(island_removal_mode 1)
			(island_area_min 10)
		)
		(polygon
			(pts
				(xy 261.499323 86.432499) (xy 261.568764 86.437317) (xy 261.620088 86.451039) (xy 261.695629 86.497754)
				(xy 261.707769 86.507298) (xy 261.774997 86.55708) (xy 261.901 86.369999) (xy 261.774997 86.182918)
				(xy 261.707768 86.232701) (xy 261.624602 86.287105) (xy 261.571748 86.302189) (xy 261.499323 86.307499)
			)
		)
	)
	(zone
		(net 711)
		(net_name "Net-(U37-SADR_{TRI})")
		(layer "F.Cu")
		(name "$teardrop_padvia$")
		(hatch none 0.1)
		(priority 32102)
		(attr
			(teardrop
				(type padvia)
			)
		)
		(connect_pads yes
			(clearance 0)
		)
		(min_thickness 0.0254)
		(filled_areas_thickness no)
		(fill yes
			(thermal_gap 0.5)
			(thermal_bridge_width 0.5)
			(island_removal_mode 1)
			(island_area_min 10)
		)
		(polygon
			(pts
				(xy 217.4165 125.834) (xy 217.417952 125.845797) (xy 217.418129 125.874081) (xy 217.409153 125.886652)
				(xy 217.389 125.895596) (xy 217.479 126.25) (xy 217.569 125.895596) (xy 217.548044 125.885992) (xy 217.53937 125.872447)
				(xy 217.540048 125.845797) (xy 217.5415 125.834)
			)
		)
	)
	(zone
		(net 212)
		(net_name "/Com Express 7 Interfaces/PCIe_{B1x4}.TX3+")
		(layer "F.Cu")
		(name "$teardrop_padvia$")
		(hatch none 0.1)
		(priority 31398)
		(attr
			(teardrop
				(type padvia)
			)
		)
		(connect_pads yes
			(clearance 0)
		)
		(min_thickness 0.0254)
		(filled_areas_thickness no)
		(fill yes
			(thermal_gap 0.5)
			(thermal_bridge_width 0.5)
			(island_removal_mode 1)
			(island_area_min 10)
		)
		(polygon
			(pts
				(xy 204.6815 165.667496) (xy 204.676105 165.505964) (xy 204.672555 165.421553) (xy 204.677177 165.319859)
				(xy 204.4565 165.299) (xy 204.293268 165.448852) (xy 204.361936 165.502992) (xy 204.378392 165.512884)
				(xy 204.417064 165.537384) (xy 204.449279 165.56689) (xy 204.471327 165.608046) (xy 204.4795 165.667496)
			)
		)
	)
	(zone
		(net 990)
		(net_name "Net-(Q14-C)")
		(layer "F.Cu")
		(name "$teardrop_padvia$")
		(hatch none 0.1)
		(priority 30866)
		(attr
			(teardrop
				(type padvia)
			)
		)
		(connect_pads yes
			(clearance 0)
		)
		(min_thickness 0.0254)
		(filled_areas_thickness no)
		(fill yes
			(thermal_gap 0.5)
			(thermal_bridge_width 0.5)
			(island_removal_mode 1)
			(island_area_min 10)
		)
		(polygon
			(pts
				(xy 199.80861 78.045163) (xy 199.814382 78.004426) (xy 199.834786 77.962511) (xy 199.861961 77.93421)
				(xy 199.901507 77.910781) (xy 199.97411 77.89151) (xy 199.70861 77.631163) (xy 199.44311 77.89151)
				(xy 199.496252 77.903377) (xy 199.537291 77.921825) (xy 199.588992 77.972499) (xy 199.608328 78.036068)
				(xy 199.60861 78.045163)
			)
		)
	)
	(zone
		(net 709)
		(net_name "Net-(U37-SCLK)")
		(layer "F.Cu")
		(name "$teardrop_padvia$")
		(hatch none 0.1)
		(priority 31592)
		(attr
			(teardrop
				(type padvia)
			)
		)
		(connect_pads yes
			(clearance 0)
		)
		(min_thickness 0.0254)
		(filled_areas_thickness no)
		(fill yes
			(thermal_gap 0.5)
			(thermal_bridge_width 0.5)
			(island_removal_mode 1)
			(island_area_min 10)
		)
		(polygon
			(pts
				(xy 214.3425 125.967961) (xy 214.347243 125.918773) (xy 214.360447 125.881568) (xy 214.405283 125.831611)
				(xy 214.445678 125.805387) (xy 214.496728 125.77171) (xy 214.546159 125.723268) (xy 214.370681 125.585663)
				(xy 214.151217 125.633488) (xy 214.183174 125.749689) (xy 214.207495 125.839359) (xy 214.2175 125.967961)
			)
		)
	)
	(zone
		(net 69)
		(net_name "Net-(C48-Pad2)")
		(layer "F.Cu")
		(name "$teardrop_padvia$")
		(hatch none 0.1)
		(priority 32142)
		(attr
			(teardrop
				(type padvia)
			)
		)
		(connect_pads yes
			(clearance 0)
		)
		(min_thickness 0.0254)
		(filled_areas_thickness no)
		(fill yes
			(thermal_gap 0.5)
			(thermal_bridge_width 0.5)
			(island_removal_mode 1)
			(island_area_min 10)
		)
		(polygon
			(pts
				(xy 312.462499 105.849099) (xy 312.504616 105.920709) (xy 312.524851 106.037522) (xy 312.519999 106.132195)
				(xy 312.619999 106.149999) (xy 312.619953 105.85092) (xy 312.595879 105.857747) (xy 312.589958 105.853136)
				(xy 312.587499 105.849099)
			)
		)
	)
	(zone
		(net 590)
		(net_name "Net-(U24-+2.5V_{IN})")
		(layer "F.Cu")
		(name "$teardrop_padvia$")
		(hatch none 0.1)
		(priority 30830)
		(attr
			(teardrop
				(type padvia)
			)
		)
		(connect_pads yes
			(clearance 0)
		)
		(min_thickness 0.0254)
		(filled_areas_thickness no)
		(fill yes
			(thermal_gap 0.5)
			(thermal_bridge_width 0.5)
			(island_removal_mode 1)
			(island_area_min 10)
		)
		(polygon
			(pts
				(xy 253.556507 88.169999) (xy 253.507988 88.172753) (xy 253.39637 88.174162) (xy 253.340948 88.160788)
				(xy 253.292499 88.129999) (xy 253.143999 88.449999) (xy 253.439999 88.610513) (xy 253.444429 88.527626)
				(xy 253.457703 88.463382) (xy 253.476051 88.420845) (xy 253.499591 88.391613) (xy 253.524583 88.376009)
				(xy 253.55243 88.370087) (xy 253.556507 88.369999)
			)
		)
	)
	(zone
		(net 62)
		(net_name "+12V_AON")
		(layer "F.Cu")
		(name "$teardrop_padvia$")
		(hatch none 0.1)
		(priority 30097)
		(attr
			(teardrop
				(type padvia)
			)
		)
		(connect_pads yes
			(clearance 0)
		)
		(min_thickness 0.0254)
		(filled_areas_thickness no)
		(fill yes
			(thermal_gap 0.5)
			(thermal_bridge_width 0.5)
			(island_removal_mode 1)
			(island_area_min 10)
		)
		(polygon
			(pts
				(xy 198.980829 74.165802) (xy 199.064639 74.189128) (xy 199.113183 74.218337) (xy 199.159338 74.258379)
				(xy 199.198216 74.305975) (xy 199.229482 74.362293) (xy 199.255473 74.4553) (xy 199.709317 74.10287)
				(xy 199.220789 73.800934) (xy 199.211834 73.897162) (xy 199.193584 73.966672) (xy 199.174428 74.000093)
				(xy 199.150108 74.019331) (xy 199.122249 74.024382)
			)
		)
	)
	(zone
		(net 252)
		(net_name "/Com Express 7 Interfaces/PCIe_{B2Bx4}.RX1-")
		(layer "F.Cu")
		(name "$teardrop_padvia$")
		(hatch none 0.1)
		(priority 31371)
		(attr
			(teardrop
				(type padvia)
			)
		)
		(connect_pads yes
			(clearance 0)
		)
		(min_thickness 0.0254)
		(filled_areas_thickness no)
		(fill yes
			(thermal_gap 0.5)
			(thermal_bridge_width 0.5)
			(island_removal_mode 1)
			(island_area_min 10)
		)
		(polygon
			(pts
				(xy 173.232504 100.4055) (xy 173.27929 100.410235) (xy 173.314742 100.423379) (xy 173.362939 100.468387)
				(xy 173.387116 100.506608) (xy 173.414485 100.549773) (xy 173.451147 100.591731) (xy 173.601 100.4285)
				(xy 173.58014 100.207823) (xy 173.479466 100.212452) (xy 173.396096 100.209019) (xy 173.394035 100.208895)
				(xy 173.232504 100.2035)
			)
		)
	)
	(zone
		(net 597)
		(net_name "/Misc/PWM1")
		(layer "F.Cu")
		(name "$teardrop_padvia$")
		(hatch none 0.1)
		(priority 30828)
		(attr
			(teardrop
				(type padvia)
			)
		)
		(connect_pads yes
			(clearance 0)
		)
		(min_thickness 0.0254)
		(filled_areas_thickness no)
		(fill yes
			(thermal_gap 0.5)
			(thermal_bridge_width 0.5)
			(island_removal_mode 1)
			(island_area_min 10)
		)
		(polygon
			(pts
				(xy 254.101365 89.587021) (xy 254.118429 89.591415) (xy 254.129549 89.605861) (xy 254.139352 89.672089)
				(xy 254.14 89.731375) (xy 254.700707 89.539293) (xy 254.14 89.35337) (xy 254.122692 89.423737) (xy 254.075643 89.475681)
				(xy 254.012978 89.498634)
			)
		)
	)
	(zone
		(net 386)
		(net_name "/Com Express 7 Interfaces/SD_WP")
		(layer "F.Cu")
		(name "$teardrop_padvia$")
		(hatch none 0.1)
		(priority 31064)
		(attr
			(teardrop
				(type padvia)
			)
		)
		(connect_pads yes
			(clearance 0)
		)
		(min_thickness 0.0254)
		(filled_areas_thickness no)
		(fill yes
			(thermal_gap 0.5)
			(thermal_bridge_width 0.5)
			(island_removal_mode 1)
			(island_area_min 10)
		)
		(polygon
			(pts
				(xy 202.893 159.9375) (xy 202.833588 159.917727) (xy 202.777503 159.854453) (xy 202.755801 159.805828)
				(xy 202.741127 159.746468) (xy 202.739347 159.7345) (xy 202.479 160) (xy 202.739347 160.2655) (xy 202.752197 160.205361)
				(xy 202.772131 160.155477) (xy 202.798056 160.115358) (xy 202.827876 160.086345) (xy 202.859294 160.068854)
				(xy 202.891105 160.062521) (xy 202.893 160.0625)
			)
		)
	)
	(zone
		(net 365)
		(net_name "/Com Express 7 MGMT/PWR_OK")
		(layer "F.Cu")
		(name "$teardrop_padvia$")
		(hatch none 0.1)
		(priority 31868)
		(attr
			(teardrop
				(type padvia)
			)
		)
		(connect_pads yes
			(clearance 0)
		)
		(min_thickness 0.0254)
		(filled_areas_thickness no)
		(fill yes
			(thermal_gap 0.5)
			(thermal_bridge_width 0.5)
			(island_removal_mode 1)
			(island_area_min 10)
		)
		(polygon
			(pts
				(xy 188.660873 118.277515) (xy 188.713382 118.231819) (xy 188.759376 118.205231) (xy 188.845824 118.184847)
				(xy 188.86116 118.183011) (xy 188.943895 118.170677) (xy 188.900707 117.949293) (xy 188.679323 117.906105)
				(xy 188.666988 117.988841) (xy 188.646651 118.086119) (xy 188.619943 118.134159) (xy 188.572485 118.189127)
			)
		)
	)
	(zone
		(net 389)
		(net_name "Net-(J12D-~{BIOS_DIS1})")
		(layer "F.Cu")
		(name "$teardrop_padvia$")
		(hatch none 0.1)
		(priority 31269)
		(attr
			(teardrop
				(type padvia)
			)
		)
		(connect_pads yes
			(clearance 0)
		)
		(min_thickness 0.0254)
		(filled_areas_thickness no)
		(fill yes
			(thermal_gap 0.5)
			(thermal_bridge_width 0.5)
			(island_removal_mode 1)
			(island_area_min 10)
		)
		(polygon
			(pts
				(xy 219.4 164.099323) (xy 219.395287 164.177234) (xy 219.3823 164.236018) (xy 219.340199 164.327048)
				(xy 219.2975 164.412221) (xy 219.5 164.501) (xy 219.7025 164.412221) (xy 219.659801 164.32705) (xy 219.617133 164.234217)
				(xy 219.604556 164.176078) (xy 219.6 164.099323)
			)
		)
	)
	(zone
		(net 1)
		(net_name "GND")
		(layer "F.Cu")
		(name "$teardrop_padvia$")
		(hatch none 0.1)
		(priority 31196)
		(attr
			(teardrop
				(type padvia)
			)
		)
		(connect_pads yes
			(clearance 0)
		)
		(min_thickness 0.0254)
		(filled_areas_thickness no)
		(fill yes
			(thermal_gap 0.5)
			(thermal_bridge_width 0.5)
			(island_removal_mode 1)
			(island_area_min 10)
		)
		(polygon
			(pts
				(xy 230.425 169.489323) (xy 230.42028 169.558646) (xy 230.407244 169.611549) (xy 230.355344 169.704135)
				(xy 230.303541 169.787636) (xy 230.5 169.891) (xy 230.707644 169.814641) (xy 230.675418 169.734142)
				(xy 230.639035 169.632683) (xy 230.625 169.489323)
			)
		)
	)
	(zone
		(net 537)
		(net_name "/Backplane/PCIe_{x2}.RX0-")
		(layer "F.Cu")
		(name "$teardrop_padvia$")
		(hatch none 0.1)
		(priority 30283)
		(attr
			(teardrop
				(type padvia)
			)
		)
		(connect_pads yes
			(clearance 0)
		)
		(min_thickness 0.0254)
		(filled_areas_thickness no)
		(fill yes
			(thermal_gap 0.5)
			(thermal_bridge_width 0.5)
			(island_removal_mode 1)
			(island_area_min 10)
		)
		(polygon
			(pts
				(xy 201.8685 155.75) (xy 201.879599 155.923112) (xy 201.894216 156.15051) (xy 201.891181 156.285138)
				(xy 201.875 156.437021) (xy 202.025 156.686) (xy 202.108295 155.81) (xy 202.077864 155.805523) (xy 202.065097 155.794185)
				(xy 202.06742 155.764227) (xy 202.0705 155.75)
			)
		)
	)
	(zone
		(net 1)
		(net_name "GND")
		(layer "F.Cu")
		(name "$teardrop_padvia$")
		(hatch none 0.1)
		(priority 30532)
		(attr
			(teardrop
				(type padvia)
			)
		)
		(connect_pads yes
			(clearance 0)
		)
		(min_thickness 0.0254)
		(filled_areas_thickness no)
		(fill yes
			(thermal_gap 0.5)
			(thermal_bridge_width 0.5)
			(island_removal_mode 1)
			(island_area_min 10)
		)
		(polygon
			(pts
				(xy 175.925 155.75) (xy 175.928333 155.764486) (xy 175.93119 155.79461) (xy 175.919036 155.805651)
				(xy 175.89 155.81) (xy 176.025 156.686) (xy 176.16 155.81) (xy 176.130666 155.805525) (xy 176.118642 155.794199)
				(xy 176.121667 155.764486) (xy 176.125 155.75)
			)
		)
	)
	(zone
		(net 166)
		(net_name "Net-(J2A-MOD_{ABS})")
		(layer "F.Cu")
		(name "$teardrop_padvia$")
		(hatch none 0.1)
		(priority 30063)
		(attr
			(teardrop
				(type padvia)
			)
		)
		(connect_pads yes
			(clearance 0)
		)
		(min_thickness 0.0254)
		(filled_areas_thickness no)
		(fill yes
			(thermal_gap 0.5)
			(thermal_bridge_width 0.5)
			(island_removal_mode 1)
			(island_area_min 10)
		)
		(polygon
			(pts
				(xy 145.335652 163.407264) (xy 145.277595 163.342385) (xy 145.237584 163.282904) (xy 145.199114 163.177939)
				(xy 145.189873 163.041643) (xy 145.186966 162.942859) (xy 145.171738 162.826111) (xy 144.749293 162.909293)
				(xy 144.666111 163.331738) (xy 144.828348 163.349046) (xy 144.881643 163.349873) (xy 144.971997 163.352904)
				(xy 145.058036 163.369259) (xy 145.147284 163.412365) (xy 145.247264 163.495652)
			)
		)
	)
	(zone
		(net 977)
		(net_name "/PCIe redriver/RX_EQ1")
		(layer "F.Cu")
		(name "$teardrop_padvia$")
		(hatch none 0.1)
		(priority 31907)
		(attr
			(teardrop
				(type padvia)
			)
		)
		(connect_pads yes
			(clearance 0)
		)
		(min_thickness 0.0254)
		(filled_areas_thickness no)
		(fill yes
			(thermal_gap 0.5)
			(thermal_bridge_width 0.5)
			(island_removal_mode 1)
			(island_area_min 10)
		)
		(polygon
			(pts
				(xy 190.175101 139.977745) (xy 190.148056 139.998045) (xy 190.123843 140.003327) (xy 190.084662 139.983875)
				(xy 190.042528 139.935363) (xy 190.007996 139.89353) (xy 189.967779 139.857824) (xy 189.842069 140.045612)
				(xy 189.967779 140.231986) (xy 190.072194 140.179409) (xy 190.093138 140.171897) (xy 190.171441 140.138514)
				(xy 190.263489 140.066133)
			)
		)
	)
	(zone
		(net 1)
		(net_name "GND")
		(layer "F.Cu")
		(name "$teardrop_padvia$")
		(hatch none 0.1)
		(priority 31240)
		(attr
			(teardrop
				(type padvia)
			)
		)
		(connect_pads yes
			(clearance 0)
		)
		(min_thickness 0.0254)
		(filled_areas_thickness no)
		(fill yes
			(thermal_gap 0.5)
			(thermal_bridge_width 0.5)
			(island_removal_mode 1)
			(island_area_min 10)
		)
		(polygon
			(pts
				(xy 190.925 151.874323) (xy 190.920263 151.965322) (xy 190.907104 152.032411) (xy 190.874583 152.119139)
				(xy 190.842355 152.199641) (xy 191.05 152.276) (xy 191.246458 152.172636) (xy 191.194657 152.089138)
				(xy 191.145166 152.003045) (xy 191.130386 151.94784) (xy 191.125 151.874323)
			)
		)
	)
	(zone
		(net 195)
		(net_name "/OCuLink/PCIe_{x4}.RX2-")
		(layer "F.Cu")
		(name "$teardrop_padvia$")
		(hatch none 0.1)
		(priority 31351)
		(attr
			(teardrop
				(type padvia)
			)
		)
		(connect_pads yes
			(clearance 0)
		)
		(min_thickness 0.0254)
		(filled_areas_thickness no)
		(fill yes
			(thermal_gap 0.5)
			(thermal_bridge_width 0.5)
			(island_removal_mode 1)
			(island_area_min 10)
		)
		(polygon
			(pts
				(xy 99.392496 159.5545) (xy 99.34571 159.549765) (xy 99.310258 159.536621) (xy 99.26206 159.491613)
				(xy 99.237884 159.453392) (xy 99.210514 159.410225) (xy 99.173852 159.368268) (xy 99.024 159.5315)
				(xy 99.04486 159.752177) (xy 99.145531 159.747548) (xy 99.228897 159.75098) (xy 99.230964 159.751105)
				(xy 99.392496 159.7565)
			)
		)
	)
	(zone
		(net 73)
		(net_name "+3V3_AON")
		(layer "F.Cu")
		(name "$teardrop_padvia$")
		(hatch none 0.1)
		(priority 30721)
		(attr
			(teardrop
				(type padvia)
			)
		)
		(connect_pads yes
			(clearance 0)
		)
		(min_thickness 0.0254)
		(filled_areas_thickness no)
		(fill yes
			(thermal_gap 0.5)
			(thermal_bridge_width 0.5)
			(island_removal_mode 1)
			(island_area_min 10)
		)
		(polygon
			(pts
				(xy 302.2395 105.45) (xy 302.244848 105.417909) (xy 302.262282 105.384743) (xy 302.288737 105.358583)
				(xy 302.327163 105.337804) (xy 302.36705 105.32705) (xy 302.175 104.809) (xy 301.98295 105.32705)
				(xy 302.028153 105.339446) (xy 302.062844 105.358095) (xy 302.105426 105.408896) (xy 302.1145 105.45)
			)
		)
	)
	(zone
		(net 531)
		(net_name "/Com Express 7 Interfaces/SD_CD")
		(layer "F.Cu")
		(name "$teardrop_padvia$")
		(hatch none 0.1)
		(priority 31655)
		(attr
			(teardrop
				(type padvia)
			)
		)
		(connect_pads yes
			(clearance 0)
		)
		(min_thickness 0.0254)
		(filled_areas_thickness no)
		(fill yes
			(thermal_gap 0.5)
			(thermal_bridge_width 0.5)
			(island_removal_mode 1)
			(island_area_min 10)
		)
		(polygon
			(pts
				(xy 113.473005 139.775383) (xy 113.543062 139.698911) (xy 113.587191 139.638166) (xy 113.613482 139.595443)
				(xy 113.681592 139.490491) (xy 113.500707 139.359293) (xy 113.283762 139.414613) (xy 113.317235 139.481244)
				(xy 113.359794 139.530538) (xy 113.392532 139.56774) (xy 113.413499 139.604463) (xy 113.41382 139.643338)
				(xy 113.384617 139.686995)
			)
		)
	)
	(zone
		(net 1)
		(net_name "GND")
		(layer "F.Cu")
		(hatch edge 0.5)
		(priority 45)
		(connect_pads yes
			(clearance 0.15)
		)
		(min_thickness 0.25)
		(filled_areas_thickness no)
		(fill yes
			(thermal_gap 0.5)
			(thermal_bridge_width 0.5)
		)
		(polygon
			(pts
				(xy 310.76 103.8) (xy 312.36 103.8) (xy 312.36 105.7) (xy 310.76 105.7)
			)
		)
	)
	(zone
		(net 264)
		(net_name "/Com Express 7 Interfaces/PCIe_{B2Bx4}.RX0+")
		(layer "F.Cu")
		(name "$teardrop_padvia$")
		(hatch none 0.1)
		(priority 30522)
		(attr
			(teardrop
				(type padvia)
			)
		)
		(connect_pads yes
			(clearance 0)
		)
		(min_thickness 0.0254)
		(filled_areas_thickness no)
		(fill yes
			(thermal_gap 0.5)
			(thermal_bridge_width 0.5)
			(island_removal_mode 1)
			(island_area_min 10)
		)
		(polygon
			(pts
				(xy 194.924 162.2) (xy 194.927537 162.214678) (xy 194.930808 162.244685) (xy 194.918857 162.255673)
				(xy 194.89 162.26) (xy 195.025 163.136) (xy 195.16 162.26) (xy 195.130796 162.255525) (xy 195.119003 162.244203)
				(xy 195.122463 162.214678) (xy 195.126 162.2)
			)
		)
	)
	(zone
		(net 1)
		(net_name "GND")
		(layer "F.Cu")
		(name "$teardrop_padvia$")
		(hatch none 0.1)
		(priority 30846)
		(attr
			(teardrop
				(type padvia)
			)
		)
		(connect_pads yes
			(clearance 0)
		)
		(min_thickness 0.0254)
		(filled_areas_thickness no)
		(fill yes
			(thermal_gap 0.5)
			(thermal_bridge_width 0.5)
			(island_removal_mode 1)
			(island_area_min 10)
		)
		(polygon
			(pts
				(xy 309.637 78.442002) (xy 309.683211 78.448212) (xy 309.73161 78.471679) (xy 309.759966 78.499586)
				(xy 309.783012 78.539812) (xy 309.798202 78.5938) (xy 310.076 78.342002) (xy 309.798202 78.090204)
				(xy 309.785069 78.139056) (xy 309.765665 78.176566) (xy 309.713055 78.223989) (xy 309.646554 78.241745)
				(xy 309.637 78.242002)
			)
		)
	)
	(zone
		(net 351)
		(net_name "Net-(J12D-LPC_AD2{slash}ESPI_IO_2)")
		(layer "F.Cu")
		(name "$teardrop_padvia$")
		(hatch none 0.1)
		(priority 30669)
		(attr
			(teardrop
				(type padvia)
			)
		)
		(connect_pads yes
			(clearance 0)
		)
		(min_thickness 0.0254)
		(filled_areas_thickness no)
		(fill yes
			(thermal_gap 0.5)
			(thermal_bridge_width 0.5)
			(island_removal_mode 1)
			(island_area_min 10)
		)
		(polygon
			(pts
				(xy 178.5875 164.07) (xy 178.598438 164.031177) (xy 178.620195 164.016067) (xy 178.66 164.01) (xy 178.525 163.134)
				(xy 178.39 164.01) (xy 178.425281 164.014517) (xy 178.446797 164.026138) (xy 178.461995 164.058961)
				(xy 178.4625 164.07)
			)
		)
	)
	(zone
		(net 1)
		(net_name "GND")
		(layer "F.Cu")
		(name "$teardrop_padvia$")
		(hatch none 0.1)
		(priority 30598)
		(attr
			(teardrop
				(type padvia)
			)
		)
		(connect_pads yes
			(clearance 0)
		)
		(min_thickness 0.0254)
		(filled_areas_thickness no)
		(fill yes
			(thermal_gap 0.5)
			(thermal_bridge_width 0.5)
			(island_removal_mode 1)
			(island_area_min 10)
		)
		(polygon
			(pts
				(xy 184.625 152.07) (xy 184.621667 152.055514) (xy 184.61881 152.02539) (xy 184.630964 152.014349)
				(xy 184.66 152.01) (xy 184.525 151.134) (xy 184.39 152.01) (xy 184.419334 152.014475) (xy 184.431358 152.025801)
				(xy 184.428333 152.055514) (xy 184.425 152.07)
			)
		)
	)
	(zone
		(net 587)
		(net_name "/M.2 key E/SUSCLK")
		(layer "F.Cu")
		(name "$teardrop_padvia$")
		(hatch none 0.1)
		(priority 30985)
		(attr
			(teardrop
				(type padvia)
			)
		)
		(connect_pads yes
			(clearance 0)
		)
		(min_thickness 0.0254)
		(filled_areas_thickness no)
		(fill yes
			(thermal_gap 0.5)
			(thermal_bridge_width 0.5)
			(island_removal_mode 1)
			(island_area_min 10)
		)
		(polygon
			(pts
				(xy 303.388 84.4275) (xy 303.325134 84.407531) (xy 303.293156 84.381079) (xy 303.264642 84.343668)
				(xy 303.242118 84.296473) (xy 303.226907 84.238833) (xy 303.226798 84.238202) (xy 302.949 84.49)
				(xy 303.226798 84.741798) (xy 303.241095 84.686365) (xy 303.262175 84.64048) (xy 303.28954 84.602799)
				(xy 303.320448 84.575566) (xy 303.353735 84.558528) (xy 303.386566 84.552511) (xy 303.388 84.5525)
			)
		)
	)
	(zone
		(net 192)
		(net_name "/OCuLink/PCIe_{REF0}.CK+")
		(layer "F.Cu")
		(name "$teardrop_padvia$")
		(hatch none 0.1)
		(priority 31372)
		(attr
			(teardrop
				(type padvia)
			)
		)
		(connect_pads yes
			(clearance 0)
		)
		(min_thickness 0.0254)
		(filled_areas_thickness no)
		(fill yes
			(thermal_gap 0.5)
			(thermal_bridge_width 0.5)
			(island_removal_mode 1)
			(island_area_min 10)
		)
		(polygon
			(pts
				(xy 150.557504 114.0705) (xy 150.60429 114.075235) (xy 150.639742 114.088379) (xy 150.687939 114.133387)
				(xy 150.712116 114.171608) (xy 150.739485 114.214773) (xy 150.776147 114.256731) (xy 150.926 114.0935)
				(xy 150.90514 113.872823) (xy 150.804466 113.877452) (xy 150.721096 113.874019) (xy 150.719035 113.873895)
				(xy 150.557504 113.8685)
			)
		)
	)
	(zone
		(net 1)
		(net_name "GND")
		(layer "F.Cu")
		(name "$teardrop_padvia$")
		(hatch none 0.1)
		(priority 31186)
		(attr
			(teardrop
				(type padvia)
			)
		)
		(connect_pads yes
			(clearance 0)
		)
		(min_thickness 0.0254)
		(filled_areas_thickness no)
		(fill yes
			(thermal_gap 0.5)
			(thermal_bridge_width 0.5)
			(island_removal_mode 1)
			(island_area_min 10)
		)
		(polygon
			(pts
				(xy 191.125 162.321677) (xy 191.12972 162.252353) (xy 191.142756 162.199449) (xy 191.194658 162.10686)
				(xy 191.246458 162.023363) (xy 191.05 161.92) (xy 190.842355 161.996358) (xy 190.874583 162.076861)
				(xy 190.910965 162.178318) (xy 190.925 162.321677)
			)
		)
	)
	(zone
		(net 357)
		(net_name "/Com Express 7 MGMT/SMBus.SCL")
		(layer "F.Cu")
		(name "$teardrop_padvia$")
		(hatch none 0.1)
		(priority 31607)
		(attr
			(teardrop
				(type padvia)
			)
		)
		(connect_pads yes
			(clearance 0)
		)
		(min_thickness 0.0254)
		(filled_areas_thickness no)
		(fill yes
			(thermal_gap 0.5)
			(thermal_bridge_width 0.5)
			(island_removal_mode 1)
			(island_area_min 10)
		)
		(polygon
			(pts
				(xy 127.8875 151.225677) (xy 127.892253 151.164547) (xy 127.905521 151.118447) (xy 127.950771 151.051755)
				(xy 127.96863 151.032657) (xy 128.037081 150.950003) (xy 127.85 150.824) (xy 127.642355 150.900358)
				(xy 127.700666 151.01542) (xy 127.744145 151.099531) (xy 127.757549 151.153939) (xy 127.7625 151.225677)
			)
		)
	)
	(zone
		(net 1)
		(net_name "GND")
		(layer "F.Cu")
		(name "$teardrop_padvia$")
		(hatch none 0.1)
		(priority 30977)
		(attr
			(teardrop
				(type padvia)
			)
		)
		(connect_pads yes
			(clearance 0)
		)
		(min_thickness 0.0254)
		(filled_areas_thickness no)
		(fill yes
			(thermal_gap 0.5)
			(thermal_bridge_width 0.5)
			(island_removal_mode 1)
			(island_area_min 10)
		)
		(polygon
			(pts
				(xy 112.838 144.7775) (xy 112.775134 144.757531) (xy 112.743156 144.731079) (xy 112.714642 144.693668)
				(xy 112.692118 144.646473) (xy 112.676907 144.588833) (xy 112.676798 144.588202) (xy 112.399 144.84)
				(xy 112.676798 145.091798) (xy 112.691095 145.036365) (xy 112.712175 144.99048) (xy 112.73954 144.952799)
				(xy 112.770448 144.925566) (xy 112.803735 144.908528) (xy 112.836566 144.902511) (xy 112.838 144.9025)
			)
		)
	)
	(zone
		(net 1)
		(net_name "GND")
		(layer "F.Cu")
		(name "$teardrop_padvia$")
		(hatch none 0.1)
		(priority 31213)
		(attr
			(teardrop
				(type padvia)
			)
		)
		(connect_pads yes
			(clearance 0)
		)
		(min_thickness 0.0254)
		(filled_areas_thickness no)
		(fill yes
			(thermal_gap 0.5)
			(thermal_bridge_width 0.5)
			(island_removal_mode 1)
			(island_area_min 10)
		)
		(polygon
			(pts
				(xy 221.925 151.948323) (xy 221.92028 152.017646) (xy 221.907244 152.070549) (xy 221.855344 152.163135)
				(xy 221.803541 152.246636) (xy 222 152.35) (xy 222.207644 152.273641) (xy 222.175418 152.193142)
				(xy 222.139035 152.091683) (xy 222.125 151.948323)
			)
		)
	)
	(zone
		(net 329)
		(net_name "/Com Express 7 Interfaces/PCIe_{B2Ax4}.TX2-")
		(layer "F.Cu")
		(name "$teardrop_padvia$")
		(hatch none 0.1)
		(priority 30380)
		(attr
			(teardrop
				(type padvia)
			)
		)
		(connect_pads yes
			(clearance 0)
		)
		(min_thickness 0.0254)
		(filled_areas_thickness no)
		(fill yes
			(thermal_gap 0.5)
			(thermal_bridge_width 0.5)
			(island_removal_mode 1)
			(island_area_min 10)
		)
		(polygon
			(pts
				(xy 292.0425 73.2) (xy 292.053603 73.355527) (xy 292.068217 73.559681) (xy 292.06518 73.679806)
				(xy 292.049 73.814533) (xy 292.199 74.036) (xy 292.28278 73.26) (xy 292.252191 73.255523) (xy 292.239299 73.244182)
				(xy 292.241476 73.214169) (xy 292.2445 73.2)
			)
		)
	)
	(zone
		(net 557)
		(net_name "Net-(U5-A0)")
		(layer "F.Cu")
		(name "$teardrop_padvia$")
		(hatch none 0.1)
		(priority 30989)
		(attr
			(teardrop
				(type padvia)
			)
		)
		(connect_pads yes
			(clearance 0)
		)
		(min_thickness 0.0254)
		(filled_areas_thickness no)
		(fill yes
			(thermal_gap 0.5)
			(thermal_bridge_width 0.5)
			(island_removal_mode 1)
			(island_area_min 10)
		)
		(polygon
			(pts
				(xy 162.5575 159.922) (xy 162.537531 159.984866) (xy 162.511079 160.016844) (xy 162.473668 160.045358)
				(xy 162.426473 160.067882) (xy 162.368833 160.083093) (xy 162.368202 160.083202) (xy 162.62 160.361)
				(xy 162.871798 160.083202) (xy 162.816365 160.068905) (xy 162.77048 160.047825) (xy 162.732799 160.02046)
				(xy 162.705566 159.989552) (xy 162.688528 159.956265) (xy 162.682511 159.923434) (xy 162.6825 159.922)
			)
		)
	)
	(zone
		(net 759)
		(net_name "Net-(U45B-LS_OK_{OUT_B})")
		(layer "F.Cu")
		(name "$teardrop_padvia$")
		(hatch none 0.1)
		(priority 31730)
		(attr
			(teardrop
				(type padvia)
			)
		)
		(connect_pads yes
			(clearance 0)
		)
		(min_thickness 0.0254)
		(filled_areas_thickness no)
		(fill yes
			(thermal_gap 0.5)
			(thermal_bridge_width 0.5)
			(island_removal_mode 1)
			(island_area_min 10)
		)
		(polygon
			(pts
				(xy 129.0275 130.109323) (xy 129.022682 130.178763) (xy 129.00896 130.230087) (xy 128.962245 130.305628)
				(xy 128.952702 130.317768) (xy 128.902919 130.384997) (xy 129.09 130.511) (xy 129.277081 130.384997)
				(xy 129.227299 130.317769) (xy 129.172894 130.234603) (xy 129.15781 130.181748) (xy 129.1525 130.109323)
			)
		)
	)
	(zone
		(net 321)
		(net_name "/Com Express 7 Interfaces/SDIO.DAT0")
		(layer "F.Cu")
		(name "$teardrop_padvia$")
		(hatch none 0.1)
		(priority 30627)
		(attr
			(teardrop
				(type padvia)
			)
		)
		(connect_pads yes
			(clearance 0)
		)
		(min_thickness 0.0254)
		(filled_areas_thickness no)
		(fill yes
			(thermal_gap 0.5)
			(thermal_bridge_width 0.5)
			(island_removal_mode 1)
			(island_area_min 10)
		)
		(polygon
			(pts
				(xy 202.434 167.75) (xy 202.435718 167.762416) (xy 202.434894 167.793794) (xy 202.420838 167.80541)
				(xy 202.39 167.81) (xy 202.525 168.686) (xy 202.66 167.81) (xy 202.629435 167.805519) (xy 202.615302 167.794149)
				(xy 202.614282 167.762416) (xy 202.616 167.75)
			)
		)
	)
	(zone
		(net 721)
		(net_name "Net-(U43C-REFCLK1-)")
		(layer "F.Cu")
		(name "$teardrop_padvia$")
		(hatch none 0.1)
		(priority 31898)
		(attr
			(teardrop
				(type padvia)
			)
		)
		(connect_pads yes
			(clearance 0)
		)
		(min_thickness 0.0254)
		(filled_areas_thickness no)
		(fill yes
			(thermal_gap 0.5)
			(thermal_bridge_width 0.5)
			(island_removal_mode 1)
			(island_area_min 10)
		)
		(polygon
			(pts
				(xy 144.53164 130.089972) (xy 144.480742 130.147349) (xy 144.448383 130.196778) (xy 144.416862 130.267692)
				(xy 144.392327 130.325954) (xy 144.352919 130.394997) (xy 144.539293 130.520707) (xy 144.727081 130.394997)
				(xy 144.658191 130.322514) (xy 144.621966 130.288539) (xy 144.59764 130.254828) (xy 144.594048 130.218922)
				(xy 144.620028 130.17836)
			)
		)
	)
	(zone
		(net 570)
		(net_name "Net-(U6-~{RESET})")
		(layer "F.Cu")
		(name "$teardrop_padvia$")
		(hatch none 0.1)
		(priority 31630)
		(attr
			(teardrop
				(type padvia)
			)
		)
		(connect_pads yes
			(clearance 0)
		)
		(min_thickness 0.0254)
		(filled_areas_thickness no)
		(fill yes
			(thermal_gap 0.5)
			(thermal_bridge_width 0.5)
			(island_removal_mode 1)
			(island_area_min 10)
		)
		(polygon
			(pts
				(xy 114.242498 78.205) (xy 114.248002 78.178061) (xy 114.266532 78.152675) (xy 114.293139 78.136439)
				(xy 114.331864 78.126703) (xy 114.36084 78.125) (xy 114.184999 77.724001) (xy 114.000821 78.125)
				(xy 114.046012 78.129611) (xy 114.078732 78.141889) (xy 114.112864 78.180027) (xy 114.117499 78.204999)
			)
		)
	)
	(zone
		(net 1)
		(net_name "GND")
		(layer "F.Cu")
		(name "$teardrop_padvia$")
		(hatch none 0.1)
		(priority 31757)
		(attr
			(teardrop
				(type padvia)
			)
		)
		(connect_pads yes
			(clearance 0)
		)
		(min_thickness 0.0254)
		(filled_areas_thickness no)
		(fill yes
			(thermal_gap 0.5)
			(thermal_bridge_width 0.5)
			(island_removal_mode 1)
			(island_area_min 10)
		)
		(polygon
			(pts
				(xy 113.999323 147.4235) (xy 114.068764 147.428318) (xy 114.120088 147.44204) (xy 114.195629 147.488755)
				(xy 114.207769 147.498299) (xy 114.274997 147.548081) (xy 114.401 147.361) (xy 114.274997 147.173919)
				(xy 114.207768 147.223702) (xy 114.124602 147.278106) (xy 114.071748 147.29319) (xy 113.999323 147.2985)
			)
		)
	)
	(zone
		(net 372)
		(net_name "/Com Express 7 MGMT/I2C.SDA")
		(layer "F.Cu")
		(name "$teardrop_padvia$")
		(hatch none 0.1)
		(priority 31623)
		(attr
			(teardrop
				(type padvia)
			)
		)
		(connect_pads yes
			(clearance 0)
		)
		(min_thickness 0.0254)
		(filled_areas_thickness no)
		(fill yes
			(thermal_gap 0.5)
			(thermal_bridge_width 0.5)
			(island_removal_mode 1)
			(island_area_min 10)
		)
		(polygon
			(pts
				(xy 192.729082 161.984306) (xy 192.765918 161.954183) (xy 192.800457 161.938356) (xy 192.86509 161.937027)
				(xy 192.915282 161.950668) (xy 192.975433 161.966766) (xy 193.044808 161.970677) (xy 193.025707 161.749293)
				(xy 192.837919 161.624997) (xy 192.782211 161.714276) (xy 192.729585 161.795803) (xy 192.640694 161.895918)
			)
		)
	)
	(zone
		(net 989)
		(net_name "Net-(Q14-B)")
		(layer "F.Cu")
		(name "$teardrop_padvia$")
		(hatch none 0.1)
		(priority 30192)
		(attr
			(teardrop
				(type padvia)
			)
		)
		(connect_pads yes
			(clearance 0)
		)
		(min_thickness 0.0254)
		(filled_areas_thickness no)
		(fill yes
			(thermal_gap 0.5)
			(thermal_bridge_width 0.5)
			(island_removal_mode 1)
			(island_area_min 10)
		)
		(polygon
			(pts
				(xy 198.15 82.47) (xy 198.15568 82.43137) (xy 198.17544 82.392114) (xy 198.202329 82.365183) (xy 198.241453 82.343287)
				(xy 198.319768 82.325558) (xy 198.049 81.849) (xy 197.779768 82.326585) (xy 197.834475 82.336031)
				(xy 197.876785 82.352559) (xy 197.929809 82.400107) (xy 197.949686 82.46087) (xy 197.95 82.47)
			)
		)
	)
	(zone
		(net 3)
		(net_name "/M.2 key E/WIFI_BT_USB_D_P")
		(layer "F.Cu")
		(name "$teardrop_padvia$")
		(hatch none 0.1)
		(priority 30410)
		(attr
			(teardrop
				(type padvia)
			)
		)
		(connect_pads yes
			(clearance 0)
		)
		(min_thickness 0.0254)
		(filled_areas_thickness no)
		(fill yes
			(thermal_gap 0.5)
			(thermal_bridge_width 0.5)
			(island_removal_mode 1)
			(island_area_min 10)
		)
		(polygon
			(pts
				(xy 154.4085 71.526) (xy 154.396393 71.527541) (xy 154.364789 71.526011) (xy 154.353112 71.511102)
				(xy 154.3485 71.478846) (xy 153.5725 71.5585) (xy 153.776657 71.7085) (xy 154.006494 71.689223)
				(xy 154.252283 71.701595) (xy 154.4085 71.711)
			)
		)
	)
	(zone
		(net 365)
		(net_name "/Com Express 7 MGMT/PWR_OK")
		(layer "F.Cu")
		(name "$teardrop_padvia$")
		(hatch none 0.1)
		(priority 30322)
		(attr
			(teardrop
				(type padvia)
			)
		)
		(connect_pads yes
			(clearance 0)
		)
		(min_thickness 0.0254)
		(filled_areas_thickness no)
		(fill yes
			(thermal_gap 0.5)
			(thermal_bridge_width 0.5)
			(island_removal_mode 1)
			(island_area_min 10)
		)
		(polygon
			(pts
				(xy 301.229 129.2015) (xy 301.280931 129.221545) (xy 301.304051 129.247406) (xy 301.322567 129.283879)
				(xy 301.339 129.3865) (xy 301.84 129.139) (xy 301.339 128.8915) (xy 301.334299 128.949882) (xy 301.321394 128.99718)
				(xy 301.302084 129.033425) (xy 301.278162 129.058668) (xy 301.229 129.0765)
			)
		)
	)
	(zone
		(net 1)
		(net_name "GND")
		(layer "F.Cu")
		(name "$teardrop_padvia$")
		(hatch none 0.1)
		(priority 30053)
		(attr
			(teardrop
				(type padvia)
			)
		)
		(connect_pads yes
			(clearance 0)
		)
		(min_thickness 0.0254)
		(filled_areas_thickness no)
		(fill yes
			(thermal_gap 0.5)
			(thermal_bridge_width 0.5)
			(island_removal_mode 1)
			(island_area_min 10)
		)
		(polygon
			(pts
				(xy 220.609248 160.297116) (xy 220.539222 160.217797) (xy 220.473573 160.115379) (xy 220.439685 160.038515)
				(xy 220.414682 159.951243) (xy 220.4 159.790883) (xy 219.999293 159.899293) (xy 219.990883 160.4)
				(xy 220.058184 160.386395) (xy 220.120048 160.383144) (xy 220.233408 160.403422) (xy 220.334192 160.455781)
				(xy 220.397116 160.509248)
			)
		)
	)
	(zone
		(net 291)
		(net_name "/2xUSB3.0+RJ45/~{GBE0_LINK}")
		(layer "F.Cu")
		(name "$teardrop_padvia$")
		(hatch none 0.1)
		(priority 31870)
		(attr
			(teardrop
				(type padvia)
			)
		)
		(connect_pads yes
			(clearance 0)
		)
		(min_thickness 0.0254)
		(filled_areas_thickness no)
		(fill yes
			(thermal_gap 0.5)
			(thermal_bridge_width 0.5)
			(island_removal_mode 1)
			(island_area_min 10)
		)
		(polygon
			(pts
				(xy 144.960873 149.827515) (xy 145.013382 149.781819) (xy 145.059376 149.755231) (xy 145.145824 149.734847)
				(xy 145.16116 149.733011) (xy 145.243895 149.720677) (xy 145.200707 149.499293) (xy 144.979323 149.456105)
				(xy 144.966988 149.538841) (xy 144.946651 149.636119) (xy 144.919943 149.684159) (xy 144.872485 149.739127)
			)
		)
	)
	(zone
		(net 1)
		(net_name "GND")
		(layer "F.Cu")
		(name "$teardrop_padvia$")
		(hatch none 0.1)
		(priority 31518)
		(attr
			(teardrop
				(type padvia)
			)
		)
		(connect_pads yes
			(clearance 0)
		)
		(min_thickness 0.0254)
		(filled_areas_thickness no)
		(fill yes
			(thermal_gap 0.5)
			(thermal_bridge_width 0.5)
			(island_removal_mode 1)
			(island_area_min 10)
		)
		(polygon
			(pts
				(xy 220.425 169.571811) (xy 220.429429 169.659924) (xy 220.440434 169.726159) (xy 220.453216 169.776953)
				(xy 220.479323 169.917287) (xy 220.7 169.901) (xy 220.825003 169.712919) (xy 220.754706 169.68351)
				(xy 220.731837 169.677712) (xy 220.690896 169.666406) (xy 220.656865 169.649331) (xy 220.633611 169.619971)
				(xy 220.625 169.571811)
			)
		)
	)
	(zone
		(net 127)
		(net_name "/USB-C console/FTDI_LED_RX")
		(layer "F.Cu")
		(name "$teardrop_padvia$")
		(hatch none 0.1)
		(priority 31842)
		(attr
			(teardrop
				(type padvia)
			)
		)
		(connect_pads yes
			(clearance 0)
		)
		(min_thickness 0.0254)
		(filled_areas_thickness no)
		(fill yes
			(thermal_gap 0.5)
			(thermal_bridge_width 0.5)
			(island_removal_mode 1)
			(island_area_min 10)
		)
		(polygon
			(pts
				(xy 115.289127 78.532485) (xy 115.236618 78.578181) (xy 115.190623 78.604768) (xy 115.104174 78.625152)
				(xy 115.088841 78.626988) (xy 115.006105 78.639323) (xy 115.049293 78.860707) (xy 115.270677 78.903895)
				(xy 115.283011 78.82116) (xy 115.303349 78.723881) (xy 115.330057 78.675841) (xy 115.377515 78.620873)
			)
		)
	)
	(zone
		(net 2)
		(net_name "+3V3")
		(layer "F.Cu")
		(name "$teardrop_padvia$")
		(hatch none 0.1)
		(priority 30309)
		(attr
			(teardrop
				(type padvia)
			)
		)
		(connect_pads yes
			(clearance 0)
		)
		(min_thickness 0.0254)
		(filled_areas_thickness no)
		(fill yes
			(thermal_gap 0.5)
			(thermal_bridge_width 0.5)
			(island_removal_mode 1)
			(island_area_min 10)
		)
		(polygon
			(pts
				(xy 115.838 149.63) (xy 115.787028 149.650463) (xy 115.749217 149.669257) (xy 115.711873 149.677794)
				(xy 115.679423 149.663674) (xy 115.656292 149.6145) (xy 115.399 149.88) (xy 115.656292 150.1455)
				(xy 115.669784 150.109356) (xy 115.687742 150.089384) (xy 115.727141 150.083731) (xy 115.787028 150.109537)
				(xy 115.838 150.13)
			)
		)
	)
	(zone
		(net 726)
		(net_name "/2xSFP+/KR to SFI #1/~{TRST}")
		(layer "F.Cu")
		(name "$teardrop_padvia$")
		(hatch none 0.1)
		(priority 31711)
		(attr
			(teardrop
				(type padvia)
			)
		)
		(connect_pads yes
			(clearance 0)
		)
		(min_thickness 0.0254)
		(filled_areas_thickness no)
		(fill yes
			(thermal_gap 0.5)
			(thermal_bridge_width 0.5)
			(island_removal_mode 1)
			(island_area_min 10)
		)
		(polygon
			(pts
				(xy 151.0875 130.109323) (xy 151.082682 130.178763) (xy 151.06896 130.230087) (xy 151.022245 130.305628)
				(xy 151.012702 130.317768) (xy 150.962919 130.384997) (xy 151.15 130.511) (xy 151.337081 130.384997)
				(xy 151.287299 130.317769) (xy 151.232894 130.234603) (xy 151.21781 130.181748) (xy 151.2125 130.109323)
			)
		)
	)
	(zone
		(net 985)
		(net_name "Net-(D33-C)")
		(layer "F.Cu")
		(name "$teardrop_padvia$")
		(hatch none 0.1)
		(priority 30150)
		(attr
			(teardrop
				(type padvia)
			)
		)
		(connect_pads yes
			(clearance 0)
		)
		(min_thickness 0.0254)
		(filled_areas_thickness no)
		(fill yes
			(thermal_gap 0.5)
			(thermal_bridge_width 0.5)
			(island_removal_mode 1)
			(island_area_min 10)
		)
		(polygon
			(pts
				(xy 188.80861 76.062163) (xy 188.81367 76.028644) (xy 188.829091 75.995738) (xy 188.854873 75.965425)
				(xy 188.891483 75.938919) (xy 188.938658 75.918016) (xy 188.997093 75.90393) (xy 189.06861 75.898184)
				(xy 188.70861 75.501163) (xy 188.34861 75.898184) (xy 188.418681 75.903704) (xy 188.477217 75.917567)
				(xy 188.524564 75.938253) (xy 188.561037 75.964231) (xy 188.58712 75.9942) (xy 188.602852 76.026426)
				(xy 188.60861 76.062163)
			)
		)
	)
	(zone
		(net 625)
		(net_name "/PCIe redriver/TX_EQ2")
		(layer "F.Cu")
		(name "$teardrop_padvia$")
		(hatch none 0.1)
		(priority 31659)
		(attr
			(teardrop
				(type padvia)
			)
		)
		(connect_pads yes
			(clearance 0)
		)
		(min_thickness 0.0254)
		(filled_areas_thickness no)
		(fill yes
			(thermal_gap 0.5)
			(thermal_bridge_width 0.5)
			(island_removal_mode 1)
			(island_area_min 10)
		)
		(polygon
			(pts
				(xy 112.573005 143.335383) (xy 112.603148 143.31199) (xy 112.63072 143.303384) (xy 112.677333 143.316967)
				(xy 112.729461 143.360205) (xy 112.782091 143.405207) (xy 112.845386 143.436237) (xy 112.900707 143.219293)
				(xy 112.769508 143.038407) (xy 112.664558 143.106516) (xy 112.584509 143.158648) (xy 112.484617 143.246995)
			)
		)
	)
	(zone
		(net 1)
		(net_name "GND")
		(layer "F.Cu")
		(name "$teardrop_padvia$")
		(hatch none 0.1)
		(priority 31094)
		(attr
			(teardrop
				(type padvia)
			)
		)
		(connect_pads yes
			(clearance 0)
		)
		(min_thickness 0.0254)
		(filled_areas_thickness no)
		(fill yes
			(thermal_gap 0.5)
			(thermal_bridge_width 0.5)
			(island_removal_mode 1)
			(island_area_min 10)
		)
		(polygon
			(pts
				(xy 306.5875 154.817) (xy 306.567727 154.876412) (xy 306.504453 154.932496) (xy 306.455828 154.954198)
				(xy 306.396469 154.968872) (xy 306.3845 154.970652) (xy 306.65 155.231) (xy 306.9155 154.970652)
				(xy 306.855362 154.957803) (xy 306.805478 154.937869) (xy 306.765358 154.911944) (xy 306.736345 154.882124)
				(xy 306.718854 154.850706) (xy 306.712521 154.818895) (xy 306.7125 154.817)
			)
		)
	)
	(zone
		(net 1)
		(net_name "GND")
		(layer "F.Cu")
		(name "$teardrop_padvia$")
		(hatch none 0.1)
		(priority 30542)
		(attr
			(teardrop
				(type padvia)
			)
		)
		(connect_pads yes
			(clearance 0)
		)
		(min_thickness 0.0254)
		(filled_areas_thickness no)
		(fill yes
			(thermal_gap 0.5)
			(thermal_bridge_width 0.5)
			(island_removal_mode 1)
			(island_area_min 10)
		)
		(polygon
			(pts
				(xy 200.925 162.2) (xy 200.928333 162.214486) (xy 200.93119 162.24461) (xy 200.919036 162.255651)
				(xy 200.89 162.26) (xy 201.025 163.136) (xy 201.16 162.26) (xy 201.130666 162.255525) (xy 201.118642 162.244199)
				(xy 201.121667 162.214486) (xy 201.125 162.2)
			)
		)
	)
	(zone
		(net 68)
		(net_name "Net-(U19-BST)")
		(layer "F.Cu")
		(name "$teardrop_padvia$")
		(hatch none 0.1)
		(priority 30920)
		(attr
			(teardrop
				(type padvia)
			)
		)
		(connect_pads yes
			(clearance 0)
		)
		(min_thickness 0.0254)
		(filled_areas_thickness no)
		(fill yes
			(thermal_gap 0.5)
			(thermal_bridge_width 0.5)
			(island_removal_mode 1)
			(island_area_min 10)
		)
		(polygon
			(pts
				(xy 313.676999 105.714499) (xy 313.740197 105.734503) (xy 313.772331 105.760961) (xy 313.800953 105.79841)
				(xy 313.823207 105.844981) (xy 313.838201 105.901797) (xy 314.115999 105.649999) (xy 313.838201 105.398201)
				(xy 313.823868 105.454282) (xy 313.802741 105.500725) (xy 313.775385 105.538778) (xy 313.744467 105.566286)
				(xy 313.71131 105.583413) (xy 313.678514 105.589486) (xy 313.676999 105.589499)
			)
		)
	)
	(zone
		(net 130)
		(net_name "Net-(D17-C_{G})")
		(layer "F.Cu")
		(name "$teardrop_padvia$")
		(hatch none 0.1)
		(priority 30042)
		(attr
			(teardrop
				(type padvia)
			)
		)
		(connect_pads yes
			(clearance 0)
		)
		(min_thickness 0.0254)
		(filled_areas_thickness no)
		(fill yes
			(thermal_gap 0.5)
			(thermal_bridge_width 0.5)
			(island_removal_mode 1)
			(island_area_min 10)
		)
		(polygon
			(pts
				(xy 100.93 76.3725) (xy 100.996119 76.391662) (xy 101.058575 76.451682) (xy 101.113056 76.561369)
				(xy 101.14619 76.722166) (xy 101.15 76.805) (xy 101.701 76.31) (xy 101.15 75.815) (xy 101.145167 75.908055)
				(xy 101.131336 75.993163) (xy 101.109363 76.069111) (xy 101.080322 76.133751) (xy 101.047847 76.182298)
				(xy 101.010956 76.218314) (xy 100.975921 76.23842) (xy 100.938706 76.247181) (xy 100.93 76.2475)
			)
		)
	)
	(zone
		(net 700)
		(net_name "/USB-C console/FTDI_TX")
		(layer "F.Cu")
		(name "$teardrop_padvia$")
		(hatch none 0.1)
		(priority 30385)
		(attr
			(teardrop
				(type padvia)
			)
		)
		(connect_pads yes
			(clearance 0)
		)
		(min_thickness 0.0254)
		(filled_areas_thickness no)
		(fill yes
			(thermal_gap 0.5)
			(thermal_bridge_width 0.5)
			(island_removal_mode 1)
			(island_area_min 10)
		)
		(polygon
			(pts
				(xy 119.990271 74.988658) (xy 119.986061 75.00753) (xy 119.971333 75.022382) (xy 119.901388 75.0459)
				(xy 119.867289 75.052289) (xy 120.038707 75.758707) (xy 120.208711 75.052289) (xy 120.145112 75.0238)
				(xy 120.097859 74.965639) (xy 120.078658 74.900271)
			)
		)
	)
	(zone
		(net 700)
		(net_name "/USB-C console/FTDI_TX")
		(layer "F.Cu")
		(name "$teardrop_padvia$")
		(hatch none 0.1)
		(priority 30112)
		(attr
			(teardrop
				(type padvia)
			)
		)
		(connect_pads yes
			(clearance 0)
		)
		(min_thickness 0.0254)
		(filled_areas_thickness no)
		(fill yes
			(thermal_gap 0.5)
			(thermal_bridge_width 0.5)
			(island_removal_mode 1)
			(island_area_min 10)
		)
		(polygon
			(pts
				(xy 118.3125 75.377794) (xy 118.317315 75.295733) (xy 118.331019 75.230388) (xy 118.377576 75.13712)
				(xy 118.445787 75.058657) (xy 118.501942 74.997158) (xy 118.561801 74.918339) (xy 118.25 74.709)
				(xy 117.938199 74.918339) (xy 118.035219 75.038517) (xy 118.054214 75.058658) (xy 118.107366 75.117541)
				(xy 118.149591 75.181624) (xy 118.177449 75.264008) (xy 118.1875 75.377794)
			)
		)
	)
	(zone
		(net 987)
		(net_name "Net-(Q13-B)")
		(layer "F.Cu")
		(name "$teardrop_padvia$")
		(hatch none 0.1)
		(priority 30187)
		(attr
			(teardrop
				(type padvia)
			)
		)
		(connect_pads yes
			(clearance 0)
		)
		(min_thickness 0.0254)
		(filled_areas_thickness no)
		(fill yes
			(thermal_gap 0.5)
			(thermal_bridge_width 0.5)
			(island_removal_mode 1)
			(island_area_min 10)
		)
		(polygon
			(pts
				(xy 201.599 82.47) (xy 201.604675 82.431486) (xy 201.624403 82.392381) (xy 201.651281 82.365531)
				(xy 201.690389 82.343718) (xy 201.769 82.326072) (xy 201.499 81.849) (xy 201.229 82.326072) (xy 201.283606 82.335617)
				(xy 201.325842 82.352225) (xy 201.378807 82.399911) (xy 201.398684 82.460814) (xy 201.399 82.47)
			)
		)
	)
	(zone
		(net 292)
		(net_name "/2xUSB3.0+RJ45/GbE.MDI1-")
		(layer "F.Cu")
		(name "$teardrop_padvia$")
		(hatch none 0.1)
		(priority 31574)
		(attr
			(teardrop
				(type padvia)
			)
		)
		(connect_pads yes
			(clearance 0)
		)
		(min_thickness 0.0254)
		(filled_areas_thickness no)
		(fill yes
			(thermal_gap 0.5)
			(thermal_bridge_width 0.5)
			(island_removal_mode 1)
			(island_area_min 10)
		)
		(polygon
			(pts
				(xy 135.41204 103.065975) (xy 135.38674 103.045431) (xy 135.340765 103.0048) (xy 135.324885 102.978002)
				(xy 135.32 102.945267) (xy 134.834293 102.919293) (xy 134.852196 103.085) (xy 135.050579 103.086385)
				(xy 135.198309 103.110221) (xy 135.251952 103.132309) (xy 135.296271 103.162914) (xy 135.305975 103.17204)
			)
		)
	)
	(zone
		(net 942)
		(net_name "/2xUSB3.0+RJ45/EN_2")
		(layer "F.Cu")
		(name "$teardrop_padvia$")
		(hatch none 0.1)
		(priority 31061)
		(attr
			(teardrop
				(type padvia)
			)
		)
		(connect_pads yes
			(clearance 0)
		)
		(min_thickness 0.0254)
		(filled_areas_thickness no)
		(fill yes
			(thermal_gap 0.5)
			(thermal_bridge_width 0.5)
			(island_removal_mode 1)
			(island_area_min 10)
		)
		(polygon
			(pts
				(xy 122.943 89.8975) (xy 122.883588 89.877727) (xy 122.827503 89.814453) (xy 122.805801 89.765828)
				(xy 122.791127 89.706468) (xy 122.789347 89.6945) (xy 122.529 89.96) (xy 122.789347 90.2255) (xy 122.802197 90.165361)
				(xy 122.822131 90.115477) (xy 122.848056 90.075358) (xy 122.877876 90.046345) (xy 122.909294 90.028854)
				(xy 122.941105 90.022521) (xy 122.943 90.0225)
			)
		)
	)
	(zone
		(net 321)
		(net_name "/Com Express 7 Interfaces/SDIO.DAT0")
		(layer "F.Cu")
		(name "$teardrop_padvia$")
		(hatch none 0.1)
		(priority 30048)
		(attr
			(teardrop
				(type padvia)
			)
		)
		(connect_pads yes
			(clearance 0)
		)
		(min_thickness 0.0254)
		(filled_areas_thickness no)
		(fill yes
			(thermal_gap 0.5)
			(thermal_bridge_width 0.5)
			(island_removal_mode 1)
			(island_area_min 10)
		)
		(polygon
			(pts
				(xy 110.595 132.319) (xy 110.563366 132.313903) (xy 110.532489 132.298222) (xy 110.505162 132.272417)
				(xy 110.482138 132.235622) (xy 110.465474 132.188468) (xy 110.456279 132.129788) (xy 110.455 132.095)
				(xy 109.504 132.41) (xy 110.455 132.725) (xy 110.459723 132.660141) (xy 110.472784 132.607088) (xy 110.492459 132.565444)
				(xy 110.517125 132.534553) (xy 110.545573 132.513687) (xy 110.575742 132.502878) (xy 110.595 132.501)
			)
		)
	)
	(zone
		(net 2)
		(net_name "+3V3")
		(layer "F.Cu")
		(name "$teardrop_padvia$")
		(hatch none 0.1)
		(priority 30932)
		(attr
			(teardrop
				(type padvia)
			)
		)
		(connect_pads yes
			(clearance 0)
		)
		(min_thickness 0.0254)
		(filled_areas_thickness no)
		(fill yes
			(thermal_gap 0.5)
			(thermal_bridge_width 0.5)
			(island_removal_mode 1)
			(island_area_min 10)
		)
		(polygon
			(pts
				(xy 113.3175 148.422) (xy 113.297531 148.484866) (xy 113.271079 148.516844) (xy 113.233668 148.545358)
				(xy 113.186473 148.567882) (xy 113.128833 148.583093) (xy 113.128202 148.583202) (xy 113.38 148.861)
				(xy 113.631798 148.583202) (xy 113.576365 148.568905) (xy 113.53048 148.547825) (xy 113.492799 148.52046)
				(xy 113.465566 148.489552) (xy 113.448528 148.456265) (xy 113.442511 148.423434) (xy 113.4425 148.422)
			)
		)
	)
	(zone
		(net 433)
		(net_name "/2xSFP+/10GKR_SFP0.RX-")
		(layer "F.Cu")
		(name "$teardrop_padvia$")
		(hatch none 0.1)
		(priority 30905)
		(attr
			(teardrop
				(type padvia)
			)
		)
		(connect_pads yes
			(clearance 0)
		)
		(min_thickness 0.0254)
		(filled_areas_thickness no)
		(fill yes
			(thermal_gap 0.5)
			(thermal_bridge_width 0.5)
			(island_removal_mode 1)
			(island_area_min 10)
		)
		(polygon
			(pts
				(xy 200.545 157.62) (xy 200.544745 157.612548) (xy 200.550791 157.578161) (xy 200.568548 157.565168)
				(xy 200.604123 157.56) (xy 200.525 156.684) (xy 200.375 157.56) (xy 200.392936 157.564466) (xy 200.397965 157.575729)
				(xy 200.390417 157.602612) (xy 200.385 157.62)
			)
		)
	)
	(zone
		(net 324)
		(net_name "/Com Express 7 Interfaces/PCIe_{B2Ax4}.TX0+")
		(layer "F.Cu")
		(name "$teardrop_padvia$")
		(hatch none 0.1)
		(priority 31451)
		(attr
			(teardrop
				(type padvia)
			)
		)
		(connect_pads yes
			(clearance 0)
		)
		(min_thickness 0.0254)
		(filled_areas_thickness no)
		(fill yes
			(thermal_gap 0.5)
			(thermal_bridge_width 0.5)
			(island_removal_mode 1)
			(island_area_min 10)
		)
		(polygon
			(pts
				(xy 228.2065 143.763584) (xy 228.199528 143.593351) (xy 228.197677 143.415931) (xy 227.977 143.399)
				(xy 227.815834 143.550918) (xy 227.884098 143.60277) (xy 227.902419 143.613184) (xy 227.941426 143.636544)
				(xy 227.973955 143.664991) (xy 227.996236 143.705135) (xy 228.0045 143.763584)
			)
		)
	)
	(zone
		(net 1)
		(net_name "GND")
		(layer "F.Cu")
		(name "$teardrop_padvia$")
		(hatch none 0.1)
		(priority 30546)
		(attr
			(teardrop
				(type padvia)
			)
		)
		(connect_pads yes
			(clearance 0)
		)
		(min_thickness 0.0254)
		(filled_areas_thickness no)
		(fill yes
			(thermal_gap 0.5)
			(thermal_bridge_width 0.5)
			(island_removal_mode 1)
			(island_area_min 10)
		)
		(polygon
			(pts
				(xy 210.425 155.75) (xy 210.428333 155.764486) (xy 210.43119 155.79461) (xy 210.419036 155.805651)
				(xy 210.39 155.81) (xy 210.525 156.686) (xy 210.66 155.81) (xy 210.630666 155.805525) (xy 210.618642 155.794199)
				(xy 210.621667 155.764486) (xy 210.625 155.75)
			)
		)
	)
	(zone
		(net 252)
		(net_name "/Com Express 7 Interfaces/PCIe_{B2Bx4}.RX1-")
		(layer "F.Cu")
		(name "$teardrop_padvia$")
		(hatch none 0.1)
		(priority 31347)
		(attr
			(teardrop
				(type padvia)
			)
		)
		(connect_pads yes
			(clearance 0)
		)
		(min_thickness 0.0254)
		(filled_areas_thickness no)
		(fill yes
			(thermal_gap 0.5)
			(thermal_bridge_width 0.5)
			(island_removal_mode 1)
			(island_area_min 10)
		)
		(polygon
			(pts
				(xy 194.549092 160.368809) (xy 194.585522 160.339074) (xy 194.619885 160.3233) (xy 194.685791 160.321045)
				(xy 194.729912 160.330976) (xy 194.779788 160.342147) (xy 194.835381 160.345891) (xy 194.825921 160.124507)
				(xy 194.655129 159.983214) (xy 194.587215 160.057674) (xy 194.525836 160.114198) (xy 194.524294 160.115565)
				(xy 194.406256 160.225973)
			)
		)
	)
	(zone
		(net 553)
		(net_name "/2xUSB3.0+RJ45/FLG_1B")
		(layer "F.Cu")
		(name "$teardrop_padvia$")
		(hatch none 0.1)
		(priority 30074)
		(attr
			(teardrop
				(type padvia)
			)
		)
		(connect_pads yes
			(clearance 0)
		)
		(min_thickness 0.0254)
		(filled_areas_thickness no)
		(fill yes
			(thermal_gap 0.5)
			(thermal_bridge_width 0.5)
			(island_removal_mode 1)
			(island_area_min 10)
		)
		(polygon
			(pts
				(xy 116.339 87.7515) (xy 116.283736 87.732104) (xy 116.234452 87.670761) (xy 116.202899 87.562049)
				(xy 116.199 87.499) (xy 115.598 87.814) (xy 116.199 88.129) (xy 116.203756 88.059663) (xy 116.217044 88.000293)
				(xy 116.237444 87.951557) (xy 116.263462 87.914336) (xy 116.291726 87.89052) (xy 116.322426 87.878176)
				(xy 116.339 87.8765)
			)
		)
	)
	(zone
		(net 273)
		(net_name "/M.2 key M #2/PCIE_{REF}.CK+")
		(layer "F.Cu")
		(name "$teardrop_padvia$")
		(hatch none 0.1)
		(priority 30436)
		(attr
			(teardrop
				(type padvia)
			)
		)
		(connect_pads yes
			(clearance 0)
		)
		(min_thickness 0.0254)
		(filled_areas_thickness no)
		(fill yes
			(thermal_gap 0.5)
			(thermal_bridge_width 0.5)
			(island_removal_mode 1)
			(island_area_min 10)
		)
		(polygon
			(pts
				(xy 222.005521 130.2435) (xy 221.927272 130.285459) (xy 221.828716 130.321472) (xy 221.751841 130.33683)
				(xy 221.671576 130.339442) (xy 221.608246 130.33) (xy 221.639 130.65) (xy 221.935 130.748914) (xy 221.932186 130.624529)
				(xy 221.944709 130.533642) (xy 221.961698 130.49161) (xy 221.98655 130.459964) (xy 222.005521 130.4455)
			)
		)
	)
	(zone
		(net 326)
		(net_name "/Com Express 7 Interfaces/PCIe_{B2Ax4}.TX1+")
		(layer "F.Cu")
		(name "$teardrop_padvia$")
		(hatch none 0.1)
		(priority 30518)
		(attr
			(teardrop
				(type padvia)
			)
		)
		(connect_pads yes
			(clearance 0)
		)
		(min_thickness 0.0254)
		(filled_areas_thickness no)
		(fill yes
			(thermal_gap 0.5)
			(thermal_bridge_width 0.5)
			(island_removal_mode 1)
			(island_area_min 10)
		)
		(polygon
			(pts
				(xy 212.424 167.75) (xy 212.427537 167.764678) (xy 212.430808 167.794685) (xy 212.418857 167.805673)
				(xy 212.39 167.81) (xy 212.525 168.686) (xy 212.66 167.81) (xy 212.630796 167.805525) (xy 212.619003 167.794203)
				(xy 212.622463 167.764678) (xy 212.626 167.75)
			)
		)
	)
	(zone
		(net 692)
		(net_name "/2xUSB3.0+RJ45/DB_FL-")
		(layer "F.Cu")
		(name "$teardrop_padvia$")
		(hatch none 0.1)
		(priority 31154)
		(attr
			(teardrop
				(type padvia)
			)
		)
		(connect_pads yes
			(clearance 0)
		)
		(min_thickness 0.0254)
		(filled_areas_thickness no)
		(fill yes
			(thermal_gap 0.5)
			(thermal_bridge_width 0.5)
			(island_removal_mode 1)
			(island_area_min 10)
		)
		(polygon
			(pts
				(xy 128.632927 105.256861) (xy 128.587939 105.201829) (xy 128.552832 105.124702) (xy 128.544807 105.075901)
				(xy 128.5475 105.021575) (xy 128.209293 105.039293) (xy 128.173057 105.2775) (xy 128.260646 105.273374)
				(xy 128.338104 105.279239) (xy 128.404339 105.293738) (xy 128.460384 105.315855) (xy 128.526861 105.362927)
			)
		)
	)
	(zone
		(net 72)
		(net_name "Net-(U20-CT)")
		(layer "F.Cu")
		(name "$teardrop_padvia$")
		(hatch none 0.1)
		(priority 30938)
		(attr
			(teardrop
				(type padvia)
			)
		)
		(connect_pads yes
			(clearance 0)
		)
		(min_thickness 0.0254)
		(filled_areas_thickness no)
		(fill yes
			(thermal_gap 0.5)
			(thermal_bridge_width 0.5)
			(island_removal_mode 1)
			(island_area_min 10)
		)
		(polygon
			(pts
				(xy 304.6825 128.228) (xy 304.702469 128.165134) (xy 304.728921 128.133156) (xy 304.766332 128.104642)
				(xy 304.813527 128.082118) (xy 304.871167 128.066907) (xy 304.871798 128.066798) (xy 304.62 127.789)
				(xy 304.368202 128.066798) (xy 304.423635 128.081095) (xy 304.46952 128.102175) (xy 304.507201 128.12954)
				(xy 304.534434 128.160448) (xy 304.551472 128.193735) (xy 304.557489 128.226566) (xy 304.5575 128.228)
			)
		)
	)
	(zone
		(net 188)
		(net_name "/OCuLink/PCIe_{x4}.RX1+")
		(layer "F.Cu")
		(name "$teardrop_padvia$")
		(hatch none 0.1)
		(priority 32056)
		(attr
			(teardrop
				(type padvia)
			)
		)
		(connect_pads yes
			(clearance 0)
		)
		(min_thickness 0.0254)
		(filled_areas_thickness no)
		(fill yes
			(thermal_gap 0.5)
			(thermal_bridge_width 0.5)
			(island_removal_mode 1)
			(island_area_min 10)
		)
		(polygon
			(pts
				(xy 98.101 151.797) (xy 98.093802 151.776352) (xy 98.084208 151.744016) (xy 98.091035 151.729993)
				(xy 98.1125 151.720004) (xy 98 151.471) (xy 97.8875 151.720004) (xy 97.908676 151.729729) (xy 97.915731 151.743357)
				(xy 97.906198 151.776352) (xy 97.899 151.797)
			)
		)
	)
	(zone
		(net 555)
		(net_name "/2xUSB3.0+RJ45/EN_1B")
		(layer "F.Cu")
		(name "$teardrop_padvia$")
		(hatch none 0.1)
		(priority 31031)
		(attr
			(teardrop
				(type padvia)
			)
		)
		(connect_pads yes
			(clearance 0)
		)
		(min_thickness 0.0254)
		(filled_areas_thickness no)
		(fill yes
			(thermal_gap 0.5)
			(thermal_bridge_width 0.5)
			(island_removal_mode 1)
			(island_area_min 10)
		)
		(polygon
			(pts
				(xy 121.5075 85.622001) (xy 121.487531 85.684866) (xy 121.461079 85.716844) (xy 121.423668 85.745359)
				(xy 121.376472 85.767883) (xy 121.318832 85.783093) (xy 121.318202 85.783202) (xy 121.57 86.060999)
				(xy 121.821798 85.783202) (xy 121.766365 85.768905) (xy 121.72048 85.747825) (xy 121.682798 85.72046)
				(xy 121.655565 85.689551) (xy 121.638527 85.656265) (xy 121.63251 85.623434) (xy 121.632499 85.622)
			)
		)
	)
	(zone
		(net 1)
		(net_name "GND")
		(layer "F.Cu")
		(name "$teardrop_padvia$")
		(hatch none 0.1)
		(priority 31208)
		(attr
			(teardrop
				(type padvia)
			)
		)
		(connect_pads yes
			(clearance 0)
		)
		(min_thickness 0.0254)
		(filled_areas_thickness no)
		(fill yes
			(thermal_gap 0.5)
			(thermal_bridge_width 0.5)
			(island_removal_mode 1)
			(island_area_min 10)
		)
		(polygon
			(pts
				(xy 199.425 151.799323) (xy 199.42028 151.868646) (xy 199.407244 151.921549) (xy 199.355344 152.014135)
				(xy 199.303541 152.097636) (xy 199.5 152.201) (xy 199.707644 152.124641) (xy 199.675418 152.044142)
				(xy 199.639035 151.942683) (xy 199.625 151.799323)
			)
		)
	)
	(zone
		(net 1)
		(net_name "GND")
		(layer "F.Cu")
		(name "$teardrop_padvia$")
		(hatch none 0.1)
		(priority 31930)
		(attr
			(teardrop
				(type padvia)
			)
		)
		(connect_pads yes
			(clearance 0)
		)
		(min_thickness 0.0254)
		(filled_areas_thickness no)
		(fill yes
			(thermal_gap 0.5)
			(thermal_bridge_width 0.5)
			(island_removal_mode 1)
			(island_area_min 10)
		)
		(polygon
			(pts
				(xy 314.718 160.81) (xy 314.707885 160.810153) (xy 314.677169 160.80954) (xy 314.64468 160.801218)
				(xy 314.615526 160.777325) (xy 314.594809 160.73) (xy 314.362 160.91) (xy 314.594809 161.09) (xy 314.608168 161.054099)
				(xy 314.626399 161.030801) (xy 314.671725 161.011101) (xy 314.707885 161.009847) (xy 314.718 161.01)
			)
		)
	)
	(zone
		(net 2)
		(net_name "+3V3")
		(layer "F.Cu")
		(name "$teardrop_padvia$")
		(hatch none 0.1)
		(priority 30398)
		(attr
			(teardrop
				(type padvia)
			)
		)
		(connect_pads yes
			(clearance 0)
		)
		(min_thickness 0.0254)
		(filled_areas_thickness no)
		(fill yes
			(thermal_gap 0.5)
			(thermal_bridge_width 0.5)
			(island_removal_mode 1)
			(island_area_min 10)
		)
		(polygon
			(pts
				(xy 197.270225 135.027275) (xy 197.224229 135.010133) (xy 197.187201 134.999718) (xy 197.158184 134.982825)
				(xy 197.149266 134.953969) (xy 197.172536 134.907665) (xy 196.800707 134.911309) (xy 196.797062 135.283139)
				(xy 196.830941 135.263147) (xy 196.855812 135.260066) (xy 196.882202 135.28222) (xy 196.899531 135.334832)
				(xy 196.916673 135.380828)
			)
		)
	)
	(zone
		(net 228)
		(net_name "/M.2 key M #1/~{PERST_D}")
		(layer "F.Cu")
		(name "$teardrop_padvia$")
		(hatch none 0.1)
		(priority 31124)
		(attr
			(teardrop
				(type padvia)
			)
		)
		(connect_pads yes
			(clearance 0)
		)
		(min_thickness 0.0254)
		(filled_areas_thickness no)
		(fill yes
			(thermal_gap 0.5)
			(thermal_bridge_width 0.5)
			(island_removal_mode 1)
			(island_area_min 10)
		)
		(polygon
			(pts
				(xy 176.627 107.7225) (xy 176.686412 107.742273) (xy 176.742497 107.805547) (xy 176.764199 107.854172)
				(xy 176.778873 107.913531) (xy 176.780653 107.9255) (xy 177.041 107.66) (xy 176.780653 107.3945)
				(xy 176.767804 107.454638) (xy 176.74787 107.504522) (xy 176.721945 107.544641) (xy 176.692125 107.573654)
				(xy 176.660707 107.591146) (xy 176.628896 107.597479) (xy 176.627 107.5975)
			)
		)
	)
	(zone
		(net 114)
		(net_name "/2xSFP+/KR to SFI #1/KR_C.TX-")
		(layer "F.Cu")
		(name "$teardrop_padvia$")
		(hatch none 0.1)
		(priority 31964)
		(attr
			(teardrop
				(type padvia)
			)
		)
		(connect_pads yes
			(clearance 0)
		)
		(min_thickness 0.0254)
		(filled_areas_thickness no)
		(fill yes
			(thermal_gap 0.5)
			(thermal_bridge_width 0.5)
			(island_removal_mode 1)
			(island_area_min 10)
		)
		(polygon
			(pts
				(xy 156.06 146.717279) (xy 156.084062 146.786651) (xy 156.120577 146.896598) (xy 156.130888 146.956686)
				(xy 156.13 147.018536) (xy 156.33 146.991) (xy 156.388769 146.76) (xy 156.307423 146.765298) (xy 156.255406 146.756508)
				(xy 156.233886 146.742657) (xy 156.221647 146.722599) (xy 156.22 146.717279)
			)
		)
	)
	(zone
		(net 1)
		(net_name "GND")
		(layer "F.Cu")
		(name "$teardrop_padvia$")
		(hatch none 0.1)
		(priority 30835)
		(attr
			(teardrop
				(type padvia)
			)
		)
		(connect_pads yes
			(clearance 0)
		)
		(min_thickness 0.0254)
		(filled_areas_thickness no)
		(fill yes
			(thermal_gap 0.5)
			(thermal_bridge_width 0.5)
			(island_removal_mode 1)
			(island_area_min 10)
		)
		(polygon
			(pts
				(xy 248.818 131.22406) (xy 248.82272 131.282144) (xy 248.83576 131.330338) (xy 248.882835 131.407866)
				(xy 248.940656 131.4649) (xy 248.996724 131.520151) (xy 249.038884 131.58905) (xy 249.245 131.511)
				(xy 249.288895 131.289323) (xy 249.22841 131.2869) (xy 249.152701 131.280635) (xy 249.127563 131.261783)
				(xy 249.118 131.22406)
			)
		)
	)
	(zone
		(net 625)
		(net_name "/PCIe redriver/TX_EQ2")
		(layer "F.Cu")
		(name "$teardrop_padvia$")
		(hatch none 0.1)
		(priority 31103)
		(attr
			(teardrop
				(type padvia)
			)
		)
		(connect_pads yes
			(clearance 0)
		)
		(min_thickness 0.0254)
		(filled_areas_thickness no)
		(fill yes
			(thermal_gap 0.5)
			(thermal_bridge_width 0.5)
			(island_removal_mode 1)
			(island_area_min 10)
		)
		(polygon
			(pts
				(xy 112.3375 143.467) (xy 112.317727 143.526412) (xy 112.254453 143.582496) (xy 112.205828 143.604198)
				(xy 112.146469 143.618872) (xy 112.1345 143.620652) (xy 112.4 143.881) (xy 112.6655 143.620652)
				(xy 112.605362 143.607803) (xy 112.555478 143.587869) (xy 112.515358 143.561944) (xy 112.486345 143.532124)
				(xy 112.468854 143.500706) (xy 112.462521 143.468895) (xy 112.4625 143.467)
			)
		)
	)
	(zone
		(net 615)
		(net_name "/PCIe misc/DIF2+")
		(layer "F.Cu")
		(name "$teardrop_padvia$")
		(hatch none 0.1)
		(priority 30424)
		(attr
			(teardrop
				(type padvia)
			)
		)
		(connect_pads yes
			(clearance 0)
		)
		(min_thickness 0.0254)
		(filled_areas_thickness no)
		(fill yes
			(thermal_gap 0.5)
			(thermal_bridge_width 0.5)
			(island_removal_mode 1)
			(island_area_min 10)
		)
		(polygon
			(pts
				(xy 214.1845 134.154479) (xy 214.161242 134.182061) (xy 214.130003 134.202725) (xy 214.038084 134.225599)
				(xy 213.881086 134.225) (xy 213.98 134.521) (xy 214.3 134.551754) (xy 214.290561 134.436622) (xy 214.315334 134.308282)
				(xy 214.373209 134.176717) (xy 214.3865 134.154479)
			)
		)
	)
	(zone
		(net 291)
		(net_name "/2xUSB3.0+RJ45/~{GBE0_LINK}")
		(layer "F.Cu")
		(name "$teardrop_padvia$")
		(hatch none 0.1)
		(priority 30645)
		(attr
			(teardrop
				(type padvia)
			)
		)
		(connect_pads yes
			(clearance 0)
		)
		(min_thickness 0.0254)
		(filled_areas_thickness no)
		(fill yes
			(thermal_gap 0.5)
			(thermal_bridge_width 0.5)
			(island_removal_mode 1)
			(island_area_min 10)
		)
		(polygon
			(pts
				(xy 179.5875 169.62) (xy 179.598438 169.581177) (xy 179.620195 169.566067) (xy 179.66 169.56) (xy 179.525 168.684)
				(xy 179.39 169.56) (xy 179.425281 169.564517) (xy 179.446797 169.576138) (xy 179.461995 169.608961)
				(xy 179.4625 169.62)
			)
		)
	)
	(zone
		(net 647)
		(net_name "Net-(Y2-EN)")
		(layer "F.Cu")
		(name "$teardrop_padvia$")
		(hatch none 0.1)
		(priority 30041)
		(attr
			(teardrop
				(type padvia)
			)
		)
		(connect_pads yes
			(clearance 0)
		)
		(min_thickness 0.0254)
		(filled_areas_thickness no)
		(fill yes
			(thermal_gap 0.5)
			(thermal_bridge_width 0.5)
			(island_removal_mode 1)
			(island_area_min 10)
		)
		(polygon
			(pts
				(xy 142.575699 136.474087) (xy 142.642291 136.567785) (xy 142.69334 136.708604) (xy 142.72488 136.911925)
				(xy 142.73 137.186981) (xy 143.190707 137.085707) (xy 143.281992 136.56) (xy 143.15259 136.555037)
				(xy 143.030374 136.540295) (xy 142.923154 136.517385) (xy 142.827128 136.486008) (xy 142.753027 136.45117)
				(xy 142.691176 136.40993) (xy 142.664087 136.385699)
			)
		)
	)
	(zone
		(net 70)
		(net_name "Net-(C49-Pad2)")
		(layer "F.Cu")
		(hatch edge 0.5)
		(priority 1)
		(connect_pads yes
			(clearance 0.15)
		)
		(min_thickness 0.25)
		(filled_areas_thickness no)
		(fill yes
			(thermal_gap 0.2)
			(thermal_bridge_width 0.5)
			(smoothing fillet)
			(radius 0.2)
		)
		(polygon
			(pts
				(xy 308.524999 115.36) (xy 308.524999 121.935001) (xy 308.700005 122.11) (xy 309.724999 122.11)
				(xy 310.724999 123.11) (xy 310.724999 127.31) (xy 310.574999 127.46) (xy 308.915172 127.46) (xy 304.749432 123.294426)
				(xy 304.749491 114.71) (xy 307.874999 114.71)
			)
		)
	)
	(zone
		(net 941)
		(net_name "/2xUSB3.0+RJ45/EN_1")
		(layer "F.Cu")
		(name "$teardrop_padvia$")
		(hatch none 0.1)
		(priority 31121)
		(attr
			(teardrop
				(type padvia)
			)
		)
		(connect_pads yes
			(clearance 0)
		)
		(min_thickness 0.0254)
		(filled_areas_thickness no)
		(fill yes
			(thermal_gap 0.5)
			(thermal_bridge_width 0.5)
			(island_removal_mode 1)
			(island_area_min 10)
		)
		(polygon
			(pts
				(xy 125.532 86.122501) (xy 125.591412 86.142274) (xy 125.647497 86.205548) (xy 125.669199 86.254173)
				(xy 125.683873 86.313532) (xy 125.685653 86.325501) (xy 125.946 86.060001) (xy 125.685653 85.794501)
				(xy 125.672804 85.854639) (xy 125.65287 85.904523) (xy 125.626945 85.944642) (xy 125.597125 85.973655)
				(xy 125.565707 85.991147) (xy 125.533896 85.99748) (xy 125.532 85.997501)
			)
		)
	)
	(zone
		(net 213)
		(net_name "/Com Express 7 Interfaces/PCIe_{B1x4}.RX2-")
		(layer "F.Cu")
		(name "$teardrop_padvia$")
		(hatch none 0.1)
		(priority 30508)
		(attr
			(teardrop
				(type padvia)
			)
		)
		(connect_pads yes
			(clearance 0)
		)
		(min_thickness 0.0254)
		(filled_areas_thickness no)
		(fill yes
			(thermal_gap 0.5)
			(thermal_bridge_width 0.5)
			(island_removal_mode 1)
			(island_area_min 10)
		)
		(polygon
			(pts
				(xy 206.424 162.2) (xy 206.427537 162.214678) (xy 206.430808 162.244685) (xy 206.418857 162.255673)
				(xy 206.39 162.26) (xy 206.525 163.136) (xy 206.66 162.26) (xy 206.630796 162.255525) (xy 206.619003 162.244203)
				(xy 206.622463 162.214678) (xy 206.626 162.2)
			)
		)
	)
	(zone
		(net 1)
		(net_name "GND")
		(layer "F.Cu")
		(name "$teardrop_padvia$")
		(hatch none 0.1)
		(priority 31892)
		(attr
			(teardrop
				(type padvia)
			)
		)
		(connect_pads yes
			(clearance 0)
		)
		(min_thickness 0.0254)
		(filled_areas_thickness no)
		(fill yes
			(thermal_gap 0.5)
			(thermal_bridge_width 0.5)
			(island_removal_mode 1)
			(island_area_min 10)
		)
		(polygon
			(pts
				(xy 193.623321 141.685037) (xy 193.668652 141.737173) (xy 193.695044 141.782915) (xy 193.71515 141.868904)
				(xy 193.716985 141.884745) (xy 193.729323 141.968895) (xy 193.950707 141.925707) (xy 193.993895 141.704323)
				(xy 193.912606 141.692005) (xy 193.814963 141.671233) (xy 193.766844 141.644331) (xy 193.711709 141.596649)
			)
		)
	)
	(zone
		(net 84)
		(net_name "/Com Express 7 MGMT/PWRBTN")
		(layer "F.Cu")
		(name "$teardrop_padvia$")
		(hatch none 0.1)
		(priority 31032)
		(attr
			(teardrop
				(type padvia)
			)
		)
		(connect_pads yes
			(clearance 0)
		)
		(min_thickness 0.0254)
		(filled_areas_thickness no)
		(fill yes
			(thermal_gap 0.5)
			(thermal_bridge_width 0.5)
			(island_removal_mode 1)
			(island_area_min 10)
		)
		(polygon
			(pts
				(xy 247.912001 128.852499) (xy 247.974866 128.872468) (xy 248.006844 128.89892) (xy 248.035358 128.936331)
				(xy 248.057882 128.983526) (xy 248.073093 129.041166) (xy 248.073202 129.041798) (xy 248.350999 128.79)
				(xy 248.073202 128.538202) (xy 248.058905 128.593635) (xy 248.037825 128.63952) (xy 248.01046 128.677201)
				(xy 247.979552 128.704434) (xy 247.946265 128.721472) (xy 247.913434 128.727489) (xy 247.912 128.7275)
			)
		)
	)
	(zone
		(net 1)
		(net_name "GND")
		(layer "F.Cu")
		(name "$teardrop_padvia$")
		(hatch none 0.1)
		(priority 30779)
		(attr
			(teardrop
				(type padvia)
			)
		)
		(connect_pads yes
			(clearance 0)
		)
		(min_thickness 0.0254)
		(filled_areas_thickness no)
		(fill yes
			(thermal_gap 0.5)
			(thermal_bridge_width 0.5)
			(island_removal_mode 1)
			(island_area_min 10)
		)
		(polygon
			(pts
				(xy 152.969177 89.4085) (xy 152.811606 89.401569) (xy 152.698078 89.373049) (xy 152.656278 89.356)
				(xy 152.5675 89.5585) (xy 152.656278 89.761) (xy 152.752317 89.726618) (xy 152.854189 89.7114) (xy 152.969177 89.7085)
			)
		)
	)
	(zone
		(net 189)
		(net_name "/OCuLink/PCIe_{x4}.RX1-")
		(layer "F.Cu")
		(name "$teardrop_padvia$")
		(hatch none 0.1)
		(priority 32082)
		(attr
			(teardrop
				(type padvia)
			)
		)
		(connect_pads yes
			(clearance 0)
		)
		(min_thickness 0.0254)
		(filled_areas_thickness no)
		(fill yes
			(thermal_gap 0.5)
			(thermal_bridge_width 0.5)
			(island_removal_mode 1)
			(island_area_min 10)
		)
		(polygon
			(pts
				(xy 98.399 150.375) (xy 98.406198 150.395648) (xy 98.415792 150.427984) (xy 98.408965 150.442007)
				(xy 98.3875 150.451995) (xy 98.5 150.701) (xy 98.6125 150.451995) (xy 98.591324 150.442271) (xy 98.584269 150.428643)
				(xy 98.593802 150.395648) (xy 98.601 150.375)
			)
		)
	)
	(zone
		(net 758)
		(net_name "Net-(U45B-LS_OK_{IN_B})")
		(layer "F.Cu")
		(name "$teardrop_padvia$")
		(hatch none 0.1)
		(priority 30121)
		(attr
			(teardrop
				(type padvia)
			)
		)
		(connect_pads yes
			(clearance 0)
		)
		(min_thickness 0.0254)
		(filled_areas_thickness no)
		(fill yes
			(thermal_gap 0.5)
			(thermal_bridge_width 0.5)
			(island_removal_mode 1)
			(island_area_min 10)
		)
		(polygon
			(pts
				(xy 127.8525 130.227794) (xy 127.857315 130.145733) (xy 127.871019 130.080388) (xy 127.917576 129.98712)
				(xy 127.985787 129.908657) (xy 128.041942 129.847158) (xy 128.101801 129.768339) (xy 127.79 129.559)
				(xy 127.478199 129.768339) (xy 127.575219 129.888517) (xy 127.594214 129.908658) (xy 127.647366 129.967541)
				(xy 127.689591 130.031624) (xy 127.717449 130.114008) (xy 127.7275 130.227794)
			)
		)
	)
	(zone
		(net 73)
		(net_name "+3V3_AON")
		(layer "F.Cu")
		(name "$teardrop_padvia$")
		(hatch none 0.1)
		(priority 31800)
		(attr
			(teardrop
				(type padvia)
			)
		)
		(connect_pads yes
			(clearance 0)
		)
		(min_thickness 0.0254)
		(filled_areas_thickness no)
		(fill yes
			(thermal_gap 0.5)
			(thermal_bridge_width 0.5)
			(island_removal_mode 1)
			(island_area_min 10)
		)
		(polygon
			(pts
				(xy 250.605677 131.4475) (xy 250.536236 131.442682) (xy 250.484913 131.42896) (xy 250.409371 131.382246)
				(xy 250.397231 131.372701) (xy 250.330003 131.322919) (xy 250.204 131.51) (xy 250.330003 131.697081)
				(xy 250.397229 131.647299) (xy 250.480396 131.592894) (xy 250.533251 131.57781) (xy 250.605677 131.5725)
			)
		)
	)
	(zone
		(net 340)
		(net_name "/Com Express 7 MGMT/SPI.CLK")
		(layer "F.Cu")
		(name "$teardrop_padvia$")
		(hatch none 0.1)
		(priority 30065)
		(attr
			(teardrop
				(type padvia)
			)
		)
		(connect_pads yes
			(clearance 0)
		)
		(min_thickness 0.0254)
		(filled_areas_thickness no)
		(fill yes
			(thermal_gap 0.5)
			(thermal_bridge_width 0.5)
			(island_removal_mode 1)
			(island_area_min 10)
		)
		(polygon
			(pts
				(xy 248.367145 161.362) (xy 248.431695 161.381763) (xy 248.465272 161.408201) (xy 248.495792 161.445419)
				(xy 248.521388 161.49326) (xy 248.540127 161.551471) (xy 248.54474 161.574405) (xy 249.323145 161.297)
				(xy 248.54474 161.019595) (xy 248.529782 161.078778) (xy 248.507898 161.128604) (xy 248.479528 161.170336)
				(xy 248.447294 161.201509) (xy 248.412626 161.222097) (xy 248.37783 161.231428) (xy 248.367145 161.232)
			)
		)
	)
	(zone
		(net 56)
		(net_name "/USB-C console/USB_D-")
		(layer "F.Cu")
		(name "$teardrop_padvia$")
		(hatch none 0.1)
		(priority 31327)
		(attr
			(teardrop
				(type padvia)
			)
		)
		(connect_pads yes
			(clearance 0)
		)
		(min_thickness 0.0254)
		(filled_areas_thickness no)
		(fill yes
			(thermal_gap 0.5)
			(thermal_bridge_width 0.5)
			(island_removal_mode 1)
			(island_area_min 10)
		)
		(polygon
			(pts
				(xy 102.0075 85.222) (xy 102.012343 85.235614) (xy 102.018533 85.259784) (xy 102.010196 85.268556)
				(xy 101.9875 85.272) (xy 102.1 86.0855) (xy 102.2125 85.272) (xy 102.187863 85.267581) (xy 102.181016 85.256646)
				(xy 102.187657 85.235614) (xy 102.1925 85.222)
			)
		)
	)
	(zone
		(net 1)
		(net_name "GND")
		(layer "F.Cu")
		(name "$teardrop_padvia$")
		(hatch none 0.1)
		(priority 30440)
		(attr
			(teardrop
				(type padvia)
			)
		)
		(connect_pads yes
			(clearance 0)
		)
		(min_thickness 0.0254)
		(filled_areas_thickness no)
		(fill yes
			(thermal_gap 0.5)
			(thermal_bridge_width 0.5)
			(island_removal_mode 1)
			(island_area_min 10)
		)
		(polygon
			(pts
				(xy 245.438709 77.622) (xy 245.398109 77.618921) (xy 245.35794 77.600578) (xy 245.326465 77.553307)
				(xy 245.311946 77.463448) (xy 244.999709 77.655) (xy 245.173209 77.95) (xy 245.228728 77.910588)
				(xy 245.300574 77.902052) (xy 245.376278 77.913244) (xy 245.438709 77.922)
			)
		)
	)
	(zone
		(net 2)
		(net_name "+3V3")
		(layer "F.Cu")
		(name "$teardrop_padvia$")
		(hatch none 0.1)
		(priority 31281)
		(attr
			(teardrop
				(type padvia)
			)
		)
		(connect_pads yes
			(clearance 0)
		)
		(min_thickness 0.0254)
		(filled_areas_thickness no)
		(fill yes
			(thermal_gap 0.5)
			(thermal_bridge_width 0.5)
			(island_removal_mode 1)
			(island_area_min 10)
		)
		(polygon
			(pts
				(xy 197.60861 73.701486) (xy 197.603897 73.779397) (xy 197.59091 73.838181) (xy 197.548809 73.929211)
				(xy 197.50611 74.014384) (xy 197.70861 74.103163) (xy 197.91111 74.014384) (xy 197.868411 73.929213)
				(xy 197.825743 73.83638) (xy 197.813166 73.778241) (xy 197.80861 73.701486)
			)
		)
	)
	(zone
		(net 643)
		(net_name "Net-(U41-IO0_4)")
		(layer "F.Cu")
		(name "$teardrop_padvia$")
		(hatch none 0.1)
		(priority 32021)
		(attr
			(teardrop
				(type padvia)
			)
		)
		(connect_pads yes
			(clearance 0)
		)
		(min_thickness 0.0254)
		(filled_areas_thickness no)
		(fill yes
			(thermal_gap 0.5)
			(thermal_bridge_width 0.5)
			(island_removal_mode 1)
			(island_area_min 10)
		)
		(polygon
			(pts
				(xy 128.2495 86.370501) (xy 128.255822 86.370405) (xy 128.295325 86.37599) (xy 128.313548 86.390922)
				(xy 128.326496 86.4205) (xy 128.713 86.308) (xy 128.326494 86.1955) (xy 128.315378 86.222494) (xy 128.299851 86.237596)
				(xy 128.255821 86.245597) (xy 128.2495 86.245501)
			)
		)
	)
	(zone
		(net 1)
		(net_name "GND")
		(layer "F.Cu")
		(name "$teardrop_padvia$")
		(hatch none 0.1)
		(priority 30615)
		(attr
			(teardrop
				(type padvia)
			)
		)
		(connect_pads yes
			(clearance 0)
		)
		(min_thickness 0.0254)
		(filled_areas_thickness no)
		(fill yes
			(thermal_gap 0.5)
			(thermal_bridge_width 0.5)
			(island_removal_mode 1)
			(island_area_min 10)
		)
		(polygon
			(pts
				(xy 180.925 150.2) (xy 180.928333 150.214486) (xy 180.93119 150.24461) (xy 180.919036 150.255651)
				(xy 180.89 150.26) (xy 181.025 151.136) (xy 181.16 150.26) (xy 181.130666 150.255525) (xy 181.118642 150.244199)
				(xy 181.121667 150.214486) (xy 181.125 150.2)
			)
		)
	)
	(zone
		(net 1)
		(net_name "GND")
		(layer "F.Cu")
		(name "$teardrop_padvia$")
		(hatch none 0.1)
		(priority 31879)
		(attr
			(teardrop
				(type padvia)
			)
		)
		(connect_pads yes
			(clearance 0)
		)
		(min_thickness 0.0254)
		(filled_areas_thickness no)
		(fill yes
			(thermal_gap 0.5)
			(thermal_bridge_width 0.5)
			(island_removal_mode 1)
			(island_area_min 10)
		)
		(polygon
			(pts
				(xy 191.230702 138.393228) (xy 191.283211 138.347532) (xy 191.329205 138.320944) (xy 191.415653 138.30056)
				(xy 191.430989 138.298724) (xy 191.513724 138.28639) (xy 191.470536 138.065006) (xy 191.249152 138.021818)
				(xy 191.236817 138.104554) (xy 191.21648 138.201832) (xy 191.189772 138.249872) (xy 191.142314 138.30484)
			)
		)
	)
	(zone
		(net 1)
		(net_name "GND")
		(layer "F.Cu")
		(hatch edge 0.5)
		(priority 22)
		(connect_pads yes
			(clearance 0.15)
		)
		(min_thickness 0.25)
		(filled_areas_thickness no)
		(fill yes
			(thermal_gap 0.2)
			(thermal_bridge_width 0.5)
		)
		(polygon
			(pts
				(xy 304.5 140.135) (xy 304.5 139.41) (xy 302.575 137.485) (xy 299.675 137.485) (xy 299.675 140.135)
			)
		)
	)
	(zone
		(net 135)
		(net_name "Net-(D19-Pad3)")
		(layer "F.Cu")
		(name "$teardrop_padvia$")
		(hatch none 0.1)
		(priority 30791)
		(attr
			(teardrop
				(type padvia)
			)
		)
		(connect_pads yes
			(clearance 0)
		)
		(min_thickness 0.0254)
		(filled_areas_thickness no)
		(fill yes
			(thermal_gap 0.5)
			(thermal_bridge_width 0.5)
			(island_removal_mode 1)
			(island_area_min 10)
		)
		(polygon
			(pts
				(xy 309.350677 74.66) (xy 309.193106 74.653069) (xy 309.079578 74.624549) (xy 309.037778 74.6075)
				(xy 308.949 74.81) (xy 309.037778 75.0125) (xy 309.133817 74.978118) (xy 309.235689 74.9629) (xy 309.350677 74.96)
			)
		)
	)
	(zone
		(net 85)
		(net_name "/Com Express 7 MGMT/MAFS_POWER")
		(layer "F.Cu")
		(name "$teardrop_padvia$")
		(hatch none 0.1)
		(priority 30470)
		(attr
			(teardrop
				(type padvia)
			)
		)
		(connect_pads yes
			(clearance 0)
		)
		(min_thickness 0.0254)
		(filled_areas_thickness no)
		(fill yes
			(thermal_gap 0.5)
			(thermal_bridge_width 0.5)
			(island_removal_mode 1)
			(island_area_min 10)
		)
		(polygon
			(pts
				(xy 258.558 161.41) (xy 258.54113 161.410338) (xy 258.496174 161.409759) (xy 258.448831 161.397941)
				(xy 258.406427 161.363362) (xy 258.376292 161.2945) (xy 258.119 161.56) (xy 258.376292 161.8255)
				(xy 258.391849 161.780731) (xy 258.412565 161.749115) (xy 258.463701 161.716381) (xy 258.54113 161.709662)
				(xy 258.558 161.71)
			)
		)
	)
	(zone
		(net 667)
		(net_name "/2xSFP+/KR to SFI #1/SFI_R.RX+")
		(layer "F.Cu")
		(name "$teardrop_padvia$")
		(hatch none 0.1)
		(priority 31173)
		(attr
			(teardrop
				(type padvia)
			)
		)
		(connect_pads yes
			(clearance 0)
		)
		(min_thickness 0.0254)
		(filled_areas_thickness no)
		(fill yes
			(thermal_gap 0.5)
			(thermal_bridge_width 0.5)
			(island_removal_mode 1)
			(island_area_min 10)
		)
		(polygon
			(pts
				(xy 149.84 143.17679) (xy 149.835347 143.112802) (xy 149.822777 143.062121) (xy 149.778645 142.980204)
				(xy 149.767609 142.964616) (xy 149.726024 142.899819) (xy 149.695196 142.811227) (xy 149.45 142.859)
				(xy 149.401227 143.105196) (xy 149.488185 143.107002) (xy 149.531073 143.101889) (xy 149.588443 143.095867)
				(xy 149.635848 143.099993) (xy 149.668097 143.123792) (xy 149.68 143.17679)
			)
		)
	)
	(zone
		(net 342)
		(net_name "Net-(J12D-TPM_PP)")
		(layer "F.Cu")
		(name "$teardrop_padvia$")
		(hatch none 0.1)
		(priority 30696)
		(attr
			(teardrop
				(type padvia)
			)
		)
		(connect_pads yes
			(clearance 0)
		)
		(min_thickness 0.0254)
		(filled_areas_thickness no)
		(fill yes
			(thermal_gap 0.5)
			(thermal_bridge_width 0.5)
			(island_removal_mode 1)
			(island_area_min 10)
		)
		(polygon
			(pts
				(xy 223.4625 167.75) (xy 223.451563 167.788823) (xy 223.429805 167.803933) (xy 223.39 167.81) (xy 223.525 168.686)
				(xy 223.66 167.81) (xy 223.624719 167.805483) (xy 223.603203 167.793862) (xy 223.588005 167.761039)
				(xy 223.5875 167.75)
			)
		)
	)
	(zone
		(net 341)
		(net_name "/Com Express 7 MGMT/SPI.MOSI")
		(layer "F.Cu")
		(name "$teardrop_padvia$")
		(hatch none 0.1)
		(priority 30067)
		(attr
			(teardrop
				(type padvia)
			)
		)
		(connect_pads yes
			(clearance 0)
		)
		(min_thickness 0.0254)
		(filled_areas_thickness no)
		(fill yes
			(thermal_gap 0.5)
			(thermal_bridge_width 0.5)
			(island_removal_mode 1)
			(island_area_min 10)
		)
		(polygon
			(pts
				(xy 248.367145 160.065) (xy 248.428711 160.08458) (xy 248.488701 160.147533) (xy 248.514064 160.19705)
				(xy 248.533101 160.257275) (xy 248.540679 160.297327) (xy 249.323145 160.026) (xy 248.54474 159.748595)
				(xy 248.508864 159.842995) (xy 248.448253 159.907222) (xy 248.411915 159.926286) (xy 248.376497 159.934587)
				(xy 248.367145 159.935)
			)
		)
	)
	(zone
		(net 945)
		(net_name "/GPIO expander/GPIOEX5")
		(layer "F.Cu")
		(name "$teardrop_padvia$")
		(hatch none 0.1)
		(priority 31738)
		(attr
			(teardrop
				(type padvia)
			)
		)
		(connect_pads yes
			(clearance 0)
		)
		(min_thickness 0.0254)
		(filled_areas_thickness no)
		(fill yes
			(thermal_gap 0.5)
			(thermal_bridge_width 0.5)
			(island_removal_mode 1)
			(island_area_min 10)
		)
		(polygon
			(pts
				(xy 210.7875 133.409323) (xy 210.782682 133.478763) (xy 210.76896 133.530087) (xy 210.722245 133.605628)
				(xy 210.712702 133.617768) (xy 210.662919 133.684997) (xy 210.85 133.811) (xy 211.037081 133.684997)
				(xy 210.987299 133.617769) (xy 210.932894 133.534603) (xy 210.91781 133.481748) (xy 210.9125 133.409323)
			)
		)
	)
	(zone
		(net 1)
		(net_name "GND")
		(layer "F.Cu")
		(name "$teardrop_padvia$")
		(hatch none 0.1)
		(priority 30056)
		(attr
			(teardrop
				(type padvia)
			)
		)
		(connect_pads yes
			(clearance 0)
		)
		(min_thickness 0.0254)
		(filled_areas_thickness no)
		(fill yes
			(thermal_gap 0.5)
			(thermal_bridge_width 0.5)
			(island_removal_mode 1)
			(island_area_min 10)
		)
		(polygon
			(pts
				(xy 255.568145 160.176) (xy 255.579703 160.175896) (xy 255.626168 160.177312) (xy 255.675413 160.190849)
				(xy 255.718312 160.228788) (xy 255.74574 160.303405) (xy 256.524145 160.026) (xy 255.74574 159.748595)
				(xy 255.732984 159.795233) (xy 255.714222 159.828911) (xy 255.665235 159.865629) (xy 255.599149 159.876189)
				(xy 255.579704 159.876104) (xy 255.568145 159.876)
			)
		)
	)
	(zone
		(net 2)
		(net_name "+3V3")
		(layer "F.Cu")
		(name "$teardrop_padvia$")
		(hatch none 0.1)
		(priority 31021)
		(attr
			(teardrop
				(type padvia)
			)
		)
		(connect_pads yes
			(clearance 0)
		)
		(min_thickness 0.0254)
		(filled_areas_thickness no)
		(fill yes
			(thermal_gap 0.5)
			(thermal_bridge_width 0.5)
			(island_removal_mode 1)
			(island_area_min 10)
		)
		(polygon
			(pts
				(xy 193.035505 129.595071) (xy 193.065837 129.653644) (xy 193.069744 129.69496) (xy 193.063453 129.741576)
				(xy 193.046008 129.790875) (xy 193.016006 129.842388) (xy 193.015637 129.842911) (xy 193.390118 129.861296)
				(xy 193.371733 129.486815) (xy 193.322427 129.515903) (xy 193.275076 129.533442) (xy 193.229081 129.540737)
				(xy 193.187969 129.538138) (xy 193.152384 129.526649) (xy 193.124915 129.507689) (xy 193.123893 129.506683)
			)
		)
	)
	(zone
		(net 990)
		(net_name "Net-(Q14-C)")
		(layer "F.Cu")
		(name "$teardrop_padvia$")
		(hatch none 0.1)
		(priority 30194)
		(attr
			(teardrop
				(type padvia)
			)
		)
		(connect_pads yes
			(clearance 0)
		)
		(min_thickness 0.0254)
		(filled_areas_thickness no)
		(fill yes
			(thermal_gap 0.5)
			(thermal_bridge_width 0.5)
			(island_removal_mode 1)
			(island_area_min 10)
		)
		(polygon
			(pts
				(xy 198.8995 79.03) (xy 198.893825 79.068514) (xy 198.874097 79.107619) (xy 198.847219 79.134469)
				(xy 198.808111 79.156281) (xy 198.7295 79.173927) (xy 198.9995 79.651) (xy 199.2695 79.173927) (xy 199.214894 79.164382)
				(xy 199.172658 79.147775) (xy 199.119693 79.100089) (xy 199.099816 79.039186) (xy 199.0995 79.03)
			)
		)
	)
	(zone
		(net 2)
		(net_name "+3V3")
		(layer "F.Cu")
		(name "$teardrop_padvia$")
		(hatch none 0.1)
		(priority 30388)
		(attr
			(teardrop
				(type padvia)
			)
		)
		(connect_pads yes
			(clearance 0)
		)
		(min_thickness 0.0254)
		(filled_areas_thickness no)
		(fill yes
			(thermal_gap 0.5)
			(thermal_bridge_width 0.5)
			(island_removal_mode 1)
			(island_area_min 10)
		)
		(polygon
			(pts
				(xy 117.152 145.408) (xy 117.172242 145.452339) (xy 117.190971 145.485785) (xy 117.199434 145.518138)
				(xy 117.18518 145.54471) (xy 117.135758 145.560811) (xy 117.4 145.822) (xy 117.666756 145.562492)
				(xy 117.628879 145.552563) (xy 117.609232 145.53709) (xy 117.606323 145.502643) (xy 117.631434 145.452952)
				(xy 117.652 145.408)
			)
		)
	)
	(zone
		(net 1)
		(net_name "GND")
		(layer "F.Cu")
		(name "$teardrop_padvia$")
		(hatch none 0.1)
		(priority 31204)
		(attr
			(teardrop
				(type padvia)
			)
		)
		(connect_pads yes
			(clearance 0)
		)
		(min_thickness 0.0254)
		(filled_areas_thickness no)
		(fill yes
			(thermal_gap 0.5)
			(thermal_bridge_width 0.5)
			(island_removal_mode 1)
			(island_area_min 10)
		)
		(polygon
			(pts
				(xy 190.925 169.498323) (xy 190.92028 169.567646) (xy 190.907244 169.620549) (xy 190.855344 169.713135)
				(xy 190.803541 169.796636) (xy 191 169.9) (xy 191.207644 169.823641) (xy 191.175418 169.743142)
				(xy 191.139035 169.641683) (xy 191.125 169.498323)
			)
		)
	)
	(zone
		(net 1)
		(net_name "GND")
		(layer "F.Cu")
		(name "$teardrop_padvia$")
		(hatch none 0.1)
		(priority 30777)
		(attr
			(teardrop
				(type padvia)
			)
		)
		(connect_pads yes
			(clearance 0)
		)
		(min_thickness 0.0254)
		(filled_areas_thickness no)
		(fill yes
			(thermal_gap 0.5)
			(thermal_bridge_width 0.5)
			(island_removal_mode 1)
			(island_area_min 10)
		)
		(polygon
			(pts
				(xy 220.422745 159.589387) (xy 220.539071 159.482864) (xy 220.639522 159.422752) (xy 220.68112 159.405257)
				(xy 220.600707 159.199293) (xy 220.394742 159.118879) (xy 220.351141 159.211105) (xy 220.289861 159.293905)
				(xy 220.210613 159.377255)
			)
		)
	)
	(zone
		(net 429)
		(net_name "/2xSFP+/MDIO1.MDC")
		(layer "F.Cu")
		(name "$teardrop_padvia$")
		(hatch none 0.1)
		(priority 31675)
		(attr
			(teardrop
				(type padvia)
			)
		)
		(connect_pads yes
			(clearance 0)
		)
		(min_thickness 0.0254)
		(filled_areas_thickness no)
		(fill yes
			(thermal_gap 0.5)
			(thermal_bridge_width 0.5)
			(island_removal_mode 1)
			(island_area_min 10)
		)
		(polygon
			(pts
				(xy 198.243715 155.394672) (xy 198.283773 155.34807) (xy 198.30874 155.30558) (xy 198.334032 155.216732)
				(xy 198.34988 155.150355) (xy 198.387081 155.075003) (xy 198.200707 154.949293) (xy 198.012919 155.075003)
				(xy 198.071152 155.134761) (xy 198.105221 155.160683) (xy 198.147678 155.193853) (xy 198.176625 155.227176)
				(xy 198.182397 155.263652) (xy 198.155328 155.306285)
			)
		)
	)
	(zone
		(net 771)
		(net_name "/Backplane/PCIe_{x2}.RX1+")
		(layer "F.Cu")
		(name "$teardrop_padvia$")
		(hatch none 0.1)
		(priority 32047)
		(attr
			(teardrop
				(type padvia)
			)
		)
		(connect_pads yes
			(clearance 0)
		)
		(min_thickness 0.0254)
		(filled_areas_thickness no)
		(fill yes
			(thermal_gap 0.5)
			(thermal_bridge_width 0.5)
			(island_removal_mode 1)
			(island_area_min 10)
		)
		(polygon
			(pts
				(xy 314.688 161.309) (xy 314.667928 161.316104) (xy 314.63631 161.325575) (xy 314.622742 161.318649)
				(xy 314.613308 161.297039) (xy 314.362 161.408) (xy 314.608735 161.522015) (xy 314.618866 161.501124)
				(xy 314.632745 161.494069) (xy 314.666773 161.503702) (xy 314.688 161.511)
			)
		)
	)
	(zone
		(net 381)
		(net_name "Net-(J12D-~{SYS_RESET})")
		(layer "F.Cu")
		(name "$teardrop_padvia$")
		(hatch none 0.1)
		(priority 31840)
		(attr
			(teardrop
				(type padvia)
			)
		)
		(connect_pads yes
			(clearance 0)
		)
		(min_thickness 0.0254)
		(filled_areas_thickness no)
		(fill yes
			(thermal_gap 0.5)
			(thermal_bridge_width 0.5)
			(island_removal_mode 1)
			(island_area_min 10)
		)
		(polygon
			(pts
				(xy 193.139127 158.722485) (xy 193.086618 158.768181) (xy 193.040623 158.794768) (xy 192.954174 158.815152)
				(xy 192.938841 158.816988) (xy 192.856105 158.829323) (xy 192.899293 159.050707) (xy 193.120677 159.093895)
				(xy 193.133011 159.01116) (xy 193.153349 158.913881) (xy 193.180057 158.865841) (xy 193.227515 158.810873)
			)
		)
	)
	(zone
		(net 772)
		(net_name "/Backplane/PCIe_{x2}.RX1-")
		(layer "F.Cu")
		(name "$teardrop_padvia$")
		(hatch none 0.1)
		(priority 32042)
		(attr
			(teardrop
				(type padvia)
			)
		)
		(connect_pads yes
			(clearance 0)
		)
		(min_thickness 0.0254)
		(filled_areas_thickness no)
		(fill yes
			(thermal_gap 0.5)
			(thermal_bridge_width 0.5)
			(island_removal_mode 1)
			(island_area_min 10)
		)
		(polygon
			(pts
				(xy 315.472935 161.7676) (xy 315.415479 161.768969) (xy 315.378084 161.777629) (xy 315.299628 161.792761)
				(xy 315.258248 161.792706) (xy 315.216315 161.783) (xy 315.134035 161.907742) (xy 315.4073 161.984069)
				(xy 315.410229 161.949046) (xy 315.415398 161.954597) (xy 315.420631 161.96271)
			)
		)
	)
	(zone
		(net 1)
		(net_name "GND")
		(layer "F.Cu")
		(name "$teardrop_padvia$")
		(hatch none 0.1)
		(priority 30224)
		(attr
			(teardrop
				(type padvia)
			)
		)
		(connect_pads yes
			(clearance 0)
		)
		(min_thickness 0.0254)
		(filled_areas_thickness no)
		(fill yes
			(thermal_gap 0.5)
			(thermal_bridge_width 0.5)
			(island_removal_mode 1)
			(island_area_min 10)
		)
		(polygon
			(pts
				(xy 245.737709 77.922) (xy 245.768317 77.91365) (xy 245.821302 77.903039) (xy 245.844434 77.916044)
				(xy 245.8609 77.952) (xy 246.553709 77.772) (xy 245.8609 77.592) (xy 245.848966 77.621959) (xy 245.832645 77.637272)
				(xy 245.794971 77.639108) (xy 245.768317 77.63035) (xy 245.737709 77.622)
			)
		)
	)
	(zone
		(net 193)
		(net_name "/OCuLink/PCIe_{REF0}.CK-")
		(layer "F.Cu")
		(name "$teardrop_padvia$")
		(hatch none 0.1)
		(priority 32049)
		(attr
			(teardrop
				(type padvia)
			)
		)
		(connect_pads yes
			(clearance 0)
		)
		(min_thickness 0.0254)
		(filled_areas_thickness no)
		(fill yes
			(thermal_gap 0.5)
			(thermal_bridge_width 0.5)
			(island_removal_mode 1)
			(island_area_min 10)
		)
		(polygon
			(pts
				(xy 111.301 152.138) (xy 111.293802 152.117352) (xy 111.284208 152.085016) (xy 111.291035 152.070993)
				(xy 111.3125 152.061004) (xy 111.2 151.812) (xy 111.0875 152.061004) (xy 111.108676 152.070729)
				(xy 111.115731 152.084357) (xy 111.106198 152.117352) (xy 111.099 152.138)
			)
		)
	)
	(zone
		(net 983)
		(net_name "Net-(D31-C)")
		(layer "F.Cu")
		(name "$teardrop_padvia$")
		(hatch none 0.1)
		(priority 30156)
		(attr
			(teardrop
				(type padvia)
			)
		)
		(connect_pads yes
			(clearance 0)
		)
		(min_thickness 0.0254)
		(filled_areas_thickness no)
		(fill yes
			(thermal_gap 0.5)
			(thermal_bridge_width 0.5)
			(island_removal_mode 1)
			(island_area_min 10)
		)
		(polygon
			(pts
				(xy 186.80861 76.062163) (xy 186.81367 76.028644) (xy 186.829091 75.995738) (xy 186.854873 75.965425)
				(xy 186.891483 75.938919) (xy 186.938658 75.918016) (xy 186.997093 75.90393) (xy 187.06861 75.898184)
				(xy 186.70861 75.501163) (xy 186.34861 75.898184) (xy 186.418681 75.903704) (xy 186.477217 75.917567)
				(xy 186.524564 75.938253) (xy 186.561037 75.964231) (xy 186.58712 75.9942) (xy 186.602852 76.026426)
				(xy 186.60861 76.062163)
			)
		)
	)
	(zone
		(net 77)
		(net_name "+5V_AON")
		(layer "F.Cu")
		(name "$teardrop_padvia$")
		(hatch none 0.1)
		(priority 30162)
		(attr
			(teardrop
				(type padvia)
			)
		)
		(connect_pads yes
			(clearance 0)
		)
		(min_thickness 0.0254)
		(filled_areas_thickness no)
		(fill yes
			(thermal_gap 0.5)
			(thermal_bridge_width 0.5)
			(island_removal_mode 1)
			(island_area_min 10)
		)
		(polygon
			(pts
				(xy 188.608611 73.542163) (xy 188.603551 73.575682) (xy 188.58813 73.608588) (xy 188.562348 73.6389)
				(xy 188.525739 73.665407) (xy 188.478563 73.686309) (xy 188.420128 73.700395) (xy 188.34861 73.706141)
				(xy 188.70861 74.103162) (xy 189.06861 73.706141) (xy 188.998539 73.700621) (xy 188.940003 73.686759)
				(xy 188.892656 73.666073) (xy 188.856183 73.640095) (xy 188.830099 73.610127) (xy 188.814368 73.577901)
				(xy 188.80861 73.542164)
			)
		)
	)
	(zone
		(net 1)
		(net_name "GND")
		(layer "F.Cu")
		(name "$teardrop_padvia$")
		(hatch none 0.1)
		(priority 31319)
		(attr
			(teardrop
				(type padvia)
			)
		)
		(connect_pads yes
			(clearance 0)
		)
		(min_thickness 0.0254)
		(filled_areas_thickness no)
		(fill yes
			(thermal_gap 0.5)
			(thermal_bridge_width 0.5)
			(island_removal_mode 1)
			(island_area_min 10)
		)
		(polygon
			(pts
				(xy 210.625 162.187793) (xy 210.629731 162.132196) (xy 210.64285 162.089645) (xy 210.688022 162.027772)
				(xy 210.711704 162.005388) (xy 210.780694 161.931389) (xy 210.6 161.799) (xy 210.383268 161.853421)
				(xy 210.38519 161.861215) (xy 210.416806 162.010064) (xy 210.425 162.187793)
			)
		)
	)
	(zone
		(net 623)
		(net_name "/PCIe redriver/TX_EQ0")
		(layer "F.Cu")
		(name "$teardrop_padvia$")
		(hatch none 0.1)
		(priority 31527)
		(attr
			(teardrop
				(type padvia)
			)
		)
		(connect_pads yes
			(clearance 0)
		)
		(min_thickness 0.0254)
		(filled_areas_thickness no)
		(fill yes
			(thermal_gap 0.5)
			(thermal_bridge_width 0.5)
			(island_removal_mode 1)
			(island_area_min 10)
		)
		(polygon
			(pts
				(xy 112.05793 145.920457) (xy 112.078676 145.922419) (xy 112.096366 145.934581) (xy 112.123426 145.992024)
				(xy 112.136228 146.088946) (xy 112.420707 145.859293) (xy 112.153843 145.604691) (xy 112.125031 145.701072)
				(xy 112.064645 145.781412) (xy 112.025831 145.810646) (xy 111.986765 145.828216) (xy 111.969543 145.83207)
			)
		)
	)
	(zone
		(net 729)
		(net_name "Net-(U43C-AMUXB)")
		(layer "F.Cu")
		(name "$teardrop_padvia$")
		(hatch none 0.1)
		(priority 31715)
		(attr
			(teardrop
				(type padvia)
			)
		)
		(connect_pads yes
			(clearance 0)
		)
		(min_thickness 0.0254)
		(filled_areas_thickness no)
		(fill yes
			(thermal_gap 0.5)
			(thermal_bridge_width 0.5)
			(island_removal_mode 1)
			(island_area_min 10)
		)
		(polygon
			(pts
				(xy 154.3375 129.739323) (xy 154.332682 129.808763) (xy 154.31896 129.860087) (xy 154.272245 129.935628)
				(xy 154.262702 129.947768) (xy 154.212919 130.014997) (xy 154.4 130.141) (xy 154.587081 130.014997)
				(xy 154.537299 129.947769) (xy 154.482894 129.864603) (xy 154.46781 129.811748) (xy 154.4625 129.739323)
			)
		)
	)
	(zone
		(net 1)
		(net_name "GND")
		(layer "F.Cu")
		(name "$teardrop_padvia$")
		(hatch none 0.1)
		(priority 31334)
		(attr
			(teardrop
				(type padvia)
			)
		)
		(connect_pads yes
			(clearance 0)
		)
		(min_thickness 0.0254)
		(filled_areas_thickness no)
		(fill yes
			(thermal_gap 0.5)
			(thermal_bridge_width 0.5)
			(island_removal_mode 1)
			(island_area_min 10)
		)
		(polygon
			(pts
				(xy 177.925 157.532918) (xy 177.920264 157.579515) (xy 177.907115 157.614791) (xy 177.862124 157.662565)
				(xy 177.823324 157.686726) (xy 177.779612 157.713999) (xy 177.737166 157.750749) (xy 177.9 157.901)
				(xy 178.120677 157.880921) (xy 178.119727 157.694822) (xy 178.125 157.532918)
			)
		)
	)
	(zone
		(net 575)
		(net_name "Net-(U18-MODE)")
		(layer "F.Cu")
		(name "$teardrop_padvia$")
		(hatch none 0.1)
		(priority 31893)
		(attr
			(teardrop
				(type padvia)
			)
		)
		(connect_pads yes
			(clearance 0)
		)
		(min_thickness 0.0254)
		(filled_areas_thickness no)
		(fill yes
			(thermal_gap 0.5)
			(thermal_bridge_width 0.5)
			(island_removal_mode 1)
			(island_area_min 10)
		)
		(polygon
			(pts
				(xy 310.225676 121.399499) (xy 310.157105 121.394691) (xy 310.106314 121.381034) (xy 310.031644 121.334532)
				(xy 310.018899 121.324376) (xy 309.950002 121.272919) (xy 309.823999 121.46) (xy 309.950002 121.647081)
				(xy 310.015451 121.599022) (xy 310.099587 121.544688) (xy 310.152774 121.529741) (xy 310.225676 121.524499)
			)
		)
	)
	(zone
		(net 85)
		(net_name "/Com Express 7 MGMT/MAFS_POWER")
		(layer "F.Cu")
		(name "$teardrop_padvia$")
		(hatch none 0.1)
		(priority 30181)
		(attr
			(teardrop
				(type padvia)
			)
		)
		(connect_pads yes
			(clearance 0)
		)
		(min_thickness 0.0254)
		(filled_areas_thickness no)
		(fill yes
			(thermal_gap 0.5)
			(thermal_bridge_width 0.5)
			(island_removal_mode 1)
			(island_area_min 10)
		)
		(polygon
			(pts
				(xy 259.7 161.7305) (xy 259.712931 161.73027) (xy 259.752147 161.731188) (xy 259.792361 161.743669)
				(xy 259.82561 161.779508) (xy 259.843928 161.8505) (xy 260.321 161.5805) (xy 259.843928 161.3105)
				(xy 259.834987 161.358579) (xy 259.819351 161.391905) (xy 259.777196 161.424282) (xy 259.712931 161.43073)
				(xy 259.7 161.4305)
			)
		)
	)
	(zone
		(net 365)
		(net_name "/Com Express 7 MGMT/PWR_OK")
		(layer "F.Cu")
		(name "$teardrop_padvia$")
		(hatch none 0.1)
		(priority 31910)
		(attr
			(teardrop
				(type padvia)
			)
		)
		(connect_pads yes
			(clearance 0)
		)
		(min_thickness 0.0254)
		(filled_areas_thickness no)
		(fill yes
			(thermal_gap 0.5)
			(thermal_bridge_width 0.5)
			(island_removal_mode 1)
			(island_area_min 10)
		)
		(polygon
			(pts
				(xy 190.9625 153.142084) (xy 190.959075 153.026992) (xy 190.957405 152.9443) (xy 190.970677 152.843895)
				(xy 190.75 152.799) (xy 190.624997 152.987081) (xy 190.700896 153.020227) (xy 190.726588 153.027243)
				(xy 190.769607 153.039952) (xy 190.804878 153.058631) (xy 190.828733 153.090326) (xy 190.8375 153.142084)
			)
		)
	)
	(zone
		(net 135)
		(net_name "Net-(D19-Pad3)")
		(layer "F.Cu")
		(name "$teardrop_padvia$")
		(hatch none 0.1)
		(priority 30749)
		(attr
			(teardrop
				(type padvia)
			)
		)
		(connect_pads yes
			(clearance 0)
		)
		(min_thickness 0.0254)
		(filled_areas_thickness no)
		(fill yes
			(thermal_gap 0.5)
			(thermal_bridge_width 0.5)
			(island_removal_mode 1)
			(island_area_min 10)
		)
		(polygon
			(pts
				(xy 309.207 74.96) (xy 309.22209 74.959663) (xy 309.262327 74.96024) (xy 309.303871 74.972054) (xy 309.339165 75.006633)
				(xy 309.360653 75.0755) (xy 309.621 74.81) (xy 309.360653 74.5445) (xy 309.349709 74.590938) (xy 309.33261 74.623135)
				(xy 309.288145 74.654578) (xy 309.22209 74.660337) (xy 309.207 74.66)
			)
		)
	)
	(zone
		(net 348)
		(net_name "Net-(J12D-~{LPC_FRAME}{slash}~{ESPI_CS0})")
		(layer "F.Cu")
		(name "$teardrop_padvia$")
		(hatch none 0.1)
		(priority 31909)
		(attr
			(teardrop
				(type padvia)
			)
		)
		(connect_pads yes
			(clearance 0)
		)
		(min_thickness 0.0254)
		(filled_areas_thickness no)
		(fill yes
			(thermal_gap 0.5)
			(thermal_bridge_width 0.5)
			(island_removal_mode 1)
			(island_area_min 10)
		)
		(polygon
			(pts
				(xy 175.39215 164.103762) (xy 175.366242 164.071117) (xy 175.354698 164.040694) (xy 175.361724 163.985191)
				(xy 175.38307 163.939636) (xy 175.420677 163.843895) (xy 175.199293 163.799293) (xy 175.074997 163.987081)
				(xy 175.16272 164.05187) (xy 175.228084 164.114715) (xy 175.240778 164.127843) (xy 175.303762 164.19215)
			)
		)
	)
	(zone
		(net 1)
		(net_name "GND")
		(layer "F.Cu")
		(name "$teardrop_padvia$")
		(hatch none 0.1)
		(priority 30023)
		(attr
			(teardrop
				(type padvia)
			)
		)
		(connect_pads yes
			(clearance 0)
		)
		(min_thickness 0.0254)
		(filled_areas_thickness no)
		(fill yes
			(thermal_gap 0.5)
			(thermal_bridge_width 0.5)
			(island_removal_mode 1)
			(island_area_min 10)
		)
		(polygon
			(pts
				(xy 285.938 74.81) (xy 285.898208 74.804995) (xy 285.859942 74.789958) (xy 285.790841 74.72943)
				(xy 285.735318 74.623324) (xy 285.702446 74.465393) (xy 285.698 74.368672) (xy 285.097 74.81) (xy 285.698 75.465715)
				(xy 285.702777 75.386294) (xy 285.716219 75.317777) (xy 285.737177 75.259354) (xy 285.764212 75.211194)
				(xy 285.833093 75.142675) (xy 285.913804 75.111713) (xy 285.938 75.11)
			)
		)
	)
	(zone
		(net 21)
		(net_name "/M.2 key E/PCIE_{REF}.CK-")
		(layer "F.Cu")
		(name "$teardrop_padvia$")
		(hatch none 0.1)
		(priority 30433)
		(attr
			(teardrop
				(type padvia)
			)
		)
		(connect_pads yes
			(clearance 0)
		)
		(min_thickness 0.0254)
		(filled_areas_thickness no)
		(fill yes
			(thermal_gap 0.5)
			(thermal_bridge_width 0.5)
			(island_removal_mode 1)
			(island_area_min 10)
		)
		(polygon
			(pts
				(xy 214.3865 135.845521) (xy 214.344541 135.767271) (xy 214.308528 135.668715) (xy 214.29317 135.59184)
				(xy 214.290559 135.511574) (xy 214.3 135.448245) (xy 213.98 135.479) (xy 213.881086 135.775) (xy 214.005471 135.772186)
				(xy 214.096359 135.784709) (xy 214.138391 135.801698) (xy 214.170036 135.826551) (xy 214.1845 135.845521)
			)
		)
	)
	(zone
		(net 325)
		(net_name "/Com Express 7 Interfaces/PCIe_{B2Ax4}.TX0-")
		(layer "F.Cu")
		(name "$teardrop_padvia$")
		(hatch none 0.1)
		(priority 31595)
		(attr
			(teardrop
				(type padvia)
			)
		)
		(connect_pads yes
			(clearance 0)
		)
		(min_thickness 0.0254)
		(filled_areas_thickness no)
		(fill yes
			(thermal_gap 0.5)
			(thermal_bridge_width 0.5)
			(island_removal_mode 1)
			(island_area_min 10)
		)
		(polygon
			(pts
				(xy 211.576624 167.281288) (xy 211.562862 167.260855) (xy 211.565998 167.245581) (xy 211.601515 167.226675)
				(xy 211.636458 167.216935) (xy 211.718503 167.187081) (xy 211.592793 166.999293) (xy 211.373004 167.044333)
				(xy 211.377097 167.143408) (xy 211.370227 167.195029) (xy 211.363202 167.251042) (xy 211.365556 167.306168)
				(xy 211.386136 167.362997) (xy 211.433789 167.424123)
			)
		)
	)
	(zone
		(net 112)
		(net_name "/2xSFP+/KR to SFI #1/KR_C.TX+")
		(layer "F.Cu")
		(name "$teardrop_padvia$")
		(hatch none 0.1)
		(priority 31952)
		(attr
			(teardrop
				(type padvia)
			)
		)
		(connect_pads yes
			(clearance 0)
		)
		(min_thickness 0.0254)
		(filled_areas_thickness no)
		(fill yes
			(thermal_gap 0.5)
			(thermal_bridge_width 0.5)
			(island_removal_mode 1)
			(island_area_min 10)
		)
		(polygon
			(pts
				(xy 155.68 146.717279) (xy 155.668264 146.740315) (xy 155.645802 146.756014) (xy 155.569443 146.765137)
				(xy 155.511231 146.76) (xy 155.57 146.991) (xy 155.77 147.018536) (xy 155.774353 146.919743) (xy 155.815938 146.786651)
				(xy 155.84 146.717279)
			)
		)
	)
	(zone
		(net 536)
		(net_name "Net-(Q3-D)")
		(layer "F.Cu")
		(name "$teardrop_padvia$")
		(hatch none 0.1)
		(priority 30912)
		(attr
			(teardrop
				(type padvia)
			)
		)
		(connect_pads yes
			(clearance 0)
		)
		(min_thickness 0.0254)
		(filled_areas_thickness no)
		(fill yes
			(thermal_gap 0.5)
			(thermal_bridge_width 0.5)
			(island_removal_mode 1)
			(island_area_min 10)
		)
		(polygon
			(pts
				(xy 292.012 96.998) (xy 292.01211 97.005134) (xy 292.011338 97.029135) (xy 292.002689 97.053142)
				(xy 291.978161 97.071612) (xy 291.92975 97.079) (xy 292.112 97.575) (xy 292.29425 97.079) (xy 292.254341 97.074431)
				(xy 292.229878 97.062448) (xy 292.212601 97.028675) (xy 292.21189 97.005134) (xy 292.212 96.998)
			)
		)
	)
	(zone
		(net 1)
		(net_name "GND")
		(layer "F.Cu")
		(name "$teardrop_padvia$")
		(hatch none 0.1)
		(priority 30468)
		(attr
			(teardrop
				(type padvia)
			)
		)
		(connect_pads yes
			(clearance 0)
		)
		(min_thickness 0.0254)
		(filled_areas_thickness no)
		(fill yes
			(thermal_gap 0.5)
			(thermal_bridge_width 0.5)
			(island_removal_mode 1)
			(island_area_min 10)
		)
		(polygon
			(pts
				(xy 309.737 82.47) (xy 309.75387 82.469662) (xy 309.798826 82.470241) (xy 309.846169 82.482059)
				(xy 309.888573 82.516638) (xy 309.918708 82.5855) (xy 310.176 82.32) (xy 309.918708 82.0545) (xy 309.903151 82.099269)
				(xy 309.882435 82.130885) (xy 309.831299 82.163619) (xy 309.75387 82.170338) (xy 309.737 82.17)
			)
		)
	)
	(zone
		(net 771)
		(net_name "/Backplane/PCIe_{x2}.RX1+")
		(layer "F.Cu")
		(name "$teardrop_padvia$")
		(hatch none 0.1)
		(priority 30021)
		(attr
			(teardrop
				(type padvia)
			)
		)
		(connect_pads yes
			(clearance 0)
		)
		(min_thickness 0.0254)
		(filled_areas_thickness no)
		(fill yes
			(thermal_gap 0.5)
			(thermal_bridge_width 0.5)
			(island_removal_mode 1)
			(island_area_min 10)
		)
		(polygon
			(pts
				(xy 317.860744 162.0165) (xy 318.255858 161.999246) (xy 318.69849 161.977362) (xy 318.959827 161.975348)
				(xy 319.254117 161.985) (xy 319.451 161.71) (xy 317.95 161.654408) (xy 317.950007 161.713332) (xy 317.940774 161.756415)
				(xy 317.925619 161.784485) (xy 317.906098 161.802295) (xy 317.860744 161.8145)
			)
		)
	)
	(zone
		(net 426)
		(net_name "Net-(J12K-10G_SDP0)")
		(layer "F.Cu")
		(name "$teardrop_padvia$")
		(hatch none 0.1)
		(priority 31770)
		(attr
			(teardrop
				(type padvia)
			)
		)
		(connect_pads yes
			(clearance 0)
		)
		(min_thickness 0.0254)
		(filled_areas_thickness no)
		(fill yes
			(thermal_gap 0.5)
			(thermal_bridge_width 0.5)
			(island_removal_mode 1)
			(island_area_min 10)
		)
		(polygon
			(pts
				(xy 196.674323 158.5125) (xy 196.743764 158.517318) (xy 196.795088 158.53104) (xy 196.870629 158.577755)
				(xy 196.882769 158.587299) (xy 196.949997 158.637081) (xy 197.076 158.45) (xy 196.949997 158.262919)
				(xy 196.882768 158.312702) (xy 196.799602 158.367106) (xy 196.746748 158.38219) (xy 196.674323 158.3875)
			)
		)
	)
	(zone
		(net 772)
		(net_name "/Backplane/PCIe_{x2}.RX1-")
		(layer "F.Cu")
		(name "$teardrop_padvia$")
		(hatch none 0.1)
		(priority 30274)
		(attr
			(teardrop
				(type padvia)
			)
		)
		(connect_pads yes
			(clearance 0)
		)
		(min_thickness 0.0254)
		(filled_areas_thickness no)
		(fill yes
			(thermal_gap 0.5)
			(thermal_bridge_width 0.5)
			(island_removal_mode 1)
			(island_area_min 10)
		)
		(polygon
			(pts
				(xy 203.3685 155.75) (xy 203.379599 155.923112) (xy 203.394216 156.15051) (xy 203.391181 156.285138)
				(xy 203.375 156.437021) (xy 203.525 156.686) (xy 203.608295 155.81) (xy 203.577864 155.805523) (xy 203.565097 155.794185)
				(xy 203.56742 155.764227) (xy 203.5705 155.75)
			)
		)
	)
	(zone
		(net 73)
		(net_name "+3V3_AON")
		(layer "F.Cu")
		(name "$teardrop_padvia$")
		(hatch none 0.1)
		(priority 30164)
		(attr
			(teardrop
				(type padvia)
			)
		)
		(connect_pads yes
			(clearance 0)
		)
		(min_thickness 0.0254)
		(filled_areas_thickness no)
		(fill yes
			(thermal_gap 0.5)
			(thermal_bridge_width 0.5)
			(island_removal_mode 1)
			(island_area_min 10)
		)
		(polygon
			(pts
				(xy 221.109129 80.818077) (xy 221.026778 80.763646) (xy 220.964488 80.727024) (xy 220.90667 80.680109)
				(xy 220.864086 80.616091) (xy 220.8475 80.528162) (xy 220.546793 80.609293) (xy 220.665662 81.11)
				(xy 220.698407 81.080825) (xy 220.720066 81.075158) (xy 220.737423 81.095898) (xy 220.745322 81.134118)
				(xy 220.755577 81.171629)
			)
		)
	)
	(zone
		(net 2)
		(net_name "+3V3")
		(layer "F.Cu")
		(name "$teardrop_padvia$")
		(hatch none 0.1)
		(priority 30333)
		(attr
			(teardrop
				(type padvia)
			)
		)
		(connect_pads yes
			(clearance 0)
		)
		(min_thickness 0.0254)
		(filled_areas_thickness no)
		(fill yes
			(thermal_gap 0.5)
			(thermal_bridge_width 0.5)
			(island_removal_mode 1)
			(island_area_min 10)
		)
		(polygon
			(pts
				(xy 239.584039 78.705461) (xy 239.624585 78.75417) (xy 239.659535 78.817976) (xy 239.678331 78.876861)
				(xy 239.68697 78.944441) (xy 239.68 79.035474) (xy 240.000707 78.980707) (xy 240.080474 78.685)
				(xy 239.947289 78.679956) (xy 239.83195 78.641148) (xy 239.736127 78.574323) (xy 239.725461 78.564039)
			)
		)
	)
	(zone
		(net 52)
		(net_name "+5V")
		(layer "F.Cu")
		(hatch edge 0.5)
		(priority 28)
		(connect_pads yes
			(clearance 0.15)
		)
		(min_thickness 0.25)
		(filled_areas_thickness no)
		(fill yes
			(thermal_gap 0.5)
			(thermal_bridge_width 0.5)
			(smoothing fillet)
			(radius 0.2)
		)
		(polygon
			(pts
				(xy 291.45 102.31) (xy 294.75 102.31) (xy 294.75 98.56) (xy 291.45 98.56)
			)
		)
	)
	(zone
		(net 537)
		(net_name "/Backplane/PCIe_{x2}.RX0-")
		(layer "F.Cu")
		(name "$teardrop_padvia$")
		(hatch none 0.1)
		(priority 31375)
		(attr
			(teardrop
				(type padvia)
			)
		)
		(connect_pads yes
			(clearance 0)
		)
		(min_thickness 0.0254)
		(filled_areas_thickness no)
		(fill yes
			(thermal_gap 0.5)
			(thermal_bridge_width 0.5)
			(island_removal_mode 1)
			(island_area_min 10)
		)
		(polygon
			(pts
				(xy 220.032504 153.6455) (xy 220.07929 153.650235) (xy 220.114742 153.663379) (xy 220.162939 153.708387)
				(xy 220.187116 153.746608) (xy 220.214485 153.789773) (xy 220.251147 153.831731) (xy 220.401 153.6685)
				(xy 220.38014 153.447823) (xy 220.279466 153.452452) (xy 220.196096 153.449019) (xy 220.194035 153.448895)
				(xy 220.032504 153.4435)
			)
		)
	)
	(zone
		(net 1)
		(net_name "GND")
		(layer "F.Cu")
		(name "$teardrop_padvia$")
		(hatch none 0.1)
		(priority 30541)
		(attr
			(teardrop
				(type padvia)
			)
		)
		(connect_pads yes
			(clearance 0)
		)
		(min_thickness 0.0254)
		(filled_areas_thickness no)
		(fill yes
			(thermal_gap 0.5)
			(thermal_bridge_width 0.5)
			(island_removal_mode 1)
			(island_area_min 10)
		)
		(polygon
			(pts
				(xy 176.425 150.2) (xy 176.428333 150.214486) (xy 176.43119 150.24461) (xy 176.419036 150.255651)
				(xy 176.39 150.26) (xy 176.525 151.136) (xy 176.66 150.26) (xy 176.630666 150.255525) (xy 176.618642 150.244199)
				(xy 176.621667 150.214486) (xy 176.625 150.2)
			)
		)
	)
	(zone
		(net 534)
		(net_name "Net-(Q1-D)")
		(layer "F.Cu")
		(name "$teardrop_padvia$")
		(hatch none 0.1)
		(priority 30843)
		(attr
			(teardrop
				(type padvia)
			)
		)
		(connect_pads yes
			(clearance 0)
		)
		(min_thickness 0.0254)
		(filled_areas_thickness no)
		(fill yes
			(thermal_gap 0.5)
			(thermal_bridge_width 0.5)
			(island_removal_mode 1)
			(island_area_min 10)
		)
		(polygon
			(pts
				(xy 307.47 139.522) (xy 307.46379 139.568211) (xy 307.440323 139.61661) (xy 307.412416 139.644966)
				(xy 307.37219 139.668012) (xy 307.318202 139.683202) (xy 307.57 139.961) (xy 307.821798 139.683202)
				(xy 307.772946 139.670069) (xy 307.735436 139.650665) (xy 307.688013 139.598055) (xy 307.670257 139.531554)
				(xy 307.67 139.522)
			)
		)
	)
	(zone
		(net 111)
		(net_name "/2xSFP+/10GKR_SFP0.TX+")
		(layer "F.Cu")
		(name "$teardrop_padvia$")
		(hatch none 0.1)
		(priority 30902)
		(attr
			(teardrop
				(type padvia)
			)
		)
		(connect_pads yes
			(clearance 0)
		)
		(min_thickness 0.0254)
		(filled_areas_thickness no)
		(fill yes
			(thermal_gap 0.5)
			(thermal_bridge_width 0.5)
			(island_removal_mode 1)
			(island_area_min 10)
		)
		(polygon
			(pts
				(xy 200.165 152.07) (xy 200.159583 152.052612) (xy 200.152109 152.024257) (xy 200.157669 152.014015)
				(xy 200.175 152.01) (xy 200.025 151.134) (xy 199.945877 152.01) (xy 199.979579 152.014497) (xy 199.997541 152.025975)
				(xy 200.005255 152.062548) (xy 200.005 152.07)
			)
		)
	)
	(zone
		(net 423)
		(net_name "/2xSFP+/I2C_{LED}.SCL")
		(layer "F.Cu")
		(name "$teardrop_padvia$")
		(hatch none 0.1)
		(priority 31777)
		(attr
			(teardrop
				(type padvia)
			)
		)
		(connect_pads yes
			(clearance 0)
		)
		(min_thickness 0.0254)
		(filled_areas_thickness no)
		(fill yes
			(thermal_gap 0.5)
			(thermal_bridge_width 0.5)
			(island_removal_mode 1)
			(island_area_min 10)
		)
		(polygon
			(pts
				(xy 161.0125 154.600677) (xy 161.017318 154.531236) (xy 161.03104 154.479912) (xy 161.077755 154.40437)
				(xy 161.087299 154.392229) (xy 161.137081 154.325003) (xy 160.95 154.199) (xy 160.762919 154.325003)
				(xy 160.812701 154.392231) (xy 160.867106 154.475397) (xy 160.88219 154.528251) (xy 160.8875 154.600677)
			)
		)
	)
	(zone
		(net 220)
		(net_name "/Com Express 7 Interfaces/PCIe_{B1x4}.TX1+")
		(layer "F.Cu")
		(name "$teardrop_padvia$")
		(hatch none 0.1)
		(priority 30251)
		(attr
			(teardrop
				(type padvia)
			)
		)
		(connect_pads yes
			(clearance 0)
		)
		(min_thickness 0.0254)
		(filled_areas_thickness no)
		(fill yes
			(thermal_gap 0.5)
			(thermal_bridge_width 0.5)
			(island_removal_mode 1)
			(island_area_min 10)
		)
		(polygon
			(pts
				(xy 207.4795 167.75) (xy 207.48258 167.764227) (xy 207.484749 167.794527) (xy 207.471877 167.805628)
				(xy 207.441705 167.81) (xy 207.525 168.686) (xy 207.675 168.437021) (xy 207.655644 168.195818) (xy 207.670401 167.923112)
				(xy 207.6815 167.75)
			)
		)
	)
	(zone
		(net 2)
		(net_name "+3V3")
		(layer "F.Cu")
		(name "$teardrop_padvia$")
		(hatch none 0.1)
		(priority 30400)
		(attr
			(teardrop
				(type padvia)
			)
		)
		(connect_pads yes
			(clearance 0)
		)
		(min_thickness 0.0254)
		(filled_areas_thickness no)
		(fill yes
			(thermal_gap 0.5)
			(thermal_bridge_width 0.5)
			(island_removal_mode 1)
			(island_area_min 10)
		)
		(polygon
			(pts
				(xy 120.65 149.314) (xy 120.629597 149.269355) (xy 120.610779 149.235808) (xy 120.602205 149.203345)
				(xy 120.616303 149.176635) (xy 120.6655 149.160347) (xy 120.4 148.9) (xy 120.1345 149.160347) (xy 120.172593 149.170167)
				(xy 120.192358 149.185574) (xy 120.195352 149.2199) (xy 120.170403 149.269355) (xy 120.15 149.314)
			)
		)
	)
	(zone
		(net 197)
		(net_name "/OCuLink/PCIe_{x4}.RX3-")
		(layer "F.Cu")
		(name "$teardrop_padvia$")
		(hatch none 0.1)
		(priority 32083)
		(attr
			(teardrop
				(type padvia)
			)
		)
		(connect_pads yes
			(clearance 0)
		)
		(min_thickness 0.0254)
		(filled_areas_thickness no)
		(fill yes
			(thermal_gap 0.5)
			(thermal_bridge_width 0.5)
			(island_removal_mode 1)
			(island_area_min 10)
		)
		(polygon
			(pts
				(xy 106.501 151.488) (xy 106.508198 151.508648) (xy 106.517792 151.540984) (xy 106.510965 151.555007)
				(xy 106.4895 151.564995) (xy 106.602 151.814) (xy 106.7145 151.564995) (xy 106.693324 151.555271)
				(xy 106.686269 151.541643) (xy 106.695802 151.508648) (xy 106.703 151.488)
			)
		)
	)
	(zone
		(net 331)
		(net_name "/Com Express 7 Interfaces/PCIe_{B2Ax4}.TX3-")
		(layer "F.Cu")
		(name "$teardrop_padvia$")
		(hatch none 0.1)
		(priority 30511)
		(attr
			(teardrop
				(type padvia)
			)
		)
		(connect_pads yes
			(clearance 0)
		)
		(min_thickness 0.0254)
		(filled_areas_thickness no)
		(fill yes
			(thermal_gap 0.5)
			(thermal_bridge_width 0.5)
			(island_removal_mode 1)
			(island_area_min 10)
		)
		(polygon
			(pts
				(xy 216.424 167.75) (xy 216.427537 167.764678) (xy 216.430808 167.794685) (xy 216.418857 167.805673)
				(xy 216.39 167.81) (xy 216.525 168.686) (xy 216.66 167.81) (xy 216.630796 167.805525) (xy 216.619003 167.794203)
				(xy 216.622463 167.764678) (xy 216.626 167.75)
			)
		)
	)
	(zone
		(net 142)
		(net_name "/2xSFP+/PHY0_{RESET}")
		(layer "F.Cu")
		(name "$teardrop_padvia$")
		(hatch none 0.1)
		(priority 31897)
		(attr
			(teardrop
				(type padvia)
			)
		)
		(connect_pads yes
			(clearance 0)
		)
		(min_thickness 0.0254)
		(filled_areas_thickness no)
		(fill yes
			(thermal_gap 0.5)
			(thermal_bridge_width 0.5)
			(island_removal_mode 1)
			(island_area_min 10)
		)
		(polygon
			(pts
				(xy 159.8125 148.047123) (xy 159.807916 147.972054) (xy 159.795824 147.915166) (xy 159.766784 147.841869)
				(xy 159.742087 147.783191) (xy 159.720677 147.706105) (xy 159.5 147.749) (xy 159.456105 147.970677)
				(xy 159.557959 147.972773) (xy 159.60785 147.970825) (xy 159.649085 147.977199) (xy 159.677143 147.999947)
				(xy 159.6875 148.047123)
			)
		)
	)
	(zone
		(net 87)
		(net_name "/Com Express 7 Interfaces/PCIe_{B2Ax4}.RX1-")
		(layer "F.Cu")
		(name "$teardrop_padvia$")
		(hatch none 0.1)
		(priority 31336)
		(attr
			(teardrop
				(type padvia)
			)
		)
		(connect_pads yes
			(clearance 0)
		)
		(min_thickness 0.0254)
		(filled_areas_thickness no)
		(fill yes
			(thermal_gap 0.5)
			(thermal_bridge_width 0.5)
			(island_removal_mode 1)
			(island_area_min 10)
		)
		(polygon
			(pts
				(xy 212.868809 160.650908) (xy 212.839075 160.614477) (xy 212.823301 160.580114) (xy 212.821045 160.514209)
				(xy 212.830976 160.470087) (xy 212.842147 160.420211) (xy 212.845891 160.364618) (xy 212.624507 160.374079)
				(xy 212.483214 160.54487) (xy 212.557673 160.612783) (xy 212.614195 160.67416) (xy 212.615566 160.675707)
				(xy 212.725973 160.793744)
			)
		)
	)
	(zone
		(net 872)
		(net_name "Net-(U34-~{KILL})")
		(layer "F.Cu")
		(name "$teardrop_padvia$")
		(hatch none 0.1)
		(priority 30974)
		(attr
			(teardrop
				(type padvia)
			)
		)
		(connect_pads yes
			(clearance 0)
		)
		(min_thickness 0.0254)
		(filled_areas_thickness no)
		(fill yes
			(thermal_gap 0.5)
			(thermal_bridge_width 0.5)
			(island_removal_mode 1)
			(island_area_min 10)
		)
		(polygon
			(pts
				(xy 246.362 131.9425) (xy 246.424866 131.962469) (xy 246.456844 131.988921) (xy 246.485358 132.026332)
				(xy 246.507882 132.073527) (xy 246.523093 132.131167) (xy 246.523202 132.131798) (xy 246.801 131.88)
				(xy 246.523202 131.628202) (xy 246.508905 131.683635) (xy 246.487825 131.72952) (xy 246.46046 131.767201)
				(xy 246.429552 131.794434) (xy 246.396265 131.811472) (xy 246.363434 131.817489) (xy 246.362 131.8175)
			)
		)
	)
	(zone
		(net 601)
		(net_name "Net-(U36-~{WP}(D2))")
		(layer "F.Cu")
		(name "$teardrop_padvia$")
		(hatch none 0.1)
		(priority 30486)
		(attr
			(teardrop
				(type padvia)
			)
		)
		(connect_pads yes
			(clearance 0)
		)
		(min_thickness 0.0254)
		(filled_areas_thickness no)
		(fill yes
			(thermal_gap 0.5)
			(thermal_bridge_width 0.5)
			(island_removal_mode 1)
			(island_area_min 10)
		)
		(polygon
			(pts
				(xy 257.818945 160.989444) (xy 257.902287 160.934065) (xy 258.032276 160.897846) (xy 258.112866 160.891483)
				(xy 258.200474 160.895) (xy 258.120707 160.599293) (xy 257.8 160.544527) (xy 257.809019 160.695684)
				(xy 257.799175 160.763214) (xy 257.78091 160.822025) (xy 257.730557 160.901056)
			)
		)
	)
	(zone
		(net 243)
		(net_name "/Com Express 7 Interfaces/PCIe_{B2Bx4}.RX2-")
		(layer "F.Cu")
		(name "$teardrop_padvia$")
		(hatch none 0.1)
		(priority 30280)
		(attr
			(teardrop
				(type padvia)
			)
		)
		(connect_pads yes
			(clearance 0)
		)
		(min_thickness 0.0254)
		(filled_areas_thickness no)
		(fill yes
			(thermal_gap 0.5)
			(thermal_bridge_width 0.5)
			(island_removal_mode 1)
			(island_area_min 10)
		)
		(polygon
			(pts
				(xy 188.3685 162.2) (xy 188.379599 162.373112) (xy 188.394216 162.60051) (xy 188.391181 162.735138)
				(xy 188.375 162.887021) (xy 188.525 163.136) (xy 188.608295 162.26) (xy 188.577864 162.255523) (xy 188.565097 162.244185)
				(xy 188.56742 162.214227) (xy 188.5705 162.2)
			)
		)
	)
	(zone
		(net 979)
		(net_name "Net-(D26-C)")
		(layer "F.Cu")
		(name "$teardrop_padvia$")
		(hatch none 0.1)
		(priority 30881)
		(attr
			(teardrop
				(type padvia)
			)
		)
		(connect_pads yes
			(clearance 0)
		)
		(min_thickness 0.0254)
		(filled_areas_thickness no)
		(fill yes
			(thermal_gap 0.5)
			(thermal_bridge_width 0.5)
			(island_removal_mode 1)
			(island_area_min 10)
		)
		(polygon
			(pts
				(xy 201.60861 76.259163) (xy 201.602838 76.2999) (xy 201.582434 76.341815) (xy 201.555259 76.370116)
				(xy 201.515713 76.393544) (xy 201.44311 76.412815) (xy 201.70861 76.673163) (xy 201.97411 76.412815)
				(xy 201.920968 76.400948) (xy 201.879929 76.382501) (xy 201.828228 76.331827) (xy 201.808892 76.268258)
				(xy 201.80861 76.259163)
			)
		)
	)
	(zone
		(net 409)
		(net_name "Net-(J12K-10G_SDP2)")
		(layer "F.Cu")
		(name "$teardrop_padvia$")
		(hatch none 0.1)
		(priority 30643)
		(attr
			(teardrop
				(type padvia)
			)
		)
		(connect_pads yes
			(clearance 0)
		)
		(min_thickness 0.0254)
		(filled_areas_thickness no)
		(fill yes
			(thermal_gap 0.5)
			(thermal_bridge_width 0.5)
			(island_removal_mode 1)
			(island_area_min 10)
		)
		(polygon
			(pts
				(xy 184.0875 157.62) (xy 184.098438 157.581177) (xy 184.120195 157.566067) (xy 184.16 157.56) (xy 184.025 156.684)
				(xy 183.89 157.56) (xy 183.925281 157.564517) (xy 183.946797 157.576138) (xy 183.961995 157.608961)
				(xy 183.9625 157.62)
			)
		)
	)
	(zone
		(net 565)
		(net_name "/2xSFP+/~{LED1_0}")
		(layer "F.Cu")
		(name "$teardrop_padvia$")
		(hatch none 0.1)
		(priority 31314)
		(attr
			(teardrop
				(type padvia)
			)
		)
		(connect_pads yes
			(clearance 0)
		)
		(min_thickness 0.0254)
		(filled_areas_thickness no)
		(fill yes
			(thermal_gap 0.5)
			(thermal_bridge_width 0.5)
			(island_removal_mode 1)
			(island_area_min 10)
		)
		(polygon
			(pts
				(xy 156.165368 160.7955) (xy 156.103072 160.800293) (xy 156.008523 160.806662) (xy 155.963923 160.80278)
				(xy 155.9265 160.79) (xy 155.778 161.11) (xy 156.074 161.234175) (xy 156.070833 161.115612) (xy 156.080689 161.021228)
				(xy 156.096296 160.971765) (xy 156.119704 160.938098) (xy 156.165368 160.9205)
			)
		)
	)
	(zone
		(net 207)
		(net_name "/Backplane/UART.TX")
		(layer "F.Cu")
		(name "$teardrop_padvia$")
		(hatch none 0.1)
		(priority 32110)
		(attr
			(teardrop
				(type padvia)
			)
		)
		(connect_pads yes
			(clearance 0)
		)
		(min_thickness 0.0254)
		(filled_areas_thickness no)
		(fill yes
			(thermal_gap 0.5)
			(thermal_bridge_width 0.5)
			(island_removal_mode 1)
			(island_area_min 10)
		)
		(polygon
			(pts
				(xy 314.81 168.0705) (xy 314.816322 168.070404) (xy 314.855825 168.075989) (xy 314.874047 168.090922)
				(xy 314.886995 168.1205) (xy 315.136 168.008) (xy 314.886995 167.8955) (xy 314.875879 167.922493)
				(xy 314.860352 167.937595) (xy 314.816322 167.945596) (xy 314.81 167.9455)
			)
		)
	)
	(zone
		(net 702)
		(net_name "/USB-C console/FTDI_CBUS3")
		(layer "F.Cu")
		(name "$teardrop_padvia$")
		(hatch none 0.1)
		(priority 30100)
		(attr
			(teardrop
				(type padvia)
			)
		)
		(connect_pads yes
			(clearance 0)
		)
		(min_thickness 0.0254)
		(filled_areas_thickness no)
		(fill yes
			(thermal_gap 0.5)
			(thermal_bridge_width 0.5)
			(island_removal_mode 1)
			(island_area_min 10)
		)
		(polygon
			(pts
				(xy 117.567205 76.2125) (xy 117.649265 76.217315) (xy 117.714611 76.231019) (xy 117.807878 76.277576)
				(xy 117.88634 76.345786) (xy 117.94784 76.401942) (xy 118.02666 76.461801) (xy 118.235999 76.15)
				(xy 118.02666 75.838199) (xy 117.906482 75.935219) (xy 117.88634 75.954214) (xy 117.827457 76.007366)
				(xy 117.763374 76.049592) (xy 117.68099 76.07745) (xy 117.567205 76.0875)
			)
		)
	)
	(zone
		(net 375)
		(net_name "/2xUSB3.0+RJ45/USB_2.D+")
		(layer "F.Cu")
		(name "$teardrop_padvia$")
		(hatch none 0.1)
		(priority 31542)
		(attr
			(teardrop
				(type padvia)
			)
		)
		(connect_pads yes
			(clearance 0)
		)
		(min_thickness 0.0254)
		(filled_areas_thickness no)
		(fill yes
			(thermal_gap 0.5)
			(thermal_bridge_width 0.5)
			(island_removal_mode 1)
			(island_area_min 10)
		)
		(polygon
			(pts
				(xy 152.485321 115.504822) (xy 152.345058 115.377993) (xy 152.229236 115.273236) (xy 152.071251 115.427335)
				(xy 152.115853 115.648719) (xy 152.195455 115.620898) (xy 152.23521 115.604771) (xy 152.273538 115.597197)
				(xy 152.312588 115.605157) (xy 152.354506 115.635637)
			)
		)
	)
	(zone
		(net 69)
		(net_name "Net-(C48-Pad2)")
		(layer "F.Cu")
		(hatch edge 0.5)
		(priority 47)
		(connect_pads yes
			(clearance 0.15)
		)
		(min_thickness 0.25)
		(filled_areas_thickness no)
		(fill yes
			(thermal_gap 0.5)
			(thermal_bridge_width 0.5)
		)
		(polygon
			(pts
				(xy 314.364999 106.26) (xy 314.514999 106.41) (xy 314.514999 113.61) (xy 314.264999 113.86) (xy 311.914999 113.86)
				(xy 311.664999 113.61) (xy 311.664999 106.86) (xy 312.014999 106.51) (xy 313.56 106.51) (xy 313.81 106.26)
			)
		)
	)
	(zone
		(net 1)
		(net_name "GND")
		(layer "F.Cu")
		(name "$teardrop_padvia$")
		(hatch none 0.1)
		(priority 30957)
		(attr
			(teardrop
				(type padvia)
			)
		)
		(connect_pads yes
			(clearance 0)
		)
		(min_thickness 0.0254)
		(filled_areas_thickness no)
		(fill yes
			(thermal_gap 0.5)
			(thermal_bridge_width 0.5)
			(island_removal_mode 1)
			(island_area_min 10)
		)
		(polygon
			(pts
				(xy 113.3175 145.422) (xy 113.297531 145.484866) (xy 113.271079 145.516844) (xy 113.233668 145.545358)
				(xy 113.186473 145.567882) (xy 113.128833 145.583093) (xy 113.128202 145.583202) (xy 113.38 145.861)
				(xy 113.631798 145.583202) (xy 113.576365 145.568905) (xy 113.53048 145.547825) (xy 113.492799 145.52046)
				(xy 113.465566 145.489552) (xy 113.448528 145.456265) (xy 113.442511 145.423434) (xy 113.4425 145.422)
			)
		)
	)
	(zone
		(net 529)
		(net_name "/M.2 key M #1/~{CLKREQ}")
		(layer "F.Cu")
		(name "$teardrop_padvia$")
		(hatch none 0.1)
		(priority 31809)
		(attr
			(teardrop
				(type padvia)
			)
		)
		(connect_pads yes
			(clearance 0)
		)
		(min_thickness 0.0254)
		(filled_areas_thickness no)
		(fill yes
			(thermal_gap 0.5)
			(thermal_bridge_width 0.5)
			(island_removal_mode 1)
			(island_area_min 10)
		)
		(polygon
			(pts
				(xy 178.130492 105.79313) (xy 178.061051 105.788312) (xy 178.009728 105.77459) (xy 177.934186 105.727876)
				(xy 177.922046 105.718331) (xy 177.854818 105.668549) (xy 177.728815 105.85563) (xy 177.854818 106.042711)
				(xy 177.922044 105.992929) (xy 178.005211 105.938524) (xy 178.058066 105.92344) (xy 178.130492 105.91813)
			)
		)
	)
	(zone
		(net 2)
		(net_name "+3V3")
		(layer "F.Cu")
		(name "$teardrop_padvia$")
		(hatch none 0.1)
		(priority 31832)
		(attr
			(teardrop
				(type padvia)
			)
		)
		(connect_pads yes
			(clearance 0)
		)
		(min_thickness 0.0254)
		(filled_areas_thickness no)
		(fill yes
			(thermal_gap 0.5)
			(thermal_bridge_width 0.5)
			(island_removal_mode 1)
			(island_area_min 10)
		)
		(polygon
			(pts
				(xy 298.600677 84.4275) (xy 298.531236 84.422682) (xy 298.479913 84.40896) (xy 298.404371 84.362246)
				(xy 298.392231 84.352701) (xy 298.325003 84.302919) (xy 298.199 84.49) (xy 298.325003 84.677081)
				(xy 298.392229 84.627299) (xy 298.475396 84.572894) (xy 298.528251 84.55781) (xy 298.600677 84.5525)
			)
		)
	)
	(zone
		(net 149)
		(net_name "/2xUSB3.0+RJ45/DC+")
		(layer "F.Cu")
		(name "$teardrop_padvia$")
		(hatch none 0.1)
		(priority 31160)
		(attr
			(teardrop
				(type padvia)
			)
		)
		(connect_pads yes
			(clearance 0)
		)
		(min_thickness 0.0254)
		(filled_areas_thickness no)
		(fill yes
			(thermal_gap 0.5)
			(thermal_bridge_width 0.5)
			(island_removal_mode 1)
			(island_area_min 10)
		)
		(polygon
			(pts
				(xy 125.867073 109.663139) (xy 125.912063 109.718172) (xy 125.94717 109.795302) (xy 125.955193 109.844101)
				(xy 125.9525 109.898424) (xy 126.290707 109.880707) (xy 126.326943 109.6425) (xy 126.239355 109.646626)
				(xy 126.161899 109.640762) (xy 126.095663 109.626263) (xy 126.039618 109.604147) (xy 125.973139 109.557073)
			)
		)
	)
	(zone
		(net 2)
		(net_name "+3V3")
		(layer "F.Cu")
		(name "$teardrop_padvia$")
		(hatch none 0.1)
		(priority 31756)
		(attr
			(teardrop
				(type padvia)
			)
		)
		(connect_pads yes
			(clearance 0)
		)
		(min_thickness 0.0254)
		(filled_areas_thickness no)
		(fill yes
			(thermal_gap 0.5)
			(thermal_bridge_width 0.5)
			(island_removal_mode 1)
			(island_area_min 10)
		)
		(polygon
			(pts
				(xy 138.649323 169.7025) (xy 138.718764 169.707318) (xy 138.770088 169.72104) (xy 138.845629 169.767755)
				(xy 138.857769 169.777299) (xy 138.924997 169.827081) (xy 139.051 169.64) (xy 138.924997 169.452919)
				(xy 138.857768 169.502702) (xy 138.774602 169.557106) (xy 138.721748 169.57219) (xy 138.649323 169.5775)
			)
		)
	)
	(zone
		(net 563)
		(net_name "/2xSFP+/~{LED0_1}")
		(layer "F.Cu")
		(name "$teardrop_padvia$")
		(hatch none 0.1)
		(priority 32014)
		(attr
			(teardrop
				(type padvia)
			)
		)
		(connect_pads yes
			(clearance 0)
		)
		(min_thickness 0.0254)
		(filled_areas_thickness no)
		(fill yes
			(thermal_gap 0.5)
			(thermal_bridge_width 0.5)
			(island_removal_mode 1)
			(island_area_min 10)
		)
		(polygon
			(pts
				(xy 156.8995 159.9225) (xy 156.905822 159.922404) (xy 156.945325 159.927989) (xy 156.963547 159.942922)
				(xy 156.976495 159.9725) (xy 157.363 159.86) (xy 156.976495 159.7475) (xy 156.965379 159.774493)
				(xy 156.949852 159.789595) (xy 156.905822 159.797596) (xy 156.8995 159.7975)
			)
		)
	)
	(zone
		(net 754)
		(net_name "Net-(U45A-LOSA)")
		(layer "F.Cu")
		(name "$teardrop_padvia$")
		(hatch none 0.1)
		(priority 31725)
		(attr
			(teardrop
				(type padvia)
			)
		)
		(connect_pads yes
			(clearance 0)
		)
		(min_thickness 0.0254)
		(filled_areas_thickness no)
		(fill yes
			(thermal_gap 0.5)
			(thermal_bridge_width 0.5)
			(island_removal_mode 1)
			(island_area_min 10)
		)
		(polygon
			(pts
				(xy 131.6275 130.109323) (xy 131.622682 130.178763) (xy 131.60896 130.230087) (xy 131.562245 130.305628)
				(xy 131.552702 130.317768) (xy 131.502919 130.384997) (xy 131.69 130.511) (xy 131.877081 130.384997)
				(xy 131.827299 130.317769) (xy 131.772894 130.234603) (xy 131.75781 130.181748) (xy 131.7525 130.109323)
			)
		)
	)
	(zone
		(net 988)
		(net_name "Net-(Q13-C)")
		(layer "F.Cu")
		(name "$teardrop_padvia$")
		(hatch none 0.1)
		(priority 30877)
		(attr
			(teardrop
				(type padvia)
			)
		)
		(connect_pads yes
			(clearance 0)
		)
		(min_thickness 0.0254)
		(filled_areas_thickness no)
		(fill yes
			(thermal_gap 0.5)
			(thermal_bridge_width 0.5)
			(island_removal_mode 1)
			(island_area_min 10)
		)
		(polygon
			(pts
				(xy 201.80861 78.045163) (xy 201.814382 78.004426) (xy 201.834786 77.962511) (xy 201.861961 77.93421)
				(xy 201.901507 77.910781) (xy 201.97411 77.89151) (xy 201.70861 77.631163) (xy 201.44311 77.89151)
				(xy 201.496252 77.903377) (xy 201.537291 77.921825) (xy 201.588992 77.972499) (xy 201.608328 78.036068)
				(xy 201.60861 78.045163)
			)
		)
	)
	(zone
		(net 356)
		(net_name "/Com Express 7 MGMT/~{CW_PWRBTN}")
		(layer "F.Cu")
		(name "$teardrop_padvia$")
		(hatch none 0.1)
		(priority 31090)
		(attr
			(teardrop
				(type padvia)
			)
		)
		(connect_pads yes
			(clearance 0)
		)
		(min_thickness 0.0254)
		(filled_areas_thickness no)
		(fill yes
			(thermal_gap 0.5)
			(thermal_bridge_width 0.5)
			(island_removal_mode 1)
			(island_area_min 10)
		)
		(polygon
			(pts
				(xy 241.8625 133.253) (xy 241.882273 133.193588) (xy 241.945547 133.137503) (xy 241.994172 133.115801)
				(xy 242.053532 133.101127) (xy 242.0655 133.099347) (xy 241.8 132.839) (xy 241.5345 133.099347)
				(xy 241.594639 133.112197) (xy 241.644523 133.132131) (xy 241.684642 133.158056) (xy 241.713655 133.187876)
				(xy 241.731146 133.219294) (xy 241.737479 133.251105) (xy 241.7375 133.253)
			)
		)
	)
	(zone
		(net 526)
		(net_name "/Backplane/~{PRSNT}")
		(layer "F.Cu")
		(name "$teardrop_padvia$")
		(hatch none 0.1)
		(priority 32117)
		(attr
			(teardrop
				(type padvia)
			)
		)
		(connect_pads yes
			(clearance 0)
		)
		(min_thickness 0.0254)
		(filled_areas_thickness no)
		(fill yes
			(thermal_gap 0.5)
			(thermal_bridge_width 0.5)
			(island_removal_mode 1)
			(island_area_min 10)
		)
		(polygon
			(pts
				(xy 315.46 164.3955) (xy 315.453678 164.395596) (xy 315.414175 164.390011) (xy 315.395953 164.375078)
				(xy 315.383005 164.3455) (xy 315.134 164.458) (xy 315.383005 164.5705) (xy 315.394121 164.543506)
				(xy 315.409648 164.528405) (xy 315.453678 164.520404) (xy 315.46 164.5205)
			)
		)
	)
	(zone
		(net 2)
		(net_name "+3V3")
		(layer "F.Cu")
		(name "$teardrop_padvia$")
		(hatch none 0.1)
		(priority 30850)
		(attr
			(teardrop
				(type padvia)
			)
		)
		(connect_pads yes
			(clearance 0)
		)
		(min_thickness 0.0254)
		(filled_areas_thickness no)
		(fill yes
			(thermal_gap 0.5)
			(thermal_bridge_width 0.5)
			(island_removal_mode 1)
			(island_area_min 10)
		)
		(polygon
			(pts
				(xy 309.637001 77.482003) (xy 309.683211 77.488213) (xy 309.731611 77.51168) (xy 309.759966 77.539587)
				(xy 309.783012 77.579813) (xy 309.798202 77.6338) (xy 310.075999 77.382002) (xy 309.798202 77.130204)
				(xy 309.785069 77.179057) (xy 309.765665 77.216567) (xy 309.713055 77.26399) (xy 309.646554 77.281747)
				(xy 309.637 77.282004)
			)
		)
	)
	(zone
		(net 431)
		(net_name "/2xSFP+/MOD0_ABS")
		(layer "F.Cu")
		(name "$teardrop_padvia$")
		(hatch none 0.1)
		(priority 31568)
		(attr
			(teardrop
				(type padvia)
			)
		)
		(connect_pads yes
			(clearance 0)
		)
		(min_thickness 0.0254)
		(filled_areas_thickness no)
		(fill yes
			(thermal_gap 0.5)
			(thermal_bridge_width 0.5)
			(island_removal_mode 1)
			(island_area_min 10)
		)
		(polygon
			(pts
				(xy 179.701852 145.0625) (xy 179.757625 145.067238) (xy 179.800063 145.080402) (xy 179.860145 145.125325)
				(xy 179.884331 145.152418) (xy 179.923059 145.194634) (xy 179.974997 145.237081) (xy 180.101 145.05)
				(xy 180.03577 144.837745) (xy 179.918123 144.886026) (xy 179.830494 144.922294) (xy 179.701852 144.9375)
			)
		)
	)
	(zone
		(net 339)
		(net_name "/Com Express 7 Interfaces/SDIO.CLK")
		(layer "F.Cu")
		(name "$teardrop_padvia$")
		(hatch none 0.1)
		(priority 31332)
		(attr
			(teardrop
				(type padvia)
			)
		)
		(connect_pads yes
			(clearance 0)
		)
		(min_thickness 0.0254)
		(filled_areas_thickness no)
		(fill yes
			(thermal_gap 0.5)
			(thermal_bridge_width 0.5)
			(island_removal_mode 1)
			(island_area_min 10)
		)
		(polygon
			(pts
				(xy 113.222333 133.591026) (xy 113.270984 133.646322) (xy 113.301335 133.6949) (xy 113.333472 133.790029)
				(xy 113.364742 133.89112) (xy 113.570707 133.810707) (xy 113.65112 133.604742) (xy 113.550029 133.573472)
				(xy 113.4562 133.541984) (xy 113.407039 133.51152) (xy 113.351026 133.462333)
			)
		)
	)
	(zone
		(net 2)
		(net_name "+3V3")
		(layer "F.Cu")
		(name "$teardrop_padvia$")
		(hatch none 0.1)
		(priority 31301)
		(attr
			(teardrop
				(type padvia)
			)
		)
		(connect_pads yes
			(clearance 0)
		)
		(min_thickness 0.0254)
		(filled_areas_thickness no)
		(fill yes
			(thermal_gap 0.5)
			(thermal_bridge_width 0.5)
			(island_removal_mode 1)
			(island_area_min 10)
		)
		(polygon
			(pts
				(xy 309.674324 77.482003) (xy 309.752236 77.486715) (xy 309.81102 77.499702) (xy 309.902052 77.541804)
				(xy 309.987222 77.584502) (xy 310.075999 77.382002) (xy 309.98722 77.179502) (xy 309.902047 77.222202)
				(xy 309.809215 77.26487) (xy 309.751077 77.277447) (xy 309.674323 77.282004)
			)
		)
	)
	(zone
		(net 730)
		(net_name "Net-(U43C-CLKOUTA+)")
		(layer "F.Cu")
		(name "$teardrop_padvia$")
		(hatch none 0.1)
		(priority 31717)
		(attr
			(teardrop
				(type padvia)
			)
		)
		(connect_pads yes
			(clearance 0)
		)
		(min_thickness 0.0254)
		(filled_areas_thickness no)
		(fill yes
			(thermal_gap 0.5)
			(thermal_bridge_width 0.5)
			(island_removal_mode 1)
			(island_area_min 10)
		)
		(polygon
			(pts
				(xy 154.9875 130.109323) (xy 154.982682 130.178763) (xy 154.96896 130.230087) (xy 154.922245 130.305628)
				(xy 154.912702 130.317768) (xy 154.862919 130.384997) (xy 155.05 130.511) (xy 155.237081 130.384997)
				(xy 155.187299 130.317769) (xy 155.132894 130.234603) (xy 155.11781 130.181748) (xy 155.1125 130.109323)
			)
		)
	)
	(zone
		(net 423)
		(net_name "/2xSFP+/I2C_{LED}.SCL")
		(layer "F.Cu")
		(name "$teardrop_padvia$")
		(hatch none 0.1)
		(priority 31817)
		(attr
			(teardrop
				(type padvia)
			)
		)
		(connect_pads yes
			(clearance 0)
		)
		(min_thickness 0.0254)
		(filled_areas_thickness no)
		(fill yes
			(thermal_gap 0.5)
			(thermal_bridge_width 0.5)
			(island_removal_mode 1)
			(island_area_min 10)
		)
		(polygon
			(pts
				(xy 176.600677 153.3125) (xy 176.531236 153.307682) (xy 176.479913 153.29396) (xy 176.404371 153.247246)
				(xy 176.392231 153.237701) (xy 176.325003 153.187919) (xy 176.199 153.375) (xy 176.325003 153.562081)
				(xy 176.392229 153.512299) (xy 176.475396 153.457894) (xy 176.528251 153.44281) (xy 176.600677 153.4375)
			)
		)
	)
	(zone
		(net 262)
		(net_name "/Com Express 7 Interfaces/PCIe_{B2Bx4}.RX0-")
		(layer "F.Cu")
		(name "$teardrop_padvia$")
		(hatch none 0.1)
		(priority 31377)
		(attr
			(teardrop
				(type padvia)
			)
		)
		(connect_pads yes
			(clearance 0)
		)
		(min_thickness 0.0254)
		(filled_areas_thickness no)
		(fill yes
			(thermal_gap 0.5)
			(thermal_bridge_width 0.5)
			(island_removal_mode 1)
			(island_area_min 10)
		)
		(polygon
			(pts
				(xy 173.232504 103.4055) (xy 173.27929 103.410235) (xy 173.314742 103.423379) (xy 173.362939 103.468387)
				(xy 173.387116 103.506608) (xy 173.414485 103.549773) (xy 173.451147 103.591731) (xy 173.601 103.4285)
				(xy 173.58014 103.207823) (xy 173.479466 103.212452) (xy 173.396096 103.209019) (xy 173.394035 103.208895)
				(xy 173.232504 103.2035)
			)
		)
	)
	(zone
		(net 682)
		(net_name "Net-(U45C-PRTAD4)")
		(layer "F.Cu")
		(name "$teardrop_padvia$")
		(hatch none 0.1)
		(priority 31460)
		(attr
			(teardrop
				(type padvia)
			)
		)
		(connect_pads yes
			(clearance 0)
		)
		(min_thickness 0.0254)
		(filled_areas_thickness no)
		(fill yes
			(thermal_gap 0.5)
			(thermal_bridge_width 0.5)
			(island_removal_mode 1)
			(island_area_min 10)
		)
		(polygon
			(pts
				(xy 125.76167 132.873283) (xy 125.686453 132.824312) (xy 125.649487 132.782089) (xy 125.619379 132.730177)
				(xy 125.595776 132.639088) (xy 125.319293 132.879293) (xy 125.571798 133.156798) (xy 125.595149 133.044177)
				(xy 125.625893 132.976455) (xy 125.644875 132.961465) (xy 125.666882 132.959785) (xy 125.673283 132.96167)
			)
		)
	)
	(zone
		(net 602)
		(net_name "Net-(U37-~{OE0})")
		(layer "F.Cu")
		(name "$teardrop_padvia$")
		(hatch none 0.1)
		(priority 31010)
		(attr
			(teardrop
				(type padvia)
			)
		)
		(connect_pads yes
			(clearance 0)
		)
		(min_thickness 0.0254)
		(filled_areas_thickness no)
		(fill yes
			(thermal_gap 0.5)
			(thermal_bridge_width 0.5)
			(island_removal_mode 1)
			(island_area_min 10)
		)
		(polygon
			(pts
				(xy 211.8225 126.528) (xy 211.842469 126.465134) (xy 211.868921 126.433156) (xy 211.906332 126.404642)
				(xy 211.953527 126.382118) (xy 212.011167 126.366907) (xy 212.011798 126.366798) (xy 211.76 126.089)
				(xy 211.508202 126.366798) (xy 211.563635 126.381095) (xy 211.60952 126.402175) (xy 211.647201 126.42954)
				(xy 211.674434 126.460448) (xy 211.691472 126.493735) (xy 211.697489 126.526566) (xy 211.6975 126.528)
			)
		)
	)
	(zone
		(net 66)
		(net_name "Net-(U18-BST)")
		(layer "F.Cu")
		(name "$teardrop_padvia$")
		(hatch none 0.1)
		(priority 30919)
		(attr
			(teardrop
				(type padvia)
			)
		)
		(connect_pads yes
			(clearance 0)
		)
		(min_thickness 0.0254)
		(filled_areas_thickness no)
		(fill yes
			(thermal_gap 0.5)
			(thermal_bridge_width 0.5)
			(island_removal_mode 1)
			(island_area_min 10)
		)
		(polygon
			(pts
				(xy 313.676999 121.524499) (xy 313.740197 121.544503) (xy 313.772331 121.570961) (xy 313.800953 121.60841)
				(xy 313.823207 121.654981) (xy 313.838201 121.711797) (xy 314.115999 121.459999) (xy 313.838201 121.208201)
				(xy 313.823868 121.264282) (xy 313.802741 121.310725) (xy 313.775385 121.348778) (xy 313.744467 121.376286)
				(xy 313.71131 121.393413) (xy 313.678514 121.399486) (xy 313.676999 121.399499)
			)
		)
	)
	(zone
		(net 192)
		(net_name "/OCuLink/PCIe_{REF0}.CK+")
		(layer "F.Cu")
		(name "$teardrop_padvia$")
		(hatch none 0.1)
		(priority 32055)
		(attr
			(teardrop
				(type padvia)
			)
		)
		(connect_pads yes
			(clearance 0)
		)
		(min_thickness 0.0254)
		(filled_areas_thickness no)
		(fill yes
			(thermal_gap 0.5)
			(thermal_bridge_width 0.5)
			(island_removal_mode 1)
			(island_area_min 10)
		)
		(polygon
			(pts
				(xy 111.801 152.138) (xy 111.793802 152.117352) (xy 111.784208 152.085016) (xy 111.791035 152.070993)
				(xy 111.8125 152.061004) (xy 111.7 151.812) (xy 111.5875 152.061004) (xy 111.608676 152.070729)
				(xy 111.615731 152.084357) (xy 111.606198 152.117352) (xy 111.599 152.138)
			)
		)
	)
	(zone
		(net 898)
		(net_name "/2xSFP+/SFP1_LEDY")
		(layer "F.Cu")
		(name "$teardrop_padvia$")
		(hatch none 0.1)
		(priority 30497)
		(attr
			(teardrop
				(type padvia)
			)
		)
		(connect_pads yes
			(clearance 0)
		)
		(min_thickness 0.0254)
		(filled_areas_thickness no)
		(fill yes
			(thermal_gap 0.5)
			(thermal_bridge_width 0.5)
			(island_removal_mode 1)
			(island_area_min 10)
		)
		(polygon
			(pts
				(xy 154.517944 161.499444) (xy 154.595761 161.449591) (xy 154.717204 161.421471) (xy 154.791476 161.420257)
				(xy 154.871762 161.429508) (xy 154.874474 161.43) (xy 154.819707 161.109293) (xy 154.524 161.029526)
				(xy 154.527538 161.115966) (xy 154.521454 161.195599) (xy 154.506419 161.268138) (xy 154.483456 161.330952)
				(xy 154.429556 161.411056)
			)
		)
	)
	(zone
		(net 2)
		(net_name "+3V3")
		(layer "F.Cu")
		(name "$teardrop_padvia$")
		(hatch none 0.1)
		(priority 30888)
		(attr
			(teardrop
				(type padvia)
			)
		)
		(connect_pads yes
			(clearance 0)
		)
		(min_thickness 0.0254)
		(filled_areas_thickness no)
		(fill yes
			(thermal_gap 0.5)
			(thermal_bridge_width 0.5)
			(island_removal_mode 1)
			(island_area_min 10)
		)
		(polygon
			(pts
				(xy 131 82.653) (xy 131.005772 82.612263) (xy 131.026176 82.570348) (xy 131.053351 82.542047) (xy 131.092897 82.518618)
				(xy 131.1655 82.499347) (xy 130.9 82.239002) (xy 130.6345 82.499348) (xy 130.687642 82.511215) (xy 130.728681 82.529663)
				(xy 130.780382 82.580337) (xy 130.799719 82.643906) (xy 130.800001 82.653001)
			)
		)
	)
	(zone
		(net 691)
		(net_name "/2xUSB3.0+RJ45/DB_FL+")
		(layer "F.Cu")
		(name "$teardrop_padvia$")
		(hatch none 0.1)
		(priority 31978)
		(attr
			(teardrop
				(type padvia)
			)
		)
		(connect_pads yes
			(clearance 0)
		)
		(min_thickness 0.0254)
		(filled_areas_thickness no)
		(fill yes
			(thermal_gap 0.5)
			(thermal_bridge_width 0.5)
			(island_removal_mode 1)
			(island_area_min 10)
		)
		(polygon
			(pts
				(xy 130.285858 105.731923) (xy 130.299094 105.741437) (xy 130.324793 105.763581) (xy 130.32868 105.779941)
				(xy 130.32 105.801498) (xy 130.800707 105.850707) (xy 130.784389 105.715) (xy 130.627296 105.710002)
				(xy 130.508147 105.690026) (xy 130.452418 105.668863) (xy 130.40698 105.639564) (xy 130.391923 105.625858)
			)
		)
	)
	(zone
		(net 23)
		(net_name "/M.2 key E/~{PERST_D}")
		(layer "F.Cu")
		(name "$teardrop_padvia$")
		(hatch none 0.1)
		(priority 30855)
		(attr
			(teardrop
				(type padvia)
			)
		)
		(connect_pads yes
			(clearance 0)
		)
		(min_thickness 0.0254)
		(filled_areas_thickness no)
		(fill yes
			(thermal_gap 0.5)
			(thermal_bridge_width 0.5)
			(island_removal_mode 1)
			(island_area_min 10)
		)
		(polygon
			(pts
				(xy 145.2405 83.872) (xy 145.279323 83.882938) (xy 145.294433 83.904695) (xy 145.3005 83.9445) (xy 146.0765 83.8095)
				(xy 145.3005 83.6745) (xy 145.295983 83.709781) (xy 145.284362 83.731297) (xy 145.251539 83.746495)
				(xy 145.2405 83.747)
			)
		)
	)
	(zone
		(net 71)
		(net_name "Net-(U49-IN+)")
		(layer "F.Cu")
		(name "$teardrop_padvia$")
		(hatch none 0.1)
		(priority 30733)
		(attr
			(teardrop
				(type padvia)
			)
		)
		(connect_pads yes
			(clearance 0)
		)
		(min_thickness 0.0254)
		(filled_areas_thickness no)
		(fill yes
			(thermal_gap 0.5)
			(thermal_bridge_width 0.5)
			(island_removal_mode 1)
			(island_area_min 10)
		)
		(polygon
			(pts
				(xy 304.0625 104.17) (xy 304.057179 104.201735) (xy 304.039931 104.234435) (xy 304.013462 104.260626)
				(xy 303.975036 104.281555) (xy 303.93295 104.29295) (xy 304.125 104.811) (xy 304.31705 104.29295)
				(xy 304.272526 104.280591) (xy 304.2384 104.261992) (xy 304.196464 104.211197) (xy 304.1875 104.17)
			)
		)
	)
	(zone
		(net 292)
		(net_name "/2xUSB3.0+RJ45/GbE.MDI1-")
		(layer "F.Cu")
		(name "$teardrop_padvia$")
		(hatch none 0.1)
		(priority 31649)
		(attr
			(teardrop
				(type padvia)
			)
		)
		(connect_pads yes
			(clearance 0)
		)
		(min_thickness 0.0254)
		(filled_areas_thickness no)
		(fill yes
			(thermal_gap 0.5)
			(thermal_bridge_width 0.5)
			(island_removal_mode 1)
			(island_area_min 10)
		)
		(polygon
			(pts
				(xy 180.175 167.742084) (xy 180.172797 167.536718) (xy 180.170677 167.398242) (xy 179.95 167.399)
				(xy 179.824997 167.587081) (xy 179.901138 167.620995) (xy 179.917738 167.62605) (xy 179.959281 167.639844)
				(xy 179.993398 167.659262) (xy 180.016501 167.691083) (xy 180.025 167.742084)
			)
		)
	)
	(zone
		(net 1)
		(net_name "GND")
		(layer "F.Cu")
		(name "$teardrop_padvia$")
		(hatch none 0.1)
		(priority 31252)
		(attr
			(teardrop
				(type padvia)
			)
		)
		(connect_pads yes
			(clearance 0)
		)
		(min_thickness 0.0254)
		(filled_areas_thickness no)
		(fill yes
			(thermal_gap 0.5)
			(thermal_bridge_width 0.5)
			(island_removal_mode 1)
			(island_area_min 10)
		)
		(polygon
			(pts
				(xy 309.674323 78.442002) (xy 309.752235 78.446715) (xy 309.81102 78.459702) (xy 309.902051 78.501804)
				(xy 309.987222 78.544502) (xy 310.076 78.342002) (xy 309.987222 78.139502) (xy 309.90205 78.182201)
				(xy 309.809217 78.224869) (xy 309.751078 78.237446) (xy 309.674323 78.242002)
			)
		)
	)
	(zone
		(net 51)
		(net_name "Net-(C13-Pad1)")
		(layer "F.Cu")
		(name "$teardrop_padvia$")
		(hatch none 0.1)
		(priority 30092)
		(attr
			(teardrop
				(type padvia)
			)
		)
		(connect_pads yes
			(clearance 0)
		)
		(min_thickness 0.0254)
		(filled_areas_thickness no)
		(fill yes
			(thermal_gap 0.5)
			(thermal_bridge_width 0.5)
			(island_removal_mode 1)
			(island_area_min 10)
		)
		(polygon
			(pts
				(xy 131.374 110.8) (xy 131.317939 110.792567) (xy 131.262329 110.760538) (xy 131.238554 110.729894)
				(xy 131.220421 110.68702) (xy 131.208103 110.6035) (xy 130.769 110.95) (xy 131.208103 111.2965)
				(xy 131.214918 111.235202) (xy 131.229503 111.187953) (xy 131.249612 111.153687) (xy 131.273934 111.12947)
				(xy 131.334458 111.103449) (xy 131.374 111.1)
			)
		)
	)
	(zone
		(net 595)
		(net_name "/Misc/PWM_{SRCSEL}")
		(layer "F.Cu")
		(name "$teardrop_padvia$")
		(hatch none 0.1)
		(priority 31871)
		(attr
			(teardrop
				(type padvia)
			)
		)
		(connect_pads yes
			(clearance 0)
		)
		(min_thickness 0.0254)
		(filled_areas_thickness no)
		(fill yes
			(thermal_gap 0.5)
			(thermal_bridge_width 0.5)
			(island_removal_mode 1)
			(island_area_min 10)
		)
		(polygon
			(pts
				(xy 252.905873 84.777514) (xy 252.958382 84.731818) (xy 253.004376 84.70523) (xy 253.090824 84.684846)
				(xy 253.10616 84.68301) (xy 253.188895 84.670676) (xy 253.145707 84.449292) (xy 252.924323 84.406104)
				(xy 252.911988 84.48884) (xy 252.891651 84.586118) (xy 252.864943 84.634158) (xy 252.817485 84.689126)
			)
		)
	)
	(zone
		(net 1)
		(net_name "GND")
		(layer "F.Cu")
		(name "$teardrop_padvia$")
		(hatch none 0.1)
		(priority 30606)
		(attr
			(teardrop
				(type padvia)
			)
		)
		(connect_pads yes
			(clearance 0)
		)
		(min_thickness 0.0254)
		(filled_areas_thickness no)
		(fill yes
			(thermal_gap 0.5)
			(thermal_bridge_width 0.5)
			(island_removal_mode 1)
			(island_area_min 10)
		)
		(polygon
			(pts
				(xy 223.625 157.62) (xy 223.621667 157.605514) (xy 223.61881 157.57539) (xy 223.630964 157.564349)
				(xy 223.66 157.56) (xy 223.525 156.684) (xy 223.39 157.56) (xy 223.419334 157.564475) (xy 223.431358 157.575801)
				(xy 223.428333 157.605514) (xy 223.425 157.62)
			)
		)
	)
	(zone
		(net 1)
		(net_name "GND")
		(layer "F.Cu")
		(name "$teardrop_padvia$")
		(hatch none 0.1)
		(priority 30526)
		(attr
			(teardrop
				(type padvia)
			)
		)
		(connect_pads yes
			(clearance 0)
		)
		(min_thickness 0.0254)
		(filled_areas_thickness no)
		(fill yes
			(thermal_gap 0.5)
			(thermal_bridge_width 0.5)
			(island_removal_mode 1)
			(island_area_min 10)
		)
		(polygon
			(pts
				(xy 220.625 169.62) (xy 220.621667 169.605514) (xy 220.61881 169.57539) (xy 220.630964 169.564349)
				(xy 220.66 169.56) (xy 220.525 168.684) (xy 220.39 169.56) (xy 220.419334 169.564475) (xy 220.431358 169.575801)
				(xy 220.428333 169.605514) (xy 220.425 169.62)
			)
		)
	)
	(zone
		(net 1)
		(net_name "GND")
		(layer "F.Cu")
		(name "$teardrop_padvia$")
		(hatch none 0.1)
		(priority 31230)
		(attr
			(teardrop
				(type padvia)
			)
		)
		(connect_pads yes
			(clearance 0)
		)
		(min_thickness 0.0254)
		(filled_areas_thickness no)
		(fill yes
			(thermal_gap 0.5)
			(thermal_bridge_width 0.5)
			(island_removal_mode 1)
			(island_area_min 10)
		)
		(polygon
			(pts
				(xy 220.625 162.400677) (xy 220.629737 162.309676) (xy 220.642896 162.242587) (xy 220.675418 162.155855)
				(xy 220.707644 162.075358) (xy 220.5 161.999) (xy 220.303541 162.102363) (xy 220.355343 162.185863)
				(xy 220.404833 162.271955) (xy 220.419614 162.32716) (xy 220.425 162.400677)
			)
		)
	)
	(zone
		(net 1)
		(net_name "GND")
		(layer "F.Cu")
		(name "$teardrop_padvia$")
		(hatch none 0.1)
		(priority 30657)
		(attr
			(teardrop
				(type padvia)
			)
		)
		(connect_pads yes
			(clearance 0)
		)
		(min_thickness 0.0254)
		(filled_areas_thickness no)
		(fill yes
			(thermal_gap 0.5)
			(thermal_bridge_width 0.5)
			(island_removal_mode 1)
			(island_area_min 10)
		)
		(polygon
			(pts
				(xy 225.5875 169.62) (xy 225.598438 169.581177) (xy 225.620195 169.566067) (xy 225.66 169.56) (xy 225.525 168.684)
				(xy 225.39 169.56) (xy 225.425281 169.564517) (xy 225.446797 169.576138) (xy 225.461995 169.608961)
				(xy 225.4625 169.62)
			)
		)
	)
	(zone
		(net 982)
		(net_name "Net-(D30-C)")
		(layer "F.Cu")
		(name "$teardrop_padvia$")
		(hatch none 0.1)
		(priority 30884)
		(attr
			(teardrop
				(type padvia)
			)
		)
		(connect_pads yes
			(clearance 0)
		)
		(min_thickness 0.0254)
		(filled_areas_thickness no)
		(fill yes
			(thermal_gap 0.5)
			(thermal_bridge_width 0.5)
			(island_removal_mode 1)
			(island_area_min 10)
		)
		(polygon
			(pts
				(xy 190.60861 76.259163) (xy 190.602838 76.2999) (xy 190.582434 76.341815) (xy 190.555259 76.370116)
				(xy 190.515713 76.393544) (xy 190.44311 76.412815) (xy 190.70861 76.673163) (xy 190.97411 76.412815)
				(xy 190.920968 76.400948) (xy 190.879929 76.382501) (xy 190.828228 76.331827) (xy 190.808892 76.268258)
				(xy 190.80861 76.259163)
			)
		)
	)
	(zone
		(net 327)
		(net_name "/Com Express 7 Interfaces/PCIe_{B2Ax4}.TX1-")
		(layer "F.Cu")
		(name "$teardrop_padvia$")
		(hatch none 0.1)
		(priority 31358)
		(attr
			(teardrop
				(type padvia)
			)
		)
		(connect_pads yes
			(clearance 0)
		)
		(min_thickness 0.0254)
		(filled_areas_thickness no)
		(fill yes
			(thermal_gap 0.5)
			(thermal_bridge_width 0.5)
			(island_removal_mode 1)
			(island_area_min 10)
		)
		(polygon
			(pts
				(xy 229.9455 145.367496) (xy 229.950235 145.32071) (xy 229.963379 145.285257) (xy 230.008387 145.23706)
				(xy 230.046608 145.212883) (xy 230.089774 145.185514) (xy 230.131731 145.148852) (xy 229.9685 144.999)
				(xy 229.747823 145.019859) (xy 229.752452 145.120536) (xy 229.749019 145.203908) (xy 229.748895 145.205963)
				(xy 229.7435 145.367496)
			)
		)
	)
	(zone
		(net 589)
		(net_name "/Misc/~{ADDRSEL}")
		(layer "F.Cu")
		(name "$teardrop_padvia$")
		(hatch none 0.1)
		(priority 30984)
		(attr
			(teardrop
				(type padvia)
			)
		)
		(connect_pads yes
			(clearance 0)
		)
		(min_thickness 0.0254)
		(filled_areas_thickness no)
		(fill yes
			(thermal_gap 0.5)
			(thermal_bridge_width 0.5)
			(island_removal_mode 1)
			(island_area_min 10)
		)
		(polygon
			(pts
				(xy 253.0325 82.736999) (xy 253.012531 82.799865) (xy 252.986079 82.831843) (xy 252.948668 82.860357)
				(xy 252.901473 82.882881) (xy 252.843833 82.898092) (xy 252.843202 82.898201) (xy 253.095 83.175999)
				(xy 253.346798 82.898201) (xy 253.291365 82.883904) (xy 253.24548 82.862824) (xy 253.207799 82.835459)
				(xy 253.180566 82.804551) (xy 253.163528 82.771264) (xy 253.157511 82.738433) (xy 253.1575 82.736999)
			)
		)
	)
	(zone
		(net 243)
		(net_name "/Com Express 7 Interfaces/PCIe_{B2Bx4}.RX2-")
		(layer "F.Cu")
		(name "$teardrop_padvia$")
		(hatch none 0.1)
		(priority 31370)
		(attr
			(teardrop
				(type padvia)
			)
		)
		(connect_pads yes
			(clearance 0)
		)
		(min_thickness 0.0254)
		(filled_areas_thickness no)
		(fill yes
			(thermal_gap 0.5)
			(thermal_bridge_width 0.5)
			(island_removal_mode 1)
			(island_area_min 10)
		)
		(polygon
			(pts
				(xy 173.232504 97.4055) (xy 173.27929 97.410235) (xy 173.314742 97.423379) (xy 173.362939 97.468387)
				(xy 173.387116 97.506608) (xy 173.414485 97.549773) (xy 173.451147 97.591731) (xy 173.601 97.4285)
				(xy 173.58014 97.207823) (xy 173.479466 97.212452) (xy 173.396096 97.209019) (xy 173.394035 97.208895)
				(xy 173.232504 97.2035)
			)
		)
	)
	(zone
		(net 2)
		(net_name "+3V3")
		(layer "F.Cu")
		(name "$teardrop_padvia$")
		(hatch none 0.1)
		(priority 30392)
		(attr
			(teardrop
				(type padvia)
			)
		)
		(connect_pads yes
			(clearance 0)
		)
		(min_thickness 0.0254)
		(filled_areas_thickness no)
		(fill yes
			(thermal_gap 0.5)
			(thermal_bridge_width 0.5)
			(island_removal_mode 1)
			(island_area_min 10)
		)
		(polygon
			(pts
				(xy 193.094761 133.678822) (xy 193.140592 133.695913) (xy 193.177552 133.706324) (xy 193.206491 133.723217)
				(xy 193.215305 133.752079) (xy 193.191889 133.798397) (xy 193.563572 133.795495) (xy 193.567957 133.423517)
				(xy 193.534116 133.443394) (xy 193.509264 133.446411) (xy 193.482861 133.424183) (xy 193.465506 133.371431)
				(xy 193.448313 133.325269)
			)
		)
	)
	(zone
		(net 331)
		(net_name "/Com Express 7 Interfaces/PCIe_{B2Ax4}.TX3-")
		(layer "F.Cu")
		(name "$teardrop_padvia$")
		(hatch none 0.1)
		(priority 30378)
		(attr
			(teardrop
				(type padvia)
			)
		)
		(connect_pads yes
			(clearance 0)
		)
		(min_thickness 0.0254)
		(filled_areas_thickness no)
		(fill yes
			(thermal_gap 0.5)
			(thermal_bridge_width 0.5)
			(island_removal_mode 1)
			(island_area_min 10)
		)
		(polygon
			(pts
				(xy 289.0415 73.2) (xy 289.052603 73.355527) (xy 289.067217 73.559681) (xy 289.06418 73.679806)
				(xy 289.048 73.814533) (xy 289.198 74.036) (xy 289.28178 73.26) (xy 289.251191 73.255523) (xy 289.238299 73.244182)
				(xy 289.240476 73.214169) (xy 289.2435 73.2)
			)
		)
	)
	(zone
		(net 780)
		(net_name "/Misc/TACH_{A3V3}")
		(layer "F.Cu")
		(name "$teardrop_padvia$")
		(hatch none 0.1)
		(priority 30809)
		(attr
			(teardrop
				(type padvia)
			)
		)
		(connect_pads yes
			(clearance 0)
		)
		(min_thickness 0.0254)
		(filled_areas_thickness no)
		(fill yes
			(thermal_gap 0.5)
			(thermal_bridge_width 0.5)
			(island_removal_mode 1)
			(island_area_min 10)
		)
		(polygon
			(pts
				(xy 260.624 83.127499) (xy 260.597391 83.122136) (xy 260.572117 83.104599) (xy 260.554478 83.078305)
				(xy 260.54305 83.040159) (xy 260.54 83.000999) (xy 259.979 83.19) (xy 260.54 83.378999) (xy 260.544627 83.331636)
				(xy 260.557018 83.296588) (xy 260.574877 83.27265) (xy 260.596015 83.258453) (xy 260.624 83.252499)
			)
		)
	)
	(zone
		(net 661)
		(net_name "Net-(U43C-PRTAD4)")
		(layer "F.Cu")
		(name "$teardrop_padvia$")
		(hatch none 0.1)
		(priority 31459)
		(attr
			(teardrop
				(type padvia)
			)
		)
		(connect_pads yes
			(clearance 0)
		)
		(min_thickness 0.0254)
		(filled_areas_thickness no)
		(fill yes
			(thermal_gap 0.5)
			(thermal_bridge_width 0.5)
			(island_removal_mode 1)
			(island_area_min 10)
		)
		(polygon
			(pts
				(xy 143.92167 132.873283) (xy 143.846453 132.824312) (xy 143.809487 132.782089) (xy 143.779379 132.730177)
				(xy 143.755776 132.639088) (xy 143.479293 132.879293) (xy 143.731798 133.156798) (xy 143.755149 133.044177)
				(xy 143.785893 132.976455) (xy 143.804875 132.961465) (xy 143.826882 132.959785) (xy 143.833283 132.96167)
			)
		)
	)
	(zone
		(net 1)
		(net_name "GND")
		(layer "F.Cu")
		(name "$teardrop_padvia$")
		(hatch none 0.1)
		(priority 31521)
		(attr
			(teardrop
				(type padvia)
			)
		)
		(connect_pads yes
			(clearance 0)
		)
		(min_thickness 0.0254)
		(filled_areas_thickness no)
		(fill yes
			(thermal_gap 0.5)
			(thermal_bridge_width 0.5)
			(island_removal_mode 1)
			(island_area_min 10)
		)
		(polygon
			(pts
				(xy 189.425 152.021811) (xy 189.420256 152.059307) (xy 189.407047 152.085714) (xy 189.363193 152.114951)
				(xy 189.318163 152.127712) (xy 189.270942 152.140856) (xy 189.224997 152.162919) (xy 189.35 152.351)
				(xy 189.570677 152.367287) (xy 189.596784 152.226951) (xy 189.616195 152.14194) (xy 189.625 152.021811)
			)
		)
	)
	(zone
		(net 755)
		(net_name "Net-(U45A-LS_OK_{IN_A})")
		(layer "F.Cu")
		(name "$teardrop_padvia$")
		(hatch none 0.1)
		(priority 30126)
		(attr
			(teardrop
				(type padvia)
			)
		)
		(connect_pads yes
			(clearance 0)
		)
		(min_thickness 0.0254)
		(filled_areas_thickness no)
		(fill yes
			(thermal_gap 0.5)
			(thermal_bridge_width 0.5)
			(island_removal_mode 1)
			(island_area_min 10)
		)
		(polygon
			(pts
				(xy 137.6025 129.377794) (xy 137.607315 129.295733) (xy 137.621019 129.230388) (xy 137.667576 129.13712)
				(xy 137.735787 129.058657) (xy 137.791942 128.997158) (xy 137.851801 128.918339) (xy 137.54 128.709)
				(xy 137.228199 128.918339) (xy 137.325219 129.038517) (xy 137.344214 129.058658) (xy 137.397366 129.117541)
				(xy 137.439591 129.181624) (xy 137.467449 129.264008) (xy 137.4775 129.377794)
			)
		)
	)
	(zone
		(net 532)
		(net_name "/Backplane/PCIe_{x2}.RX0+")
		(layer "F.Cu")
		(name "$teardrop_padvia$")
		(hatch none 0.1)
		(priority 31408)
		(attr
			(teardrop
				(type padvia)
			)
		)
		(connect_pads yes
			(clearance 0)
		)
		(min_thickness 0.0254)
		(filled_areas_thickness no)
		(fill yes
			(thermal_gap 0.5)
			(thermal_bridge_width 0.5)
			(island_removal_mode 1)
			(island_area_min 10)
		)
		(polygon
			(pts
				(xy 220.032504 153.2565) (xy 220.194035 153.251105) (xy 220.278445 153.247554) (xy 220.38014 153.252177)
				(xy 220.401 153.0315) (xy 220.251147 152.868268) (xy 220.197007 152.936935) (xy 220.187115 152.953393)
				(xy 220.162615 152.992065) (xy 220.133109 153.024279) (xy 220.091953 153.046327) (xy 220.032504 153.0545)
			)
		)
	)
	(zone
		(net 193)
		(net_name "/OCuLink/PCIe_{REF0}.CK-")
		(layer "F.Cu")
		(name "$teardrop_padvia$")
		(hatch none 0.1)
		(priority 32074)
		(attr
			(teardrop
				(type padvia)
			)
		)
		(connect_pads yes
			(clearance 0)
		)
		(min_thickness 0.0254)
		(filled_areas_thickness no)
		(fill yes
			(thermal_gap 0.5)
			(thermal_bridge_width 0.5)
			(island_removal_mode 1)
			(island_area_min 10)
		)
		(polygon
			(pts
				(xy 111.099 151.488) (xy 111.106198 151.508648) (xy 111.115792 151.540984) (xy 111.108965 151.555007)
				(xy 111.0875 151.564995) (xy 111.2 151.814) (xy 111.3125 151.564995) (xy 111.291324 151.555271)
				(xy 111.284269 151.541643) (xy 111.293802 151.508648) (xy 111.301 151.488)
			)
		)
	)
	(zone
		(net 1)
		(net_name "GND")
		(layer "F.Cu")
		(name "$teardrop_padvia$")
		(hatch none 0.1)
		(priority 31925)
		(attr
			(teardrop
				(type padvia)
			)
		)
		(connect_pads yes
			(clearance 0)
		)
		(min_thickness 0.0254)
		(filled_areas_thickness no)
		(fill yes
			(thermal_gap 0.5)
			(thermal_bridge_width 0.5)
			(island_removal_mode 1)
			(island_area_min 10)
		)
		(polygon
			(pts
				(xy 314.718 163.86) (xy 314.707885 163.860153) (xy 314.677169 163.85954) (xy 314.64468 163.851218)
				(xy 314.615526 163.827325) (xy 314.594809 163.78) (xy 314.362 163.96) (xy 314.594809 164.14) (xy 314.608168 164.104099)
				(xy 314.626399 164.080801) (xy 314.671725 164.061101) (xy 314.707885 164.059847) (xy 314.718 164.06)
			)
		)
	)
	(zone
		(net 241)
		(net_name "/Com Express 7 Interfaces/PCIe_{B2Bx4}.TX3-")
		(layer "F.Cu")
		(name "$teardrop_padvia$")
		(hatch none 0.1)
		(priority 30278)
		(attr
			(teardrop
				(type padvia)
			)
		)
		(connect_pads yes
			(clearance 0)
		)
		(min_thickness 0.0254)
		(filled_areas_thickness no)
		(fill yes
			(thermal_gap 0.5)
			(thermal_bridge_width 0.5)
			(island_removal_mode 1)
			(island_area_min 10)
		)
		(polygon
			(pts
				(xy 186.8685 167.75) (xy 186.879599 167.923112) (xy 186.894216 168.15051) (xy 186.891181 168.285138)
				(xy 186.875 168.437021) (xy 187.025 168.686) (xy 187.108295 167.81) (xy 187.077864 167.805523) (xy 187.065097 167.794185)
				(xy 187.06742 167.764227) (xy 187.0705 167.75)
			)
		)
	)
	(zone
		(net 72)
		(net_name "Net-(U20-CT)")
		(layer "F.Cu")
		(name "$teardrop_padvia$")
		(hatch none 0.1)
		(priority 30936)
		(attr
			(teardrop
				(type padvia)
			)
		)
		(connect_pads yes
			(clearance 0)
		)
		(min_thickness 0.0254)
		(filled_areas_thickness no)
		(fill yes
			(thermal_gap 0.5)
			(thermal_bridge_width 0.5)
			(island_removal_mode 1)
			(island_area_min 10)
		)
		(polygon
			(pts
				(xy 304.6825 127.228) (xy 304.702469 127.165134) (xy 304.728921 127.133156) (xy 304.766332 127.104642)
				(xy 304.813527 127.082118) (xy 304.871167 127.066907) (xy 304.871798 127.066798) (xy 304.62 126.789)
				(xy 304.368202 127.066798) (xy 304.423635 127.081095) (xy 304.46952 127.102175) (xy 304.507201 127.12954)
				(xy 304.534434 127.160448) (xy 304.551472 127.193735) (xy 304.557489 127.226566) (xy 304.5575 127.228)
			)
		)
	)
	(zone
		(net 321)
		(net_name "/Com Express 7 Interfaces/SDIO.DAT0")
		(layer "F.Cu")
		(name "$teardrop_padvia$")
		(hatch none 0.1)
		(priority 31474)
		(attr
			(teardrop
				(type padvia)
			)
		)
		(connect_pads yes
			(clearance 0)
		)
		(min_thickness 0.0254)
		(filled_areas_thickness no)
		(fill yes
			(thermal_gap 0.5)
			(thermal_bridge_width 0.5)
			(island_removal_mode 1)
			(island_area_min 10)
		)
		(polygon
			(pts
				(xy 202.616 167.900677) (xy 202.620696 167.816825) (xy 202.633569 167.75428) (xy 202.668233 167.668433)
				(xy 202.707644 167.575358) (xy 202.5 167.499) (xy 202.312919 167.625003) (xy 202.358229 167.686996)
				(xy 202.413176 167.772668) (xy 202.428559 167.826883) (xy 202.434 167.900677)
			)
		)
	)
	(zone
		(net 560)
		(net_name "Net-(U5-~{RESET})")
		(layer "F.Cu")
		(name "$teardrop_padvia$")
		(hatch none 0.1)
		(priority 30503)
		(attr
			(teardrop
				(type padvia)
			)
		)
		(connect_pads yes
			(clearance 0)
		)
		(min_thickness 0.0254)
		(filled_areas_thickness no)
		(fill yes
			(thermal_gap 0.5)
			(thermal_bridge_width 0.5)
			(island_removal_mode 1)
			(island_area_min 10)
		)
		(polygon
			(pts
				(xy 157.939444 157.591056) (xy 157.889591 157.513239) (xy 157.861471 157.391796) (xy 157.860257 157.317524)
				(xy 157.869508 157.237238) (xy 157.87 157.234526) (xy 157.549293 157.289293) (xy 157.469526 157.585)
				(xy 157.555966 157.581462) (xy 157.635599 157.587546) (xy 157.708138 157.602581) (xy 157.770952 157.625544)
				(xy 157.851056 157.679444)
			)
		)
	)
	(zone
		(net 929)
		(net_name "/2xSFP+/SFP1_LEDG")
		(layer "F.Cu")
		(name "$teardrop_padvia$")
		(hatch none 0.1)
		(priority 30945)
		(attr
			(teardrop
				(type padvia)
			)
		)
		(connect_pads yes
			(clearance 0)
		)
		(min_thickness 0.0254)
		(filled_areas_thickness no)
		(fill yes
			(thermal_gap 0.5)
			(thermal_bridge_width 0.5)
			(island_removal_mode 1)
			(island_area_min 10)
		)
		(polygon
			(pts
				(xy 154.7565 162.672) (xy 154.736531 162.734866) (xy 154.710079 162.766844) (xy 154.672668 162.795358)
				(xy 154.625473 162.817882) (xy 154.567833 162.833093) (xy 154.567202 162.833202) (xy 154.819 163.111)
				(xy 155.070798 162.833202) (xy 155.015365 162.818905) (xy 154.96948 162.797825) (xy 154.931799 162.77046)
				(xy 154.904566 162.739552) (xy 154.887528 162.706265) (xy 154.881511 162.673434) (xy 154.8815 162.672)
			)
		)
	)
	(zone
		(net 1)
		(net_name "GND")
		(layer "F.Cu")
		(name "$teardrop_padvia$")
		(hatch none 0.1)
		(priority 31535)
		(attr
			(teardrop
				(type padvia)
			)
		)
		(connect_pads yes
			(clearance 0)
		)
		(min_thickness 0.0254)
		(filled_areas_thickness no)
		(fill yes
			(thermal_gap 0.5)
			(thermal_bridge_width 0.5)
			(island_removal_mode 1)
			(island_area_min 10)
		)
		(polygon
			(pts
				(xy 236.6 155.477019) (xy 236.604644 155.536951) (xy 236.617154 155.584557) (xy 236.661324 155.662407)
				(xy 236.671154 155.675688) (xy 236.710825 155.734797) (xy 236.739323 155.813895) (xy 236.96 155.771)
				(xy 237.003895 155.549323) (xy 236.919579 155.546604) (xy 236.874135 155.547477) (xy 236.836003 155.540993)
				(xy 236.809764 155.519919) (xy 236.8 155.477019)
			)
		)
	)
	(zone
		(net 51)
		(net_name "Net-(C13-Pad1)")
		(layer "F.Cu")
		(name "$teardrop_padvia$")
		(hatch none 0.1)
		(priority 30143)
		(attr
			(teardrop
				(type padvia)
			)
		)
		(connect_pads yes
			(clearance 0)
		)
		(min_thickness 0.0254)
		(filled_areas_thickness no)
		(fill yes
			(thermal_gap 0.5)
			(thermal_bridge_width 0.5)
			(island_removal_mode 1)
			(island_area_min 10)
		)
		(polygon
			(pts
				(xy 130.066964 99.339095) (xy 130.122924 99.351039) (xy 130.185844 99.37655) (xy 130.236481 99.409075)
				(xy 130.280113 99.452912) (xy 130.305358 99.494461) (xy 130.321088 99.543508) (xy 130.325207 99.584182)
				(xy 130.770707 99.250707) (xy 130.325861 98.912533) (xy 130.325165 98.987411) (xy 130.318981 99.100239)
				(xy 130.305389 99.122778) (xy 130.279095 99.126964)
			)
		)
	)
	(zone
		(net 664)
		(net_name "/2xSFP+/KR to SFI #1/KR_R.RX+")
		(layer "F.Cu")
		(name "$teardrop_padvia$")
		(hatch none 0.1)
		(priority 31966)
		(attr
			(teardrop
				(type padvia)
			)
		)
		(connect_pads yes
			(clearance 0)
		)
		(min_thickness 0.0254)
		(filled_areas_thickness no)
		(fill yes
			(thermal_gap 0.5)
			(thermal_bridge_width 0.5)
			(island_removal_mode 1)
			(island_area_min 10)
		)
		(polygon
			(pts
				(xy 153.06 146.717279) (xy 153.084062 146.786651) (xy 153.120577 146.896598) (xy 153.130888 146.956686)
				(xy 153.13 147.018536) (xy 153.33 146.991) (xy 153.388769 146.76) (xy 153.307423 146.765298) (xy 153.255406 146.756508)
				(xy 153.233886 146.742657) (xy 153.221647 146.722599) (xy 153.22 146.717279)
			)
		)
	)
	(zone
		(net 624)
		(net_name "/PCIe redriver/TX_EQ1")
		(layer "F.Cu")
		(name "$teardrop_padvia$")
		(hatch none 0.1)
		(priority 31726)
		(attr
			(teardrop
				(type padvia)
			)
		)
		(connect_pads yes
			(clearance 0)
		)
		(min_thickness 0.0254)
		(filled_areas_thickness no)
		(fill yes
			(thermal_gap 0.5)
			(thermal_bridge_width 0.5)
			(island_removal_mode 1)
			(island_area_min 10)
		)
		(polygon
			(pts
				(xy 111.7875 147.209323) (xy 111.782682 147.278763) (xy 111.76896 147.330087) (xy 111.722245 147.405628)
				(xy 111.712702 147.417768) (xy 111.662919 147.484997) (xy 111.85 147.611) (xy 112.037081 147.484997)
				(xy 111.987299 147.417769) (xy 111.932894 147.334603) (xy 111.91781 147.281748) (xy 111.9125 147.209323)
			)
		)
	)
	(zone
		(net 279)
		(net_name "/Misc/TACH_{A5V}")
		(layer "F.Cu")
		(name "$teardrop_padvia$")
		(hatch none 0.1)
		(priority 32029)
		(attr
			(teardrop
				(type padvia)
			)
		)
		(connect_pads yes
			(clearance 0)
		)
		(min_thickness 0.0254)
		(filled_areas_thickness no)
		(fill yes
			(thermal_gap 0.5)
			(thermal_bridge_width 0.5)
			(island_removal_mode 1)
			(island_area_min 10)
		)
		(polygon
			(pts
				(xy 264.519208 76.843) (xy 264.513686 76.870072) (xy 264.49503 76.895611) (xy 264.468411 76.91178)
				(xy 264.42967 76.921399) (xy 264.401708 76.923) (xy 264.581708 77.124) (xy 264.761708 76.923) (xy 264.716208 76.918387)
				(xy 264.68324 76.9061) (xy 264.648864 76.867945) (xy 264.644208 76.843)
			)
		)
	)
	(zone
		(net 732)
		(net_name "Net-(U43C-CLKOUTB+)")
		(layer "F.Cu")
		(name "$teardrop_padvia$")
		(hatch none 0.1)
		(priority 31473)
		(attr
			(teardrop
				(type padvia)
			)
		)
		(connect_pads yes
			(clearance 0)
		)
		(min_thickness 0.0254)
		(filled_areas_thickness no)
		(fill yes
			(thermal_gap 0.5)
			(thermal_bridge_width 0.5)
			(island_removal_mode 1)
			(island_area_min 10)
		)
		(polygon
			(pts
				(xy 156.715607 139.496005) (xy 156.659844 139.544933) (xy 156.610961 139.574262) (xy 156.52167 139.597534)
				(xy 156.493497 139.601012) (xy 156.401227 139.614804) (xy 156.449293 139.860707) (xy 156.695196 139.908773)
				(xy 156.708304 139.801352) (xy 156.725939 139.696454) (xy 156.753485 139.643865) (xy 156.803995 139.584393)
			)
		)
	)
	(zone
		(net 2)
		(net_name "+3V3")
		(layer "F.Cu")
		(name "$teardrop_padvia$")
		(hatch none 0.1)
		(priority 30395)
		(attr
			(teardrop
				(type padvia)
			)
		)
		(connect_pads yes
			(clearance 0)
		)
		(min_thickness 0.0254)
		(filled_areas_thickness no)
		(fill yes
			(thermal_gap 0.5)
			(thermal_bridge_width 0.5)
			(island_removal_mode 1)
			(island_area_min 10)
		)
		(polygon
			(pts
				(xy 120.151 145.408) (xy 120.171322 145.452492) (xy 120.190096 145.485989) (xy 120.198614 145.518397)
				(xy 120.184438 145.545038) (xy 120.135129 145.561232) (xy 120.4 145.822) (xy 120.666128 145.562072)
				(xy 120.628143 145.552198) (xy 120.608437 145.536758) (xy 120.605486 145.502371) (xy 120.630516 145.452799)
				(xy 120.651 145.408)
			)
		)
	)
	(zone
		(net 85)
		(net_name "/Com Express 7 MGMT/MAFS_POWER")
		(layer "F.Cu")
		(name "$teardrop_padvia$")
		(hatch none 0.1)
		(priority 30488)
		(attr
			(teardrop
				(type padvia)
			)
		)
		(connect_pads yes
			(clearance 0)
		)
		(min_thickness 0.0254)
		(filled_areas_thickness no)
		(fill yes
			(thermal_gap 0.5)
			(thermal_bridge_width 0.5)
			(island_removal_mode 1)
			(island_area_min 10)
		)
		(polygon
			(pts
				(xy 259.558 161.4305) (xy 259.545052 161.430685) (xy 259.502923 161.4296) (xy 259.459032 161.41678)
				(xy 259.421088 161.380292) (xy 259.396798 161.308202) (xy 259.119 161.56) (xy 259.35908 161.837)
				(xy 259.377203 161.795134) (xy 259.399947 161.765615) (xy 259.4551 161.734966) (xy 259.536175 161.729868)
				(xy 259.558 161.7305)
			)
		)
	)
	(zone
		(net 237)
		(net_name "/Com Express 7 Interfaces/PCIe_{B2Bx4}.RX3-")
		(layer "F.Cu")
		(name "$teardrop_padvia$")
		(hatch none 0.1)
		(priority 31384)
		(attr
			(teardrop
				(type padvia)
			)
		)
		(connect_pads yes
			(clearance 0)
		)
		(min_thickness 0.0254)
		(filled_areas_thickness no)
		(fill yes
			(thermal_gap 0.5)
			(thermal_bridge_width 0.5)
			(island_removal_mode 1)
			(island_area_min 10)
		)
		(polygon
			(pts
				(xy 190.832504 159.8955) (xy 190.87929 159.900235) (xy 190.914742 159.913379) (xy 190.962939 159.958387)
				(xy 190.987116 159.996608) (xy 191.014485 160.039773) (xy 191.051147 160.081731) (xy 191.201 159.9185)
				(xy 191.18014 159.697823) (xy 191.079466 159.702452) (xy 190.996096 159.699019) (xy 190.994035 159.698895)
				(xy 190.832504 159.6935)
			)
		)
	)
	(zone
		(net 434)
		(net_name "/Com Express 7 MGMT/~{TYPE1}")
		(layer "F.Cu")
		(name "$teardrop_padvia$")
		(hatch none 0.1)
		(priority 31724)
		(attr
			(teardrop
				(type padvia)
			)
		)
		(connect_pads yes
			(clearance 0)
		)
		(min_thickness 0.0254)
		(filled_areas_thickness no)
		(fill yes
			(thermal_gap 0.5)
			(thermal_bridge_width 0.5)
			(island_removal_mode 1)
			(island_area_min 10)
		)
		(polygon
			(pts
				(xy 249.4125 133.374323) (xy 249.407682 133.443763) (xy 249.39396 133.495087) (xy 249.347245 133.570628)
				(xy 249.337702 133.582768) (xy 249.287919 133.649997) (xy 249.475 133.776) (xy 249.662081 133.649997)
				(xy 249.612299 133.582769) (xy 249.557894 133.499603) (xy 249.54281 133.446748) (xy 249.5375 133.374323)
			)
		)
	)
	(zone
		(net 2)
		(net_name "+3V3")
		(layer "F.Cu")
		(name "$teardrop_padvia$")
		(hatch none 0.1)
		(priority 30408)
		(attr
			(teardrop
				(type padvia)
			)
		)
		(connect_pads yes
			(clearance 0)
		)
		(min_thickness 0.0254)
		(filled_areas_thickness no)
		(fill yes
			(thermal_gap 0.5)
			(thermal_bridge_width 0.5)
			(island_removal_mode 1)
			(island_area_min 10)
		)
		(polygon
			(pts
				(xy 115.65 145.408) (xy 115.670403 145.452645) (xy 115.689221 145.486192) (xy 115.697795 145.518655)
				(xy 115.683697 145.545365) (xy 115.6345 145.561652) (xy 115.9 145.822) (xy 116.1655 145.561652)
				(xy 116.127407 145.551832) (xy 116.107642 145.536425) (xy 116.104648 145.5021) (xy 116.129597 145.452645)
				(xy 116.15 145.408)
			)
		)
	)
	(zone
		(net 593)
		(net_name "Net-(U24-V_{CCP})")
		(layer "F.Cu")
		(name "$teardrop_padvia$")
		(hatch none 0.1)
		(priority 31151)
		(attr
			(teardrop
				(type padvia)
			)
		)
		(connect_pads yes
			(clearance 0)
		)
		(min_thickness 0.0254)
		(filled_areas_thickness no)
		(fill yes
			(thermal_gap 0.5)
			(thermal_bridge_width 0.5)
			(island_removal_mode 1)
			(island_area_min 10)
		)
		(polygon
			(pts
				(xy 253.474695 89.348883) (xy 253.45299 89.349721) (xy 253.436628 89.337294) (xy 253.414518 89.275129)
				(xy 253.396798 89.173201) (xy 253.144293 89.450706) (xy 253.417501 89.695812) (xy 253.44255 89.616492)
				(xy 253.49984 89.550623) (xy 253.58575 89.500802) (xy 253.616116 89.490304)
			)
		)
	)
	(zone
		(net 92)
		(net_name "/Com Express 7 Interfaces/PCIe_{B2Ax4}.RX2+")
		(layer "F.Cu")
		(name "$teardrop_padvia$")
		(hatch none 0.1)
		(priority 31338)
		(attr
			(teardrop
				(type padvia)
			)
		)
		(connect_pads yes
			(clearance 0)
		)
		(min_thickness 0.0254)
		(filled_areas_thickness no)
		(fill yes
			(thermal_gap 0.5)
			(thermal_bridge_width 0.5)
			(island_removal_mode 1)
			(island_area_min 10)
		)
		(polygon
			(pts
				(xy 290.153 75.019852) (xy 290.148265 75.066638) (xy 290.135121 75.10209) (xy 290.090113 75.150287)
				(xy 290.051893 75.174463) (xy 290.008726 75.201832) (xy 289.966768 75.238495) (xy 290.13 75.388348)
				(xy 290.350677 75.367488) (xy 290.346048 75.266817) (xy 290.34948 75.18345) (xy 290.349605 75.181383)
				(xy 290.355 75.019852)
			)
		)
	)
	(zone
		(net 873)
		(net_name "Net-(U34-EN)")
		(layer "F.Cu")
		(name "$teardrop_padvia$")
		(hatch none 0.1)
		(priority 30976)
		(attr
			(teardrop
				(type padvia)
			)
		)
		(connect_pads yes
			(clearance 0)
		)
		(min_thickness 0.0254)
		(filled_areas_thickness no)
		(fill yes
			(thermal_gap 0.5)
			(thermal_bridge_width 0.5)
			(island_removal_mode 1)
			(island_area_min 10)
		)
		(polygon
			(pts
				(xy 243.238 131.8175) (xy 243.175134 131.797531) (xy 243.143156 131.771079) (xy 243.114642 131.733668)
				(xy 243.092118 131.686473) (xy 243.076907 131.628833) (xy 243.076798 131.628202) (xy 242.799 131.88)
				(xy 243.076798 132.131798) (xy 243.091095 132.076365) (xy 243.112175 132.03048) (xy 243.13954 131.992799)
				(xy 243.170448 131.965566) (xy 243.203735 131.948528) (xy 243.236566 131.942511) (xy 243.238 131.9425)
			)
		)
	)
	(zone
		(net 366)
		(net_name "Net-(J12D-WDT)")
		(layer "F.Cu")
		(name "$teardrop_padvia$")
		(hatch none 0.1)
		(priority 30640)
		(attr
			(teardrop
				(type padvia)
			)
		)
		(connect_pads yes
			(clearance 0)
		)
		(min_thickness 0.0254)
		(filled_areas_thickness no)
		(fill yes
			(thermal_gap 0.5)
			(thermal_bridge_width 0.5)
			(island_removal_mode 1)
			(island_area_min 10)
		)
		(polygon
			(pts
				(xy 189.0875 164.07) (xy 189.098438 164.031177) (xy 189.120195 164.016067) (xy 189.16 164.01) (xy 189.025 163.134)
				(xy 188.89 164.01) (xy 188.925281 164.014517) (xy 188.946797 164.026138) (xy 188.961995 164.058961)
				(xy 188.9625 164.07)
			)
		)
	)
	(zone
		(net 359)
		(net_name "/Com Express 7 MGMT/SMBus.~{INT}")
		(layer "F.Cu")
		(name "$teardrop_padvia$")
		(hatch none 0.1)
		(priority 31786)
		(attr
			(teardrop
				(type padvia)
			)
		)
		(connect_pads yes
			(clearance 0)
		)
		(min_thickness 0.0254)
		(filled_areas_thickness no)
		(fill yes
			(thermal_gap 0.5)
			(thermal_bridge_width 0.5)
			(island_removal_mode 1)
			(island_area_min 10)
		)
		(polygon
			(pts
				(xy 186.9625 132.400677) (xy 186.967318 132.331236) (xy 186.98104 132.279912) (xy 187.027755 132.20437)
				(xy 187.037299 132.192229) (xy 187.087081 132.125003) (xy 186.9 131.999) (xy 186.712919 132.125003)
				(xy 186.762701 132.192231) (xy 186.817106 132.275397) (xy 186.83219 132.328251) (xy 186.8375 132.400677)
			)
		)
	)
	(zone
		(net 1)
		(net_name "GND")
		(layer "F.Cu")
		(name "$teardrop_padvia$")
		(hatch none 0.1)
		(priority 30790)
		(attr
			(teardrop
				(type padvia)
			)
		)
		(connect_pads yes
			(clearance 0)
		)
		(min_thickness 0.0254)
		(filled_areas_thickness no)
		(fill yes
			(thermal_gap 0.5)
			(thermal_bridge_width 0.5)
			(island_removal_mode 1)
			(island_area_min 10)
		)
		(polygon
			(pts
				(xy 152.969177 70.9105) (xy 152.811606 70.903569) (xy 152.698078 70.875049) (xy 152.656278 70.858)
				(xy 152.5675 71.0605) (xy 152.656278 71.263) (xy 152.752317 71.228618) (xy 152.854189 71.2134) (xy 152.969177 71.2105)
			)
		)
	)
	(zone
		(net 284)
		(net_name "/Misc/PWM_{C5V}")
		(layer "F.Cu")
		(name "$teardrop_padvia$")
		(hatch none 0.1)
		(priority 30007)
		(attr
			(teardrop
				(type padvia)
			)
		)
		(connect_pads yes
			(clearance 0)
		)
		(min_thickness 0.0254)
		(filled_areas_thickness no)
		(fill yes
			(thermal_gap 0.5)
			(thermal_bridge_width 0.5)
			(island_removal_mode 1)
			(island_area_min 10)
		)
		(polygon
			(pts
				(xy 231.223207 73.204379) (xy 231.242418 73.092884) (xy 231.304777 72.965774) (xy 231.419498 72.822593)
				(xy 231.592986 72.669697) (xy 231.820209 72.522375) (xy 231.879928 72.490568) (xy 231.160707 71.859)
				(xy 230.441486 72.490568) (xy 230.681706 72.635511) (xy 230.786957 72.716099) (xy 230.880521 72.800833)
				(xy 230.954617 72.881528) (xy 231.015159 72.96348) (xy 231.055846 73.035756) (xy 231.08353 73.107416)
				(xy 231.098207 73.204379)
			)
		)
	)
	(zone
		(net 51)
		(net_name "Net-(C13-Pad1)")
		(layer "F.Cu")
		(name "$teardrop_padvia$")
		(hatch none 0.1)
		(priority 30473)
		(attr
			(teardrop
				(type padvia)
			)
		)
		(connect_pads yes
			(clearance 0)
		)
		(min_thickness 0.0254)
		(filled_areas_thickness no)
		(fill yes
			(thermal_gap 0.5)
			(thermal_bridge_width 0.5)
			(island_removal_mode 1)
			(island_area_min 10)
		)
		(polygon
			(pts
				(xy 129.938 98.86) (xy 129.92113 98.860338) (xy 129.876174 98.859759) (xy 129.828831 98.847941)
				(xy 129.786427 98.813362) (xy 129.756292 98.7445) (xy 129.499 99.01) (xy 129.756292 99.2755) (xy 129.771849 99.230731)
				(xy 129.792565 99.199115) (xy 129.843701 99.166381) (xy 129.92113 99.159662) (xy 129.938 99.16)
			)
		)
	)
	(zone
		(net 649)
		(net_name "/2xSFP+/KR to SFI #1/MDIO")
		(layer "F.Cu")
		(name "$teardrop_padvia$")
		(hatch none 0.1)
		(priority 31456)
		(attr
			(teardrop
				(type padvia)
			)
		)
		(connect_pads yes
			(clearance 0)
		)
		(min_thickness 0.0254)
		(filled_areas_thickness no)
		(fill yes
			(thermal_gap 0.5)
			(thermal_bridge_width 0.5)
			(island_removal_mode 1)
			(island_area_min 10)
		)
		(polygon
			(pts
				(xy 143.203283 143.96833) (xy 143.182421 143.970711) (xy 143.164159 143.96195) (xy 143.133725 143.911885)
				(xy 143.101798 143.773202) (xy 142.849293 144.050707) (xy 143.125776 144.290912) (xy 143.151115 144.196044)
				(xy 143.209248 144.112738) (xy 143.287758 144.058211) (xy 143.29167 144.056717)
			)
		)
	)
	(zone
		(net 970)
		(net_name "/M.2 key M #2/M2_3V3")
		(layer "F.Cu")
		(name "$teardrop_padvia$")
		(hatch none 0.1)
		(priority 30766)
		(attr
			(teardrop
				(type padvia)
			)
		)
		(connect_pads yes
			(clearance 0)
		)
		(min_thickness 0.0254)
		(filled_areas_thickness no)
		(fill yes
			(thermal_gap 0.5)
			(thermal_bridge_width 0.5)
			(island_removal_mode 1)
			(island_area_min 10)
		)
		(polygon
			(pts
				(xy 304.597 80.978677) (xy 304.603932 80.8211) (xy 304.632456 80.707565) (xy 304.6495 80.665778)
				(xy 304.447 80.577) (xy 304.2445 80.665778) (xy 304.278883 80.761822) (xy 304.294101 80.863702)
				(xy 304.297 80.978677)
			)
		)
	)
	(zone
		(net 187)
		(net_name "/OCuLink/PCIe_{x4}.RX0-")
		(layer "F.Cu")
		(name "$teardrop_padvia$")
		(hatch none 0.1)
		(priority 32064)
		(attr
			(teardrop
				(type padvia)
			)
		)
		(connect_pads yes
			(clearance 0)
		)
		(min_thickness 0.0254)
		(filled_areas_thickness no)
		(fill yes
			(thermal_gap 0.5)
			(thermal_bridge_width 0.5)
			(island_removal_mode 1)
			(island_area_min 10)
		)
		(polygon
			(pts
				(xy 97.103 151.797) (xy 97.095802 151.776352) (xy 97.086208 151.744016) (xy 97.093035 151.729993)
				(xy 97.1145 151.720004) (xy 97.002 151.471) (xy 96.8895 151.720004) (xy 96.910676 151.729729) (xy 96.917731 151.743357)
				(xy 96.908198 151.776352) (xy 96.901 151.797)
			)
		)
	)
	(zone
		(net 549)
		(net_name "Net-(R14-Pad2)")
		(layer "F.Cu")
		(name "$teardrop_padvia$")
		(hatch none 0.1)
		(priority 30428)
		(attr
			(teardrop
				(type padvia)
			)
		)
		(connect_pads yes
			(clearance 0)
		)
		(min_thickness 0.0254)
		(filled_areas_thickness no)
		(fill yes
			(thermal_gap 0.5)
			(thermal_bridge_width 0.5)
			(island_removal_mode 1)
			(island_area_min 10)
		)
		(polygon
			(pts
				(xy 135.42 113.445) (xy 135.370167 113.43574) (xy 135.346156 113.419372) (xy 135.326648 113.390919)
				(xy 135.312274 113.32) (xy 134.844 113.545) (xy 135.312274 113.77) (xy 135.318547 113.72239) (xy 135.332162 113.688567)
				(xy 135.372122 113.653408) (xy 135.42 113.645)
			)
		)
	)
	(zone
		(net 1)
		(net_name "GND")
		(layer "F.Cu")
		(name "$teardrop_padvia$")
		(hatch none 0.1)
		(priority 30087)
		(attr
			(teardrop
				(type padvia)
			)
		)
		(connect_pads yes
			(clearance 0)
		)
		(min_thickness 0.0254)
		(filled_areas_thickness no)
		(fill yes
			(thermal_gap 0.5)
			(thermal_bridge_width 0.5)
			(island_removal_mode 1)
			(island_area_min 10)
		)
		(polygon
			(pts
				(xy 184.376404 72.702163) (xy 184.285027 72.697312) (xy 184.213098 72.683354) (xy 184.111548 72.636414)
				(xy 184.032705 72.576993) (xy 183.916949 72.490362) (xy 183.70761 72.802163) (xy 183.916949 73.113964)
				(xy 184.032704 73.027333) (xy 184.099586 72.975993) (xy 184.169321 72.936497) (xy 184.256673 72.911127)
				(xy 184.376404 72.902163)
			)
		)
	)
	(zone
		(net 86)
		(net_name "/Com Express 7 Interfaces/PCIe_{B2Ax4}.RX0-")
		(layer "F.Cu")
		(name "$teardrop_padvia$")
		(hatch none 0.1)
		(priority 30362)
		(attr
			(teardrop
				(type padvia)
			)
		)
		(connect_pads yes
			(clearance 0)
		)
		(min_thickness 0.0254)
		(filled_areas_thickness no)
		(fill yes
			(thermal_gap 0.5)
			(thermal_bridge_width 0.5)
			(island_removal_mode 1)
			(island_area_min 10)
		)
		(polygon
			(pts
				(xy 296.744 74.87) (xy 296.74098 74.855836) (xy 296.738965 74.825494) (xy 296.751965 74.814378)
				(xy 296.782322 74.81) (xy 296.699 74.034) (xy 296.549 74.253414) (xy 296.568141 74.467736) (xy 296.553216 74.713526)
				(xy 296.542 74.87)
			)
		)
	)
	(zone
		(net 591)
		(net_name "Net-(U24-+12V_{IN})")
		(layer "F.Cu")
		(name "$teardrop_padvia$")
		(hatch none 0.1)
		(priority 30714)
		(attr
			(teardrop
				(type padvia)
			)
		)
		(connect_pads yes
			(clearance 0)
		)
		(min_thickness 0.0254)
		(filled_areas_thickness no)
		(fill yes
			(thermal_gap 0.5)
			(thermal_bridge_width 0.5)
			(island_removal_mode 1)
			(island_area_min 10)
		)
		(polygon
			(pts
				(xy 254.056 87.739999) (xy 254.060806 87.73997) (xy 254.08628 87.741149) (xy 254.112048 87.750737)
				(xy 254.131993 87.777198) (xy 254.14 87.828999) (xy 254.701 87.64) (xy 254.14 87.450999) (xy 254.13542 87.492301)
				(xy 254.123361 87.518368) (xy 254.088848 87.538426) (xy 254.060806 87.540028) (xy 254.056 87.539999)
			)
		)
	)
	(zone
		(net 1)
		(net_name "GND")
		(layer "F.Cu")
		(name "$teardrop_padvia$")
		(hatch none 0.1)
		(priority 30593)
		(attr
			(teardrop
				(type padvia)
			)
		)
		(connect_pads yes
			(clearance 0)
		)
		(min_thickness 0.0254)
		(filled_areas_thickness no)
		(fill yes
			(thermal_gap 0.5)
			(thermal_bridge_width 0.5)
			(island_removal_mode 1)
			(island_area_min 10)
		)
		(polygon
			(pts
				(xy 190.925 162.2) (xy 190.928333 162.214486) (xy 190.93119 162.24461) (xy 190.919036 162.255651)
				(xy 190.89 162.26) (xy 191.025 163.136) (xy 191.16 162.26) (xy 191.130666 162.255525) (xy 191.118642 162.244199)
				(xy 191.121667 162.214486) (xy 191.125 162.2)
			)
		)
	)
	(zone
		(net 771)
		(net_name "/Backplane/PCIe_{x2}.RX1+")
		(layer "F.Cu")
		(name "$teardrop_padvia$")
		(hatch none 0.1)
		(priority 32034)
		(attr
			(teardrop
				(type padvia)
			)
		)
		(connect_pads yes
			(clearance 0)
		)
		(min_thickness 0.0254)
		(filled_areas_thickness no)
		(fill yes
			(thermal_gap 0.5)
			(thermal_bridge_width 0.5)
			(island_removal_mode 1)
			(island_area_min 10)
		)
		(polygon
			(pts
				(xy 314.038 161.5645) (xy 314.117272 161.546854) (xy 314.202896 161.525263) (xy 314.250145 161.523372)
				(xy 314.300083 161.533) (xy 314.364 161.408) (xy 314.088953 161.340707) (xy 314.08432 161.36751)
				(xy 314.073289 161.375052) (xy 314.051941 161.367832) (xy 314.038 161.3625)
			)
		)
	)
	(zone
		(net 931)
		(net_name "/2xSFP+/SFP0_LEDG")
		(layer "F.Cu")
		(name "$teardrop_padvia$")
		(hatch none 0.1)
		(priority 31052)
		(attr
			(teardrop
				(type padvia)
			)
		)
		(connect_pads yes
			(clearance 0)
		)
		(min_thickness 0.0254)
		(filled_areas_thickness no)
		(fill yes
			(thermal_gap 0.5)
			(thermal_bridge_width 0.5)
			(island_removal_mode 1)
			(island_area_min 10)
		)
		(polygon
			(pts
				(xy 156.192 166.2975) (xy 156.132588 166.277727) (xy 156.076503 166.214453) (xy 156.054801 166.165828)
				(xy 156.040127 166.106468) (xy 156.038347 166.0945) (xy 155.778 166.36) (xy 156.038347 166.6255)
				(xy 156.051197 166.565361) (xy 156.071131 166.515477) (xy 156.097056 166.475358) (xy 156.126876 166.446345)
				(xy 156.158294 166.428854) (xy 156.190105 166.422521) (xy 156.192 166.4225)
			)
		)
	)
	(zone
		(net 377)
		(net_name "/Com Express 7 Interfaces/USB1.D-")
		(layer "F.Cu")
		(name "$teardrop_padvia$")
		(hatch none 0.1)
		(priority 30295)
		(attr
			(teardrop
				(type padvia)
			)
		)
		(connect_pads yes
			(clearance 0)
		)
		(min_thickness 0.0254)
		(filled_areas_thickness no)
		(fill yes
			(thermal_gap 0.5)
			(thermal_bridge_width 0.5)
			(island_removal_mode 1)
			(island_area_min 10)
		)
		(polygon
			(pts
				(xy 198.1775 164.07) (xy 198.168097 163.896083) (xy 198.155714 163.661032) (xy 198.159219 163.521494)
				(xy 198.175 163.363685) (xy 198.025 163.134) (xy 197.945877 164.01) (xy 197.977617 164.014484) (xy 197.992473 164.025869)
				(xy 197.994085 164.057811) (xy 197.9925 164.07)
			)
		)
	)
	(zone
		(net 62)
		(net_name "+12V_AON")
		(layer "F.Cu")
		(name "$teardrop_padvia$")
		(hatch none 0.1)
		(priority 30737)
		(attr
			(teardrop
				(type padvia)
			)
		)
		(connect_pads yes
			(clearance 0)
		)
		(min_thickness 0.0254)
		(filled_areas_thickness no)
		(fill yes
			(thermal_gap 0.5)
			(thermal_bridge_width 0.5)
			(island_removal_mode 1)
			(island_area_min 10)
		)
		(polygon
			(pts
				(xy 305.7645 147.17) (xy 305.759203 147.201401) (xy 305.742126 147.233656) (xy 305.715646 147.259863)
				(xy 305.677224 147.280921) (xy 305.63295 147.29295) (xy 305.825 147.811) (xy 306.01705 147.29295)
				(xy 305.973198 147.280629) (xy 305.939633 147.262077) (xy 305.898347 147.211289) (xy 305.8895 147.17)
			)
		)
	)
	(zone
		(net 988)
		(net_name "Net-(Q13-C)")
		(layer "F.Cu")
		(name "$teardrop_padvia$")
		(hatch none 0.1)
		(priority 30196)
		(attr
			(teardrop
				(type padvia)
			)
		)
		(connect_pads yes
			(clearance 0)
		)
		(min_thickness 0.0254)
		(filled_areas_thickness no)
		(fill yes
			(thermal_gap 0.5)
			(thermal_bridge_width 0.5)
			(island_removal_mode 1)
			(island_area_min 10)
		)
		(polygon
			(pts
				(xy 202.3495 79.03) (xy 202.343825 79.068514) (xy 202.324097 79.107619) (xy 202.297219 79.134469)
				(xy 202.258111 79.156281) (xy 202.1795 79.173927) (xy 202.4495 79.651) (xy 202.7195 79.173927) (xy 202.664894 79.164382)
				(xy 202.622658 79.147775) (xy 202.569693 79.100089) (xy 202.549816 79.039186) (xy 202.5495 79.03)
			)
		)
	)
	(zone
		(net 125)
		(net_name "/2xUSB3.0+RJ45/P2_D-")
		(layer "F.Cu")
		(name "$teardrop_padvia$")
		(hatch none 0.1)
		(priority 30489)
		(attr
			(teardrop
				(type padvia)
			)
		)
		(connect_pads yes
			(clearance 0)
		)
		(min_thickness 0.0254)
		(filled_areas_thickness no)
		(fill yes
			(thermal_gap 0.5)
			(thermal_bridge_width 0.5)
			(island_removal_mode 1)
			(island_area_min 10)
		)
		(polygon
			(pts
				(xy 129.236343 116.0025) (xy 129.29596 115.967912) (xy 129.370351 115.937436) (xy 129.447472 115.917509)
				(xy 129.530124 115.909048) (xy 129.634492 115.92) (xy 129.601 115.6) (xy 129.305 115.50316) (xy 129.308054 115.632518)
				(xy 129.294889 115.728557) (xy 129.27747 115.771885) (xy 129.251918 115.804943) (xy 129.236343 115.8175)
			)
		)
	)
	(zone
		(net 38)
		(net_name "Net-(J100-SUSCLK)")
		(layer "F.Cu")
		(name "$teardrop_padvia$")
		(hatch none 0.1)
		(priority 31048)
		(attr
			(teardrop
				(type padvia)
			)
		)
		(connect_pads yes
			(clearance 0)
		)
		(min_thickness 0.0254)
		(filled_areas_thickness no)
		(fill yes
			(thermal_gap 0.5)
			(thermal_bridge_width 0.5)
			(island_removal_mode 1)
			(island_area_min 10)
		)
		(polygon
			(pts
				(xy 144.343 82.9975) (xy 144.283588 82.977727) (xy 144.227503 82.914453) (xy 144.205801 82.865828)
				(xy 144.191127 82.806468) (xy 144.189347 82.7945) (xy 143.929 83.06) (xy 144.189347 83.3255) (xy 144.202197 83.265361)
				(xy 144.222131 83.215477) (xy 144.248056 83.175358) (xy 144.277876 83.146345) (xy 144.309294 83.128854)
				(xy 144.341105 83.122521) (xy 144.343 83.1225)
			)
		)
	)
	(zone
		(net 1)
		(net_name "GND")
		(layer "F.Cu")
		(name "$teardrop_padvia$")
		(hatch none 0.1)
		(priority 30610)
		(attr
			(teardrop
				(type padvia)
			)
		)
		(connect_pads yes
			(clearance 0)
		)
		(min_thickness 0.0254)
		(filled_areas_thickness no)
		(fill yes
			(thermal_gap 0.5)
			(thermal_bridge_width 0.5)
			(island_removal_mode 1)
			(island_area_min 10)
		)
		(polygon
			(pts
				(xy 205.425 162.2) (xy 205.428333 162.214486) (xy 205.43119 162.24461) (xy 205.419036 162.255651)
				(xy 205.39 162.26) (xy 205.525 163.136) (xy 205.66 162.26) (xy 205.630666 162.255525) (xy 205.618642 162.244199)
				(xy 205.621667 162.214486) (xy 205.625 162.2)
			)
		)
	)
	(zone
		(net 347)
		(net_name "/2xUSB3.0+RJ45/~{GBE0_ACT}")
		(layer "F.Cu")
		(name "$teardrop_padvia$")
		(hatch none 0.1)
		(priority 31901)
		(attr
			(teardrop
				(type padvia)
			)
		)
		(connect_pads yes
			(clearance 0)
		)
		(min_thickness 0.0254)
		(filled_areas_thickness no)
		(fill yes
			(thermal_gap 0.5)
			(thermal_bridge_width 0.5)
			(island_removal_mode 1)
			(island_area_min 10)
		)
		(polygon
			(pts
				(xy 164.219972 114.25836) (xy 164.241126 114.286262) (xy 164.247606 114.311695) (xy 164.230399 114.354244)
				(xy 164.181809 114.402514) (xy 164.112919 114.474997) (xy 164.300707 114.600707) (xy 164.487081 114.474997)
				(xy 164.429376 114.36356) (xy 164.423136 114.347691) (xy 164.385714 114.266403) (xy 164.30836 114.169972)
			)
		)
	)
	(zone
		(net 355)
		(net_name "Net-(J12D-LPC_CLK{slash}ESPI_CK)")
		(layer "F.Cu")
		(name "$teardrop_padvia$")
		(hatch none 0.1)
		(priority 30646)
		(attr
			(teardrop
				(type padvia)
			)
		)
		(connect_pads yes
			(clearance 0)
		)
		(min_thickness 0.0254)
		(filled_areas_thickness no)
		(fill yes
			(thermal_gap 0.5)
			(thermal_bridge_width 0.5)
			(island_removal_mode 1)
			(island_area_min 10)
		)
		(polygon
			(pts
				(xy 180.5875 164.07) (xy 180.598438 164.031177) (xy 180.620195 164.016067) (xy 180.66 164.01) (xy 180.525 163.134)
				(xy 180.39 164.01) (xy 180.425281 164.014517) (xy 180.446797 164.026138) (xy 180.461995 164.058961)
				(xy 180.4625 164.07)
			)
		)
	)
	(zone
		(net 73)
		(net_name "+3V3_AON")
		(layer "F.Cu")
		(name "$teardrop_padvia$")
		(hatch none 0.1)
		(priority 30236)
		(attr
			(teardrop
				(type padvia)
			)
		)
		(connect_pads yes
			(clearance 0)
		)
		(min_thickness 0.0254)
		(filled_areas_thickness no)
		(fill yes
			(thermal_gap 0.5)
			(thermal_bridge_width 0.5)
			(island_removal_mode 1)
			(island_area_min 10)
		)
		(polygon
			(pts
				(xy 244.981316 126.949185) (xy 244.961497 126.929851) (xy 244.911256 126.878763) (xy 244.863808 126.814555)
				(xy 244.831081 126.732914) (xy 244.825 126.629526) (xy 244.529293 126.709293) (xy 244.474527 127.03)
				(xy 244.528255 127.02494) (xy 244.575708 127.029458) (xy 244.659204 127.062888) (xy 244.73597 127.12711)
				(xy 244.751658 127.143306) (xy 244.769185 127.161316)
			)
		)
	)
	(zone
		(net 73)
		(net_name "+3V3_AON")
		(layer "F.Cu")
		(name "$teardrop_padvia$")
		(hatch none 0.1)
		(priority 30197)
		(attr
			(teardrop
				(type padvia)
			)
		)
		(connect_pads yes
			(clearance 0)
		)
		(min_thickness 0.0254)
		(filled_areas_thickness no)
		(fill yes
			(thermal_gap 0.5)
			(thermal_bridge_width 0.5)
			(island_removal_mode 1)
			(island_area_min 10)
		)
		(polygon
			(pts
				(xy 304.752 147.04611) (xy 304.735366 146.976108) (xy 304.706423 146.911702) (xy 304.654642 146.780192)
				(xy 304.647678 146.712217) (xy 304.665 146.644897) (xy 304.37 146.609) (xy 304.201703 146.925863)
				(xy 304.25882 146.930895) (xy 304.293099 146.94359) (xy 304.307994 146.958584) (xy 304.313479 146.976196)
				(xy 304.307247 147.018442) (xy 304.302 147.04611)
			)
		)
	)
	(zone
		(net 209)
		(net_name "/Com Express 7 Interfaces/PCIe_{B1x4}.RX3-")
		(layer "F.Cu")
		(name "$teardrop_padvia$")
		(hatch none 0.1)
		(priority 30281)
		(attr
			(teardrop
				(type padvia)
			)
		)
		(connect_pads yes
			(clearance 0)
		)
		(min_thickness 0.0254)
		(filled_areas_thickness no)
		(fill yes
			(thermal_gap 0.5)
			(thermal_bridge_width 0.5)
			(island_removal_mode 1)
			(island_area_min 10)
		)
		(polygon
			(pts
				(xy 204.8685 162.2) (xy 204.879599 162.373112) (xy 204.894216 162.60051) (xy 204.891181 162.735138)
				(xy 204.875 162.887021) (xy 205.025 163.136) (xy 205.108295 162.26) (xy 205.077864 162.255523) (xy 205.065097 162.244185)
				(xy 205.06742 162.214227) (xy 205.0705 162.2)
			)
		)
	)
	(zone
		(net 206)
		(net_name "/Backplane/USB.D+")
		(layer "F.Cu")
		(name "$teardrop_padvia$")
		(hatch none 0.1)
		(priority 31534)
		(attr
			(teardrop
				(type padvia)
			)
		)
		(connect_pads yes
			(clearance 0)
		)
		(min_thickness 0.0254)
		(filled_areas_thickness no)
		(fill yes
			(thermal_gap 0.5)
			(thermal_bridge_width 0.5)
			(island_removal_mode 1)
			(island_area_min 10)
		)
		(polygon
			(pts
				(xy 212.8475 148.744916) (xy 212.853356 148.920057) (xy 212.856323 149.091365) (xy 213.077 149.101)
				(xy 213.202003 148.912919) (xy 213.13422 148.877253) (xy 213.094585 148.85792) (xy 213.062257 148.833824)
				(xy 213.04048 148.798358) (xy 213.0325 148.744916)
			)
		)
	)
	(zone
		(net 189)
		(net_name "/OCuLink/PCIe_{x4}.RX1-")
		(layer "F.Cu")
		(name "$teardrop_padvia$")
		(hatch none 0.1)
		(priority 32085)
		(attr
			(teardrop
				(type padvia)
			)
		)
		(connect_pads yes
			(clearance 0)
		)
		(min_thickness 0.0254)
		(filled_areas_thickness no)
		(fill yes
			(thermal_gap 0.5)
			(thermal_bridge_width 0.5)
			(island_removal_mode 1)
			(island_area_min 10)
		)
		(polygon
			(pts
				(xy 98.399 151.147) (xy 98.406198 151.167648) (xy 98.415792 151.199984) (xy 98.408965 151.214007)
				(xy 98.3875 151.223995) (xy 98.5 151.473) (xy 98.6125 151.223995) (xy 98.591324 151.214271) (xy 98.584269 151.200643)
				(xy 98.593802 151.167648) (xy 98.601 151.147)
			)
		)
	)
	(zone
		(net 365)
		(net_name "/Com Express 7 MGMT/PWR_OK")
		(layer "F.Cu")
		(name "$teardrop_padvia$")
		(hatch none 0.1)
		(priority 30982)
		(attr
			(teardrop
				(type padvia)
			)
		)
		(connect_pads yes
			(clearance 0)
		)
		(min_thickness 0.0254)
		(filled_areas_thickness no)
		(fill yes
			(thermal_gap 0.5)
			(thermal_bridge_width 0.5)
			(island_removal_mode 1)
			(island_area_min 10)
		)
		(polygon
			(pts
				(xy 301.8225 128.228) (xy 301.842469 128.165134) (xy 301.868921 128.133156) (xy 301.906332 128.104642)
				(xy 301.953527 128.082118) (xy 302.011167 128.066907) (xy 302.011798 128.066798) (xy 301.76 127.789)
				(xy 301.508202 128.066798) (xy 301.563635 128.081095) (xy 301.60952 128.102175) (xy 301.647201 128.12954)
				(xy 301.674434 128.160448) (xy 301.691472 128.193735) (xy 301.697489 128.226566) (xy 301.6975 128.228)
			)
		)
	)
	(zone
		(net 313)
		(net_name "/2xUSB3.0+RJ45/USB_1.D+")
		(layer "F.Cu")
		(name "$teardrop_padvia$")
		(hatch none 0.1)
		(priority 30299)
		(attr
			(teardrop
				(type padvia)
			)
		)
		(connect_pads yes
			(clearance 0)
		)
		(min_thickness 0.0254)
		(filled_areas_thickness no)
		(fill yes
			(thermal_gap 0.5)
			(thermal_bridge_width 0.5)
			(island_removal_mode 1)
			(island_area_min 10)
		)
		(polygon
			(pts
				(xy 196.8725 167.75) (xy 196.881903 167.923917) (xy 196.894286 168.158968) (xy 196.890781 168.298506)
				(xy 196.875 168.456314) (xy 197.025 168.686) (xy 197.104123 167.81) (xy 197.072384 167.805516) (xy 197.057527 167.794131)
				(xy 197.055915 167.762189) (xy 197.0575 167.75)
			)
		)
	)
	(zone
		(net 290)
		(net_name "/2xUSB3.0+RJ45/GbE.MDI2+")
		(layer "F.Cu")
		(name "$teardrop_padvia$")
		(hatch none 0.1)
		(priority 30315)
		(attr
			(teardrop
				(type padvia)
			)
		)
		(connect_pads yes
			(clearance 0)
		)
		(min_thickness 0.0254)
		(filled_areas_thickness no)
		(fill yes
			(thermal_gap 0.5)
			(thermal_bridge_width 0.5)
			(island_removal_mode 1)
			(island_area_min 10)
		)
		(polygon
			(pts
				(xy 178.875 167.75) (xy 178.882191 167.932252) (xy 178.891641 168.183885) (xy 178.888369 168.333893)
				(xy 178.875 168.504204) (xy 179.025 168.686) (xy 179.090241 167.81) (xy 179.055265 167.805495) (xy 179.035678 167.793958)
				(xy 179.024981 167.762811) (xy 179.024965 167.754084) (xy 179.025 167.75)
			)
		)
	)
	(zone
		(net 1)
		(net_name "GND")
		(layer "F.Cu")
		(name "$teardrop_padvia$")
		(hatch none 0.1)
		(priority 30201)
		(attr
			(teardrop
				(type padvia)
			)
		)
		(connect_pads yes
			(clearance 0)
		)
		(min_thickness 0.0254)
		(filled_areas_thickness no)
		(fill yes
			(thermal_gap 0.5)
			(thermal_bridge_width 0.5)
			(island_removal_mode 1)
			(island_area_min 10)
		)
		(polygon
			(pts
				(xy 305.4 147.046508) (xy 305.394674 147.018679) (xy 305.388273 146.987179) (xy 305.394484 146.957363)
				(xy 305.426996 146.934942) (xy 305.499496 146.925624) (xy 305.33 146.609) (xy 305.035 146.646626)
				(xy 305.053141 146.723338) (xy 305.037511 146.812341) (xy 304.994929 146.913127) (xy 304.963692 146.984135)
				(xy 304.95 147.046508)
			)
		)
	)
	(zone
		(net 2)
		(net_name "+3V3")
		(layer "F.Cu")
		(name "$teardrop_padvia$")
		(hatch none 0.1)
		(priority 32148)
		(attr
			(teardrop
				(type padvia)
			)
		)
		(connect_pads yes
			(clearance 0)
		)
		(min_thickness 0.0254)
		(filled_areas_thickness no)
		(fill yes
			(thermal_gap 0.5)
			(thermal_bridge_width 0.5)
			(island_removal_mode 1)
			(island_area_min 10)
		)
		(polygon
			(pts
				(xy 220.2725 125.359323) (xy 220.267764 125.331184) (xy 220.254615 125.310239) (xy 220.208158 125.287664)
				(xy 220.131044 125.292043) (xy 220.084681 125.308623) (xy 220.044927 125.333459) (xy 220.019691 125.360944)
				(xy 220.007903 125.392268) (xy 220.0075 125.399) (xy 220.21 125.399) (xy 220.0075 125.399) (xy 220.012082 125.410036)
				(xy 220.024541 125.408577) (xy 220.070632 125.378082) (xy 220.122991 125.343768) (xy 220.140711 125.342013)
				(xy 220.1475 125.359323)
			)
		)
	)
	(zone
		(net 45)
		(net_name "/2xUSB3.0+RJ45/USBSS_2.TX+")
		(layer "F.Cu")
		(name "$teardrop_padvia$")
		(hatch none 0.1)
		(priority 30298)
		(attr
			(teardrop
				(type padvia)
			)
		)
		(connect_pads yes
			(clearance 0)
		)
		(min_thickness 0.0254)
		(filled_areas_thickness no)
		(fill yes
			(thermal_gap 0.5)
			(thermal_bridge_width 0.5)
			(island_removal_mode 1)
			(island_area_min 10)
		)
		(polygon
			(pts
				(xy 181.8725 150.2) (xy 181.881903 150.373917) (xy 181.894286 150.608968) (xy 181.890781 150.748506)
				(xy 181.875 150.906314) (xy 182.025 151.136) (xy 182.104123 150.26) (xy 182.072384 150.255516) (xy 182.057527 150.244131)
				(xy 182.055915 150.212189) (xy 182.0575 150.2)
			)
		)
	)
	(zone
		(net 160)
		(net_name "/2xUSB3.0+RJ45/USBSS_2.RX-")
		(layer "F.Cu")
		(name "$teardrop_padvia$")
		(hatch none 0.1)
		(priority 30296)
		(attr
			(teardrop
				(type padvia)
			)
		)
		(connect_pads yes
			(clearance 0)
		)
		(min_thickness 0.0254)
		(filled_areas_thickness no)
		(fill yes
			(thermal_gap 0.5)
			(thermal_bridge_width 0.5)
			(island_removal_mode 1)
			(island_area_min 10)
		)
		(polygon
			(pts
				(xy 181.6775 157.62) (xy 181.668097 157.446083) (xy 181.655714 157.211032) (xy 181.659219 157.071494)
				(xy 181.675 156.913685) (xy 181.525 156.684) (xy 181.445877 157.56) (xy 181.477617 157.564484) (xy 181.492473 157.575869)
				(xy 181.494085 157.607811) (xy 181.4925 157.62)
			)
		)
	)
	(zone
		(net 686)
		(net_name "/2xSFP+/KR to SFI #1/SFI_R.RX-")
		(layer "F.Cu")
		(name "$teardrop_padvia$")
		(hatch none 0.1)
		(priority 31973)
		(attr
			(teardrop
				(type padvia)
			)
		)
		(connect_pads yes
			(clearance 0)
		)
		(min_thickness 0.0254)
		(filled_areas_thickness no)
		(fill yes
			(thermal_gap 0.5)
			(thermal_bridge_width 0.5)
			(island_removal_mode 1)
			(island_area_min 10)
		)
		(polygon
			(pts
				(xy 150.06 146.739321) (xy 150.117156 146.872485) (xy 150.133682 146.955296) (xy 150.13 147.043457)
				(xy 150.33 147.017) (xy 150.390044 146.786) (xy 150.313465 146.787721) (xy 150.262459 146.777296)
				(xy 150.23741 146.761991) (xy 150.220675 146.740569) (xy 150.22 146.739321)
			)
		)
	)
	(zone
		(net 738)
		(net_name "Net-(U43B-LS_OK_{IN_B})")
		(layer "F.Cu")
		(name "$teardrop_padvia$")
		(hatch none 0.1)
		(priority 30103)
		(attr
			(teardrop
				(type padvia)
			)
		)
		(connect_pads yes
			(clearance 0)
		)
		(min_thickness 0.0254)
		(filled_areas_thickness no)
		(fill yes
			(thermal_gap 0.5)
			(thermal_bridge_width 0.5)
			(island_removal_mode 1)
			(island_area_min 10)
		)
		(polygon
			(pts
				(xy 146.0125 130.227794) (xy 146.017315 130.145733) (xy 146.031019 130.080388) (xy 146.077576 129.98712)
				(xy 146.145787 129.908657) (xy 146.201942 129.847158) (xy 146.261801 129.768339) (xy 145.95 129.559)
				(xy 145.638199 129.768339) (xy 145.735219 129.888517) (xy 145.754214 129.908658) (xy 145.807366 129.967541)
				(xy 145.849591 130.031624) (xy 145.877449 130.114008) (xy 145.8875 130.227794)
			)
		)
	)
	(zone
		(net 313)
		(net_name "/2xUSB3.0+RJ45/USB_1.D+")
		(layer "F.Cu")
		(name "$teardrop_padvia$")
		(hatch none 0.1)
		(priority 31505)
		(attr
			(teardrop
				(type padvia)
			)
		)
		(connect_pads yes
			(clearance 0)
		)
		(min_thickness 0.0254)
		(filled_areas_thickness no)
		(fill yes
			(thermal_gap 0.5)
			(thermal_bridge_width 0.5)
			(island_removal_mode 1)
			(island_area_min 10)
		)
		(polygon
			(pts
				(xy 134.226793 116.235321) (xy 134.340111 116.116085) (xy 134.469205 115.986794) (xy 134.322665 115.821251)
				(xy 134.101281 115.817509) (xy 134.114466 115.899818) (xy 134.123636 115.927903) (xy 134.136992 115.971487)
				(xy 134.141836 116.014102) (xy 134.130666 116.057768) (xy 134.095978 116.104506)
			)
		)
	)
	(zone
		(net 668)
		(net_name "Net-(Y3-EN)")
		(layer "F.Cu")
		(name "$teardrop_padvia$")
		(hatch none 0.1)
		(priority 30962)
		(attr
			(teardrop
				(type padvia)
			)
		)
		(connect_pads yes
			(clearance 0)
		)
		(min_thickness 0.0254)
		(filled_areas_thickness no)
		(fill yes
			(thermal_gap 0.5)
			(thermal_bridge_width 0.5)
			(island_removal_mode 1)
			(island_area_min 10)
		)
		(polygon
			(pts
				(xy 124.4225 136.318) (xy 124.442469 136.255134) (xy 124.468921 136.223156) (xy 124.506332 136.194642)
				(xy 124.553527 136.172118) (xy 124.611167 136.156907) (xy 124.611798 136.156798) (xy 124.36 135.879)
				(xy 124.108202 136.156798) (xy 124.163635 136.171095) (xy 124.20952 136.192175) (xy 124.247201 136.21954)
				(xy 124.274434 136.250448) (xy 124.291472 136.283735) (xy 124.297489 136.316566) (xy 124.2975 136.318)
			)
		)
	)
	(zone
		(net 73)
		(net_name "+3V3_AON")
		(layer "F.Cu")
		(name "$teardrop_padvia$")
		(hatch none 0.1)
		(priority 30735)
		(attr
			(teardrop
				(type padvia)
			)
		)
		(connect_pads yes
			(clearance 0)
		)
		(min_thickness 0.0254)
		(filled_areas_thickness no)
		(fill yes
			(thermal_gap 0.5)
			(thermal_bridge_width 0.5)
			(island_removal_mode 1)
			(island_area_min 10)
		)
		(polygon
			(pts
				(xy 303.4145 106.77) (xy 303.409203 106.801401) (xy 303.392126 106.833656) (xy 303.365646 106.859863)
				(xy 303.327224 106.880921) (xy 303.28295 106.89295) (xy 303.475 107.411) (xy 303.66705 106.89295)
				(xy 303.623198 106.880629) (xy 303.589633 106.862077) (xy 303.548347 106.811289) (xy 303.5395 106.77)
			)
		)
	)
	(zone
		(net 209)
		(net_name "/Com Express 7 Interfaces/PCIe_{B1x4}.RX3-")
		(layer "F.Cu")
		(name "$teardrop_padvia$")
		(hatch none 0.1)
		(priority 31365)
		(attr
			(teardrop
				(type padvia)
			)
		)
		(connect_pads yes
			(clearance 0)
		)
		(min_thickness 0.0254)
		(filled_areas_thickness no)
		(fill yes
			(thermal_gap 0.5)
			(thermal_bridge_width 0.5)
			(island_removal_mode 1)
			(island_area_min 10)
		)
		(polygon
			(pts
				(xy 205.0705 161.767496) (xy 205.075235 161.72071) (xy 205.088379 161.685257) (xy 205.133387 161.63706)
				(xy 205.171608 161.612883) (xy 205.214774 161.585514) (xy 205.256731 161.548852) (xy 205.0935 161.399)
				(xy 204.872823 161.419859) (xy 204.877452 161.520536) (xy 204.874019 161.603908) (xy 204.873895 161.605963)
				(xy 204.8685 161.767496)
			)
		)
	)
	(zone
		(net 1)
		(net_name "GND")
		(layer "F.Cu")
		(name "$teardrop_padvia$")
		(hatch none 0.1)
		(priority 31798)
		(attr
			(teardrop
				(type padvia)
			)
		)
		(connect_pads yes
			(clearance 0)
		)
		(min_thickness 0.0254)
		(filled_areas_thickness no)
		(fill yes
			(thermal_gap 0.5)
			(thermal_bridge_width 0.5)
			(island_removal_mode 1)
			(island_area_min 10)
		)
		(polygon
			(pts
				(xy 253.728928 128.069248) (xy 253.659487 128.06443) (xy 253.608164 128.050708) (xy 253.532622 128.003994)
				(xy 253.520482 127.994449) (xy 253.453254 127.944667) (xy 253.327251 128.131748) (xy 253.453254 128.318829)
				(xy 253.52048 128.269047) (xy 253.603647 128.214642) (xy 253.656502 128.199558) (xy 253.728928 128.194248)
			)
		)
	)
	(zone
		(net 16)
		(net_name "/Com Express 7 Interfaces/PCIe_{B1x2}.RX0-")
		(layer "F.Cu")
		(name "$teardrop_padvia$")
		(hatch none 0.1)
		(priority 30239)
		(attr
			(teardrop
				(type padvia)
			)
		)
		(connect_pads yes
			(clearance 0)
		)
		(min_thickness 0.0254)
		(filled_areas_thickness no)
		(fill yes
			(thermal_gap 0.5)
			(thermal_bridge_width 0.5)
			(island_removal_mode 1)
			(island_area_min 10)
		)
		(polygon
			(pts
				(xy 203.5705 164.07) (xy 203.56742 164.055773) (xy 203.565252 164.025473) (xy 203.578123 164.014372)
				(xy 203.608295 164.01) (xy 203.525 163.134) (xy 203.375 163.382978) (xy 203.394356 163.624182) (xy 203.379599 163.896888)
				(xy 203.3685 164.07)
			)
		)
	)
	(zone
		(net 1)
		(net_name "GND")
		(layer "F.Cu")
		(name "$teardrop_padvia$")
		(hatch none 0.1)
		(priority 30310)
		(attr
			(teardrop
				(type padvia)
			)
		)
		(connect_pads yes
			(clearance 0)
		)
		(min_thickness 0.0254)
		(filled_areas_thickness no)
		(fill yes
			(thermal_gap 0.5)
			(thermal_bridge_width 0.5)
			(island_removal_mode 1)
			(island_area_min 10)
		)
		(polygon
			(pts
				(xy 259.164829 77.622) (xy 259.109974 77.61181) (xy 259.085257 77.593235) (xy 259.06522 77.560482)
				(xy 259.047914 77.458129) (xy 259.047761 77.442686) (xy 258.729708 77.605) (xy 258.75737 77.9) (xy 258.852385 77.877163)
				(xy 258.966444 77.885042) (xy 259.047079 77.902323) (xy 259.164829 77.922)
			)
		)
	)
	(zone
		(net 737)
		(net_name "Net-(U43B-LOSB)")
		(layer "F.Cu")
		(name "$teardrop_padvia$")
		(hatch none 0.1)
		(priority 30104)
		(attr
			(teardrop
				(type padvia)
			)
		)
		(connect_pads yes
			(clearance 0)
		)
		(min_thickness 0.0254)
		(filled_areas_thickness no)
		(fill yes
			(thermal_gap 0.5)
			(thermal_bridge_width 0.5)
			(island_removal_mode 1)
			(island_area_min 10)
		)
		(polygon
			(pts
				(xy 146.6625 129.377794) (xy 146.667315 129.295733) (xy 146.681019 129.230388) (xy 146.727576 129.13712)
				(xy 146.795787 129.058657) (xy 146.851942 128.997158) (xy 146.911801 128.918339) (xy 146.6 128.709)
				(xy 146.288199 128.918339) (xy 146.385219 129.038517) (xy 146.404214 129.058658) (xy 146.457366 129.117541)
				(xy 146.499591 129.181624) (xy 146.527449 129.264008) (xy 146.5375 129.377794)
			)
		)
	)
	(zone
		(net 204)
		(net_name "/Backplane/USB.D-")
		(layer "F.Cu")
		(name "$teardrop_padvia$")
		(hatch none 0.1)
		(priority 31483)
		(attr
			(teardrop
				(type padvia)
			)
		)
		(connect_pads yes
			(clearance 0)
		)
		(min_thickness 0.0254)
		(filled_areas_thickness no)
		(fill yes
			(thermal_gap 0.5)
			(thermal_bridge_width 0.5)
			(island_removal_mode 1)
			(island_area_min 10)
		)
		(polygon
			(pts
				(xy 197.9925 170.140416) (xy 197.98776 170.185027) (xy 197.974582 170.218424) (xy 197.929799 170.262019)
				(xy 197.88718 170.284851) (xy 197.839337 170.310508) (xy 197.793311 170.347104) (xy 197.9525 170.501)
				(xy 198.173177 170.487562) (xy 198.173316 170.304857) (xy 198.1775 170.140416)
			)
		)
	)
	(zone
		(net 215)
		(net_name "/Com Express 7 Interfaces/PCIe_{B1x4}.TX2-")
		(layer "F.Cu")
		(name "$teardrop_padvia$")
		(hatch none 0.1)
		(priority 30276)
		(attr
			(teardrop
				(type padvia)
			)
		)
		(connect_pads yes
			(clearance 0)
		)
		(min_thickness 0.0254)
		(filled_areas_thickness no)
		(fill yes
			(thermal_gap 0.5)
			(thermal_bridge_width 0.5)
			(island_removal_mode 1)
			(island_area_min 10)
		)
		(polygon
			(pts
				(xy 206.3685 167.75) (xy 206.379599 167.923112) (xy 206.394216 168.15051) (xy 206.391181 168.285138)
				(xy 206.375 168.437021) (xy 206.525 168.686) (xy 206.608295 167.81) (xy 206.577864 167.805523) (xy 206.565097 167.794185)
				(xy 206.56742 167.764227) (xy 206.5705 167.75)
			)
		)
	)
	(zone
		(net 1)
		(net_name "GND")
		(layer "F.Cu")
		(name "$teardrop_padvia$")
		(hatch none 0.1)
		(priority 30806)
		(attr
			(teardrop
				(type padvia)
			)
		)
		(connect_pads yes
			(clearance 0)
		)
		(min_thickness 0.0254)
		(filled_areas_thickness no)
		(fill yes
			(thermal_gap 0.5)
			(thermal_bridge_width 0.5)
			(island_removal_mode 1)
			(island_area_min 10)
		)
		(polygon
			(pts
				(xy 154.099323 80.7095) (xy 154.254912 80.716311) (xy 154.36676 80.743991) (xy 154.411954 80.762389)
				(xy 154.501 80.56) (xy 154.412488 80.357389) (xy 154.317068 80.391427) (xy 154.21624 80.406537)
				(xy 154.099323 80.4095)
			)
		)
	)
	(zone
		(net 1)
		(net_name "GND")
		(layer "F.Cu")
		(name "$teardrop_padvia$")
		(hatch none 0.1)
		(priority 31388)
		(attr
			(teardrop
				(type padvia)
			)
		)
		(connect_pads yes
			(clearance 0)
		)
		(min_thickness 0.0254)
		(filled_areas_thickness no)
		(fill yes
			(thermal_gap 0.5)
			(thermal_bridge_width 0.5)
			(island_removal_mode 1)
			(island_area_min 10)
		)
		(polygon
			(pts
				(xy 227.125 150.017082) (xy 227.119727 149.855177) (xy 227.120677 149.669078) (xy 226.9 149.649)
				(xy 226.737166 149.79925) (xy 226.80577 149.852892) (xy 226.823323 149.863273) (xy 226.862212 149.887497)
				(xy 226.894608 149.916765) (xy 226.91678 149.95774) (xy 226.925 150.017082)
			)
		)
	)
	(zone
		(net 1)
		(net_name "GND")
		(layer "F.Cu")
		(name "$teardrop_padvia$")
		(hatch none 0.1)
		(priority 31974)
		(attr
			(teardrop
				(type padvia)
			)
		)
		(connect_pads yes
			(clearance 0)
		)
		(min_thickness 0.0254)
		(filled_areas_thickness no)
		(fill yes
			(thermal_gap 0.5)
			(thermal_bridge_width 0.5)
			(island_removal_mode 1)
			(island_area_min 10)
		)
		(polygon
			(pts
				(xy 242.76 127.8925) (xy 242.784175 127.897488) (xy 242.805315 127.912403) (xy 242.837239 127.974163)
				(xy 242.85 128.085991) (xy 243.076 127.96) (xy 242.85 127.648058) (xy 242.845382 127.690884) (xy 242.83306 127.722983)
				(xy 242.793201 127.760192) (xy 242.76 127.7675)
			)
		)
	)
	(zone
		(net 526)
		(net_name "/Backplane/~{PRSNT}")
		(layer "F.Cu")
		(name "$teardrop_padvia$")
		(hatch none 0.1)
		(priority 30029)
		(attr
			(teardrop
				(type padvia)
			)
		)
		(connect_pads yes
			(clearance 0)
		)
		(min_thickness 0.0254)
		(filled_areas_thickness no)
		(fill yes
			(thermal_gap 0.5)
			(thermal_bridge_width 0.5)
			(island_removal_mode 1)
			(island_area_min 10)
		)
		(polygon
			(pts
				(xy 317.84 164.9725) (xy 317.902625 164.992823) (xy 317.933436 165.019267) (xy 317.960377 165.056912)
				(xy 317.990273 165.144727) (xy 319.451 164.91) (xy 317.990273 164.675273) (xy 317.976502 164.727739)
				(xy 317.956084 164.770431) (xy 317.929557 164.804843) (xy 317.89976 164.829005) (xy 317.84 164.8475)
			)
		)
	)
	(zone
		(net 492)
		(net_name "/2xSFP+/MOD1_ABS")
		(layer "F.Cu")
		(name "$teardrop_padvia$")
		(hatch none 0.1)
		(priority 31087)
		(attr
			(teardrop
				(type padvia)
			)
		)
		(connect_pads yes
			(clearance 0)
		)
		(min_thickness 0.0254)
		(filled_areas_thickness no)
		(fill yes
			(thermal_gap 0.5)
			(thermal_bridge_width 0.5)
			(island_removal_mode 1)
			(island_area_min 10)
		)
		(polygon
			(pts
				(xy 179.293 145.937499) (xy 179.233588 145.917726) (xy 179.177503 145.854452) (xy 179.155801 145.805827)
				(xy 179.141127 145.746467) (xy 179.139347 145.734499) (xy 178.879 145.999999) (xy 179.139347 146.265499)
				(xy 179.152197 146.20536) (xy 179.172131 146.155476) (xy 179.198056 146.115357) (xy 179.227876 146.086344)
				(xy 179.259294 146.068853) (xy 179.291105 146.06252) (xy 179.293 146.062499)
			)
		)
	)
	(zone
		(net 430)
		(net_name "/2xSFP+/MDIO0.MDC")
		(layer "F.Cu")
		(name "$teardrop_padvia$")
		(hatch none 0.1)
		(priority 31877)
		(attr
			(teardrop
				(type padvia)
			)
		)
		(connect_pads yes
			(clearance 0)
		)
		(min_thickness 0.0254)
		(filled_areas_thickness no)
		(fill yes
			(thermal_gap 0.5)
			(thermal_bridge_width 0.5)
			(island_removal_mode 1)
			(island_area_min 10)
		)
		(polygon
			(pts
				(xy 200.860873 154.027515) (xy 200.913382 153.981819) (xy 200.959376 153.955231) (xy 201.045824 153.934847)
				(xy 201.06116 153.933011) (xy 201.143895 153.920677) (xy 201.100707 153.699293) (xy 200.879323 153.656105)
				(xy 200.866988 153.738841) (xy 200.846651 153.836119) (xy 200.819943 153.884159) (xy 200.772485 153.939127)
			)
		)
	)
	(zone
		(net 129)
		(net_name "Net-(D17-C_{R})")
		(layer "F.Cu")
		(name "$teardrop_padvia$")
		(hatch none 0.1)
		(priority 31810)
		(attr
			(teardrop
				(type padvia)
			)
		)
		(connect_pads yes
			(clearance 0)
		)
		(min_thickness 0.0254)
		(filled_areas_thickness no)
		(fill yes
			(thermal_gap 0.5)
			(thermal_bridge_width 0.5)
			(island_removal_mode 1)
			(island_area_min 10)
		)
		(polygon
			(pts
				(xy 100.180677 78.7475) (xy 100.111236 78.742682) (xy 100.059913 78.72896) (xy 99.984371 78.682246)
				(xy 99.972231 78.672701) (xy 99.905003 78.622919) (xy 99.779 78.81) (xy 99.905003 78.997081) (xy 99.972229 78.947299)
				(xy 100.055396 78.892894) (xy 100.108251 78.87781) (xy 100.180677 78.8725)
			)
		)
	)
	(zone
		(net 365)
		(net_name "/Com Express 7 MGMT/PWR_OK")
		(layer "F.Cu")
		(name "$teardrop_padvia$")
		(hatch none 0.1)
		(priority 31702)
		(attr
			(teardrop
				(type padvia)
			)
		)
		(connect_pads yes
			(clearance 0)
		)
		(min_thickness 0.0254)
		(filled_areas_thickness no)
		(fill yes
			(thermal_gap 0.5)
			(thermal_bridge_width 0.5)
			(island_removal_mode 1)
			(island_area_min 10)
		)
		(polygon
			(pts
				(xy 185.8875 146.049323) (xy 185.882682 146.118763) (xy 185.86896 146.170087) (xy 185.822245 146.245628)
				(xy 185.812702 146.257768) (xy 185.762919 146.324997) (xy 185.95 146.451) (xy 186.137081 146.324997)
				(xy 186.087299 146.257769) (xy 186.032894 146.174603) (xy 186.01781 146.121748) (xy 186.0125 146.049323)
			)
		)
	)
	(zone
		(net 123)
		(net_name "/2xUSB3.0+RJ45/P1_D-")
		(layer "F.Cu")
		(name "$teardrop_padvia$")
		(hatch none 0.1)
		(priority 30445)
		(attr
			(teardrop
				(type padvia)
			)
		)
		(connect_pads yes
			(clearance 0)
		)
		(min_thickness 0.0254)
		(filled_areas_thickness no)
		(fill yes
			(thermal_gap 0.5)
			(thermal_bridge_width 0.5)
			(island_removal_mode 1)
			(island_area_min 10)
		)
		(polygon
			(pts
				(xy 129.280355 118.632) (xy 129.306964 118.650822) (xy 129.326829 118.677426) (xy 129.349132 118.758805)
				(xy 129.345 118.9455) (xy 129.641 118.85) (xy 129.676245 118.53) (xy 129.558093 118.535121) (xy 129.42295 118.506369)
				(xy 129.280355 118.447)
			)
		)
	)
	(zone
		(net 547)
		(net_name "/2xUSB3.0+RJ45/P1_ISET")
		(layer "F.Cu")
		(name "$teardrop_padvia$")
		(hatch none 0.1)
		(priority 30079)
		(attr
			(teardrop
				(type padvia)
			)
		)
		(connect_pads yes
			(clearance 0)
		)
		(min_thickness 0.0254)
		(filled_areas_thickness no)
		(fill yes
			(thermal_gap 0.5)
			(thermal_bridge_width 0.5)
			(island_removal_mode 1)
			(island_area_min 10)
		)
		(polygon
			(pts
				(xy 118.939 86.8015) (xy 118.883736 86.782104) (xy 118.834452 86.720761) (xy 118.802899 86.612049)
				(xy 118.799 86.549) (xy 118.198 86.864) (xy 118.799 87.179) (xy 118.803756 87.109663) (xy 118.817044 87.050293)
				(xy 118.837444 87.001557) (xy 118.863462 86.964336) (xy 118.891726 86.94052) (xy 118.922426 86.928176)
				(xy 118.939 86.9265)
			)
		)
	)
	(zone
		(net 628)
		(net_name "/PCIe redriver/TX_SW")
		(layer "F.Cu")
		(name "$teardrop_padvia$")
		(hatch none 0.1)
		(priority 31567)
		(attr
			(teardrop
				(type padvia)
			)
		)
		(connect_pads yes
			(clearance 0)
		)
		(min_thickness 0.0254)
		(filled_areas_thickness no)
		(fill yes
			(thermal_gap 0.5)
			(thermal_bridge_width 0.5)
			(island_removal_mode 1)
			(island_area_min 10)
		)
		(polygon
			(pts
				(xy 113.502852 143.9425) (xy 113.558625 143.947238) (xy 113.601063 143.960402) (xy 113.661145 144.005325)
				(xy 113.685331 144.032418) (xy 113.724059 144.074634) (xy 113.775997 144.117081) (xy 113.902 143.93)
				(xy 113.83677 143.717745) (xy 113.719123 143.766026) (xy 113.631494 143.802294) (xy 113.502852 143.8175)
			)
		)
	)
	(zone
		(net 374)
		(net_name "/2xUSB3.0+RJ45/USB_2.D-")
		(layer "F.Cu")
		(name "$teardrop_padvia$")
		(hatch none 0.1)
		(priority 31550)
		(attr
			(teardrop
				(type padvia)
			)
		)
		(connect_pads yes
			(clearance 0)
		)
		(min_thickness 0.0254)
		(filled_areas_thickness no)
		(fill yes
			(thermal_gap 0.5)
			(thermal_bridge_width 0.5)
			(island_removal_mode 1)
			(island_area_min 10)
		)
		(polygon
			(pts
				(xy 155.1845 122.657916) (xy 155.196099 122.851542) (xy 155.206323 123.001757) (xy 155.427 123.001)
				(xy 155.552003 122.812919) (xy 155.471979 122.77623) (xy 155.432393 122.760841) (xy 155.399785 122.740273)
				(xy 155.377654 122.708104) (xy 155.3695 122.657916)
			)
		)
	)
	(zone
		(net 871)
		(net_name "Net-(U22-SW)")
		(layer "F.Cu")
		(hatch edge 0.5)
		(priority 15)
		(connect_pads yes
			(clearance 0.15)
		)
		(min_thickness 0.25)
		(filled_areas_thickness no)
		(fill yes
			(thermal_gap 0.2)
			(thermal_bridge_width 0.5)
		)
		(polygon
			(pts
				(xy 312.225499 133.81) (xy 312.625499 133.81) (xy 312.625499 133.06) (xy 313.175499 132.51) (xy 313.175499 128.76)
				(xy 312.925499 128.51) (xy 311.925499 128.51) (xy 311.675499 128.76) (xy 311.675499 132.51) (xy 312.225499 133.06)
			)
		)
	)
	(zone
		(net 49)
		(net_name "/2xUSB3.0+RJ45/USBSS_2.TX-")
		(layer "F.Cu")
		(name "$teardrop_padvia$")
		(hatch none 0.1)
		(priority 31493)
		(attr
			(teardrop
				(type padvia)
			)
		)
		(connect_pads yes
			(clearance 0)
		)
		(min_thickness 0.0254)
		(filled_areas_thickness no)
		(fill yes
			(thermal_gap 0.5)
			(thermal_bridge_width 0.5)
			(island_removal_mode 1)
			(island_area_min 10)
		)
		(polygon
			(pts
				(xy 181.6775 149.934584) (xy 181.673316 149.770141) (xy 181.673177 149.587437) (xy 181.4525 149.574)
				(xy 181.293311 149.727895) (xy 181.360836 149.776773) (xy 181.387179 149.790148) (xy 181.427443 149.811523)
				(xy 181.461001 149.838232) (xy 181.483979 149.877007) (xy 181.4925 149.934584)
			)
		)
	)
	(zone
		(net 432)
		(net_name "/2xSFP+/10GKR_SFP0.RX+")
		(layer "F.Cu")
		(name "$teardrop_padvia$")
		(hatch none 0.1)
		(priority 30903)
		(attr
			(teardrop
				(type padvia)
			)
		)
		(connect_pads yes
			(clearance 0)
		)
		(min_thickness 0.0254)
		(filled_areas_thickness no)
		(fill yes
			(thermal_gap 0.5)
			(thermal_bridge_width 0.5)
			(island_removal_mode 1)
			(island_area_min 10)
		)
		(polygon
			(pts
				(xy 200.165 157.62) (xy 200.159583 157.602612) (xy 200.152109 157.574257) (xy 200.157669 157.564015)
				(xy 200.175 157.56) (xy 200.025 156.684) (xy 199.945877 157.56) (xy 199.979579 157.564497) (xy 199.997541 157.575975)
				(xy 200.005255 157.612548) (xy 200.005 157.62)
			)
		)
	)
	(zone
		(net 983)
		(net_name "Net-(D31-C)")
		(layer "F.Cu")
		(name "$teardrop_padvia$")
		(hatch none 0.1)
		(priority 30885)
		(attr
			(teardrop
				(type padvia)
			)
		)
		(connect_pads yes
			(clearance 0)
		)
		(min_thickness 0.0254)
		(filled_areas_thickness no)
		(fill yes
			(thermal_gap 0.5)
			(thermal_bridge_width 0.5)
			(island_removal_mode 1)
			(island_area_min 10)
		)
		(polygon
			(pts
				(xy 186.60861 76.259163) (xy 186.602838 76.2999) (xy 186.582434 76.341815) (xy 186.555259 76.370116)
				(xy 186.515713 76.393544) (xy 186.44311 76.412815) (xy 186.70861 76.673163) (xy 186.97411 76.412815)
				(xy 186.920968 76.400948) (xy 186.879929 76.382501) (xy 186.828228 76.331827) (xy 186.808892 76.268258)
				(xy 186.80861 76.259163)
			)
		)
	)
	(zone
		(net 296)
		(net_name "/2xUSB3.0+RJ45/GbE.CTREF")
		(layer "F.Cu")
		(name "$teardrop_padvia$")
		(hatch none 0.1)
		(priority 31259)
		(attr
			(teardrop
				(type padvia)
			)
		)
		(connect_pads yes
			(clearance 0)
		)
		(min_thickness 0.0254)
		(filled_areas_thickness no)
		(fill yes
			(thermal_gap 0.5)
			(thermal_bridge_width 0.5)
			(island_removal_mode 1)
			(island_area_min 10)
		)
		(polygon
			(pts
				(xy 135.6 119.800677) (xy 135.604713 119.722764) (xy 135.6177 119.66398) (xy 135.659802 119.572947)
				(xy 135.7025 119.487778) (xy 135.5 119.399) (xy 135.2975 119.487778) (xy 135.340198 119.572949)
				(xy 135.382867 119.665783) (xy 135.395444 119.723922) (xy 135.4 119.800677)
			)
		)
	)
	(zone
		(net 120)
		(net_name "/2xSFP+/KR to SFI #2/KR_C.TX+")
		(layer "F.Cu")
		(name "$teardrop_padvia$")
		(hatch none 0.1)
		(priority 31950)
		(attr
			(teardrop
				(type padvia)
			)
		)
		(connect_pads yes
			(clearance 0)
		)
		(min_thickness 0.0254)
		(filled_areas_thickness no)
		(fill yes
			(thermal_gap 0.5)
			(thermal_bridge_width 0.5)
			(island_removal_mode 1)
			(island_area_min 10)
		)
		(polygon
			(pts
				(xy 137.52 146.717279) (xy 137.508264 146.740315) (xy 137.485802 146.756014) (xy 137.409443 146.765137)
				(xy 137.351231 146.76) (xy 137.41 146.991) (xy 137.61 147.018536) (xy 137.614353 146.919743) (xy 137.655938 146.786651)
				(xy 137.68 146.717279)
			)
		)
	)
	(zone
		(net 490)
		(net_name "/2xSFP+/MDIO1.MDIO")
		(layer "F.Cu")
		(name "$teardrop_padvia$")
		(hatch none 0.1)
		(priority 31749)
		(attr
			(teardrop
				(type padvia)
			)
		)
		(connect_pads yes
			(clearance 0)
		)
		(min_thickness 0.0254)
		(filled_areas_thickness no)
		(fill yes
			(thermal_gap 0.5)
			(thermal_bridge_width 0.5)
			(island_removal_mode 1)
			(island_area_min 10)
		)
		(polygon
			(pts
				(xy 184.049323 146.1625) (xy 184.118764 146.167318) (xy 184.170088 146.18104) (xy 184.245629 146.227755)
				(xy 184.257769 146.237299) (xy 184.324997 146.287081) (xy 184.451 146.1) (xy 184.324997 145.912919)
				(xy 184.257768 145.962702) (xy 184.174602 146.017106) (xy 184.121748 146.03219) (xy 184.049323 146.0375)
			)
		)
	)
	(zone
		(net 1)
		(net_name "GND")
		(layer "F.Cu")
		(name "$teardrop_padvia$")
		(hatch none 0.1)
		(priority 31210)
		(attr
			(teardrop
				(type padvia)
			)
		)
		(connect_pads yes
			(clearance 0)
		)
		(min_thickness 0.0254)
		(filled_areas_thickness no)
		(fill yes
			(thermal_gap 0.5)
			(thermal_bridge_width 0.5)
			(island_removal_mode 1)
			(island_area_min 10)
		)
		(polygon
			(pts
				(xy 217.425 157.399323) (xy 217.42028 157.468646) (xy 217.407244 157.521549) (xy 217.355344 157.614135)
				(xy 217.303541 157.697636) (xy 217.5 157.801) (xy 217.707644 157.724641) (xy 217.675418 157.644142)
				(xy 217.639035 157.542683) (xy 217.625 157.399323)
			)
		)
	)
	(zone
		(net 357)
		(net_name "/Com Express 7 MGMT/SMBus.SCL")
		(layer "F.Cu")
		(name "$teardrop_padvia$")
		(hatch none 0.1)
		(priority 30664)
		(attr
			(teardrop
				(type padvia)
			)
		)
		(connect_pads yes
			(clearance 0)
		)
		(min_thickness 0.0254)
		(filled_areas_thickness no)
		(fill yes
			(thermal_gap 0.5)
			(thermal_bridge_width 0.5)
			(island_removal_mode 1)
			(island_area_min 10)
		)
		(polygon
			(pts
				(xy 182.0875 164.07) (xy 182.098438 164.031177) (xy 182.120195 164.016067) (xy 182.16 164.01) (xy 182.025 163.134)
				(xy 181.89 164.01) (xy 181.925281 164.014517) (xy 181.946797 164.026138) (xy 181.961995 164.058961)
				(xy 181.9625 164.07)
			)
		)
	)
	(zone
		(net 267)
		(net_name "/Com Express 7 Interfaces/PCIe_{B2Bx4}.TX0-")
		(layer "F.Cu")
		(name "$teardrop_padvia$")
		(hatch none 0.1)
		(priority 31355)
		(attr
			(teardrop
				(type padvia)
			)
		)
		(connect_pads yes
			(clearance 0)
		)
		(min_thickness 0.0254)
		(filled_areas_thickness no)
		(fill yes
			(thermal_gap 0.5)
			(thermal_bridge_width 0.5)
			(island_removal_mode 1)
			(island_area_min 10)
		)
		(polygon
			(pts
				(xy 191.517496 164.8045) (xy 191.47071 164.799765) (xy 191.435258 164.786621) (xy 191.38706 164.741613)
				(xy 191.362884 164.703392) (xy 191.335514 164.660225) (xy 191.298852 164.618268) (xy 191.149 164.7815)
				(xy 191.16986 165.002177) (xy 191.270531 164.997548) (xy 191.353897 165.00098) (xy 191.355964 165.001105)
				(xy 191.517496 165.0065)
			)
		)
	)
	(zone
		(net 400)
		(net_name "/Com Express 7 MGMT/FAN_PWM")
		(layer "F.Cu")
		(name "$teardrop_padvia$")
		(hatch none 0.1)
		(priority 30744)
		(attr
			(teardrop
				(type padvia)
			)
		)
		(connect_pads yes
			(clearance 0)
		)
		(min_thickness 0.0254)
		(filled_areas_thickness no)
		(fill yes
			(thermal_gap 0.5)
			(thermal_bridge_width 0.5)
			(island_removal_mode 1)
			(island_area_min 10)
		)
		(polygon
			(pts
				(xy 240.910708 77.2475) (xy 240.967159 77.267545) (xy 240.993969 77.293724) (xy 241.01676 77.330733)
				(xy 241.042643 77.4325) (xy 241.421708 77.185) (xy 241.042643 76.9375) (xy 241.032835 76.994825)
				(xy 241.015681 77.041504) (xy 240.992536 77.078054) (xy 240.965445 77.103695) (xy 240.910708 77.1225)
			)
		)
	)
	(zone
		(net 137)
		(net_name "/Com Express 7 MGMT/~{TYPE2}")
		(layer "F.Cu")
		(name "$teardrop_padvia$")
		(hatch none 0.1)
		(priority 31752)
		(attr
			(teardrop
				(type padvia)
			)
		)
		(connect_pads yes
			(clearance 0)
		)
		(min_thickness 0.0254)
		(filled_areas_thickness no)
		(fill yes
			(thermal_gap 0.5)
			(thermal_bridge_width 0.5)
			(island_removal_mode 1)
			(island_area_min 10)
		)
		(polygon
			(pts
				(xy 215.999323 143.5625) (xy 216.068764 143.567318) (xy 216.120088 143.58104) (xy 216.195629 143.627755)
				(xy 216.207769 143.637299) (xy 216.274997 143.687081) (xy 216.401 143.5) (xy 216.274997 143.312919)
				(xy 216.207768 143.362702) (xy 216.124602 143.417106) (xy 216.071748 143.43219) (xy 215.999323 143.4375)
			)
		)
	)
	(zone
		(net 1)
		(net_name "GND")
		(layer "F.Cu")
		(name "$teardrop_padvia$")
		(hatch none 0.1)
		(priority 30787)
		(attr
			(teardrop
				(type padvia)
			)
		)
		(connect_pads yes
			(clearance 0)
		)
		(min_thickness 0.0254)
		(filled_areas_thickness no)
		(fill yes
			(thermal_gap 0.5)
			(thermal_bridge_width 0.5)
			(island_removal_mode 1)
			(island_area_min 10)
		)
		(polygon
			(pts
				(xy 152.969177 80.4095) (xy 152.811606 80.402569) (xy 152.698078 80.374049) (xy 152.656278 80.357)
				(xy 152.5675 80.5595) (xy 152.656278 80.762) (xy 152.752317 80.727618) (xy 152.854189 80.7124) (xy 152.969177 80.7095)
			)
		)
	)
	(zone
		(net 951)
		(net_name "/2xSFP+/KR to SFI #2/BYP_TX-")
		(layer "F.Cu")
		(name "$teardrop_padvia$")
		(hatch none 0.1)
		(priority 31954)
		(attr
			(teardrop
				(type padvia)
			)
		)
		(connect_pads yes
			(clearance 0)
		)
		(min_thickness 0.0254)
		(filled_areas_thickness no)
		(fill yes
			(thermal_gap 0.5)
			(thermal_bridge_width 0.5)
			(island_removal_mode 1)
			(island_area_min 10)
		)
		(polygon
			(pts
				(xy 138.06 148.526893) (xy 138.072488 148.503919) (xy 138.095566 148.488424) (xy 138.17326 148.479871)
				(xy 138.229562 148.485) (xy 138.172 148.254) (xy 137.972 148.225449) (xy 137.967606 148.324729)
				(xy 137.923133 148.463503) (xy 137.9 148.526893)
			)
		)
	)
	(zone
		(net 41)
		(net_name "Net-(BT1-+)")
		(layer "F.Cu")
		(name "$teardrop_padvia$")
		(hatch none 0.1)
		(priority 30234)
		(attr
			(teardrop
				(type padvia)
			)
		)
		(connect_pads yes
			(clearance 0)
		)
		(min_thickness 0.0254)
		(filled_areas_thickness no)
		(fill yes
			(thermal_gap 0.5)
			(thermal_bridge_width 0.5)
			(island_removal_mode 1)
			(island_area_min 10)
		)
		(polygon
			(pts
				(xy 310.128684 74.570815) (xy 310.148503 74.590149) (xy 310.198744 74.641237) (xy 310.246192 74.705445)
				(xy 310.278919 74.787086) (xy 310.285 74.890474) (xy 310.580707 74.810707) (xy 310.635474 74.49)
				(xy 310.581746 74.49506) (xy 310.534293 74.490542) (xy 310.450797 74.457112) (xy 310.37403 74.39289)
				(xy 310.358342 74.376694) (xy 310.340815 74.358684)
			)
		)
	)
	(zone
		(net 586)
		(net_name "Net-(U22-FB)")
		(layer "F.Cu")
		(name "$teardrop_padvia$")
		(hatch none 0.1)
		(priority 31093)
		(attr
			(teardrop
				(type padvia)
			)
		)
		(connect_pads yes
			(clearance 0)
		)
		(min_thickness 0.0254)
		(filled_areas_thickness no)
		(fill yes
			(thermal_gap 0.5)
			(thermal_bridge_width 0.5)
			(island_removal_mode 1)
			(island_area_min 10)
		)
		(polygon
			(pts
				(xy 313.012999 135.567) (xy 312.993226 135.626412) (xy 312.929952 135.682496) (xy 312.881327 135.704198)
				(xy 312.821968 135.718872) (xy 312.809999 135.720652) (xy 313.075499 135.981) (xy 313.340999 135.720652)
				(xy 313.280861 135.707803) (xy 313.230977 135.687869) (xy 313.190857 135.661944) (xy 313.161844 135.632124)
				(xy 313.144353 135.600706) (xy 313.13802 135.568895) (xy 313.137999 135.567)
			)
		)
	)
	(zone
		(net 2)
		(net_name "+3V3")
		(layer "F.Cu")
		(name "$teardrop_padvia$")
		(hatch none 0.1)
		(priority 30757)
		(attr
			(teardrop
				(type padvia)
			)
		)
		(connect_pads yes
			(clearance 0)
		)
		(min_thickness 0.0254)
		(filled_areas_thickness no)
		(fill yes
			(thermal_gap 0.5)
			(thermal_bridge_width 0.5)
			(island_removal_mode 1)
			(island_area_min 10)
		)
		(polygon
			(pts
				(xy 146.679823 71.958499) (xy 146.8374 71.965431) (xy 146.950934 71.993955) (xy 146.992722 72.010999)
				(xy 147.0815 71.808499) (xy 146.992722 71.605999) (xy 146.896677 71.640382) (xy 146.794796 71.6556)
				(xy 146.679823 71.658499)
			)
		)
	)
	(zone
		(net 552)
		(net_name "Net-(R17-Pad2)")
		(layer "F.Cu")
		(name "$teardrop_padvia$")
		(hatch none 0.1)
		(priority 30431)
		(attr
			(teardrop
				(type padvia)
			)
		)
		(connect_pads yes
			(clearance 0)
		)
		(min_thickness 0.0254)
		(filled_areas_thickness no)
		(fill yes
			(thermal_gap 0.5)
			(thermal_bridge_width 0.5)
			(island_removal_mode 1)
			(island_area_min 10)
		)
		(polygon
			(pts
				(xy 135.42 101.745) (xy 135.370167 101.73574) (xy 135.346156 101.719372) (xy 135.326648 101.690919)
				(xy 135.312274 101.62) (xy 134.844 101.845) (xy 135.312274 102.07) (xy 135.318547 102.02239) (xy 135.332162 101.988567)
				(xy 135.372122 101.953408) (xy 135.42 101.945)
			)
		)
	)
	(zone
		(net 6)
		(net_name "/M.2 key E/~{LED_2}")
		(layer "F.Cu")
		(name "$teardrop_padvia$")
		(hatch none 0.1)
		(priority 30853)
		(attr
			(teardrop
				(type padvia)
			)
		)
		(connect_pads yes
			(clearance 0)
		)
		(min_thickness 0.0254)
		(filled_areas_thickness no)
		(fill yes
			(thermal_gap 0.5)
			(thermal_bridge_width 0.5)
			(island_removal_mode 1)
			(island_area_min 10)
		)
		(polygon
			(pts
				(xy 145.2405 74.872) (xy 145.279323 74.882938) (xy 145.294433 74.904695) (xy 145.3005 74.9445) (xy 146.0765 74.8095)
				(xy 145.3005 74.6745) (xy 145.295983 74.709781) (xy 145.284362 74.731297) (xy 145.251539 74.746495)
				(xy 145.2405 74.747)
			)
		)
	)
	(zone
		(net 558)
		(net_name "Net-(U5-SDA)")
		(layer "F.Cu")
		(name "$teardrop_padvia$")
		(hatch none 0.1)
		(priority 32017)
		(attr
			(teardrop
				(type padvia)
			)
		)
		(connect_pads yes
			(clearance 0)
		)
		(min_thickness 0.0254)
		(filled_areas_thickness no)
		(fill yes
			(thermal_gap 0.5)
			(thermal_bridge_width 0.5)
			(island_removal_mode 1)
			(island_area_min 10)
		)
		(polygon
			(pts
				(xy 159.9855 158.2095) (xy 159.985596 158.215822) (xy 159.980011 158.255325) (xy 159.965078 158.273547)
				(xy 159.9355 158.286495) (xy 160.048 158.673) (xy 160.1605 158.286495) (xy 160.133507 158.275379)
				(xy 160.118405 158.259852) (xy 160.110404 158.215822) (xy 160.1105 158.2095)
			)
		)
	)
	(zone
		(net 239)
		(net_name "/Com Express 7 Interfaces/PCIe_{B2Bx4}.RX3+")
		(layer "F.Cu")
		(name "$teardrop_padvia$")
		(hatch none 0.1)
		(priority 31415)
		(attr
			(teardrop
				(type padvia)
			)
		)
		(connect_pads yes
			(clearance 0)
		)
		(min_thickness 0.0254)
		(filled_areas_thickness no)
		(fill yes
			(thermal_gap 0.5)
			(thermal_bridge_width 0.5)
			(island_removal_mode 1)
			(island_area_min 10)
		)
		(polygon
			(pts
				(xy 190.832504 159.5065) (xy 190.994035 159.501105) (xy 191.078445 159.497554) (xy 191.18014 159.502177)
				(xy 191.201 159.2815) (xy 191.051147 159.118268) (xy 190.997007 159.186935) (xy 190.987115 159.203393)
				(xy 190.962615 159.242065) (xy 190.933109 159.274279) (xy 190.891953 159.296327) (xy 190.832504 159.3045)
			)
		)
	)
	(zone
		(net 1)
		(net_name "GND")
		(layer "F.Cu")
		(name "$teardrop_padvia$")
		(hatch none 0.1)
		(priority 31682)
		(attr
			(teardrop
				(type padvia)
			)
		)
		(connect_pads yes
			(clearance 0)
		)
		(min_thickness 0.0254)
		(filled_areas_thickness no)
		(fill yes
			(thermal_gap 0.5)
			(thermal_bridge_width 0.5)
			(island_removal_mode 1)
			(island_area_min 10)
		)
		(polygon
			(pts
				(xy 307.4555 82.832) (xy 307.449978 82.859072) (xy 307.431322 82.884611) (xy 307.404703 82.90078)
				(xy 307.365962 82.910399) (xy 307.338 82.912) (xy 307.518 83.288) (xy 307.698 82.912) (xy 307.6525 82.907387)
				(xy 307.619532 82.8951) (xy 307.585156 82.856945) (xy 307.5805 82.832)
			)
		)
	)
	(zone
		(net 84)
		(net_name "/Com Express 7 MGMT/PWRBTN")
		(layer "F.Cu")
		(name "$teardrop_padvia$")
		(hatch none 0.1)
		(priority 30207)
		(attr
			(teardrop
				(type padvia)
			)
		)
		(connect_pads yes
			(clearance 0)
		)
		(min_thickness 0.0254)
		(filled_areas_thickness no)
		(fill yes
			(thermal_gap 0.5)
			(thermal_bridge_width 0.5)
			(island_removal_mode 1)
			(island_area_min 10)
		)
		(polygon
			(pts
				(xy 239.4215 129.21) (xy 239.441221 129.15274) (xy 239.504033 129.100216) (xy 239.552653 129.080449)
				(xy 239.611951 129.067923) (xy 239.629 129.066072) (xy 239.359 128.589) (xy 239.089 129.066072)
				(xy 239.150244 129.076248) (xy 239.201171 129.093925) (xy 239.242014 129.117823) (xy 239.271697 129.146022)
				(xy 239.28963 129.176012) (xy 239.296441 129.206862) (xy 239.2965 129.21)
			)
		)
	)
	(zone
		(net 889)
		(net_name "/Power/PG_{3V3}")
		(layer "F.Cu")
		(name "$teardrop_padvia$")
		(hatch none 0.1)
		(priority 31790)
		(attr
			(teardrop
				(type padvia)
			)
		)
		(connect_pads yes
			(clearance 0)
		)
		(min_thickness 0.0254)
		(filled_areas_thickness no)
		(fill yes
			(thermal_gap 0.5)
			(thermal_bridge_width 0.5)
			(island_removal_mode 1)
			(island_area_min 10)
		)
		(polygon
			(pts
				(xy 311.327499 103.250677) (xy 311.332317 103.181236) (xy 311.346039 103.129912) (xy 311.392754 103.05437)
				(xy 311.402298 103.042229) (xy 311.45208 102.975003) (xy 311.264999 102.849) (xy 311.077918 102.975003)
				(xy 311.1277 103.042231) (xy 311.182105 103.125397) (xy 311.197189 103.178251) (xy 311.202499 103.250677)
			)
		)
	)
	(zone
		(net 628)
		(net_name "/PCIe redriver/TX_SW")
		(layer "F.Cu")
		(name "$teardrop_padvia$")
		(hatch none 0.1)
		(priority 31578)
		(attr
			(teardrop
				(type padvia)
			)
		)
		(connect_pads yes
			(clearance 0)
		)
		(min_thickness 0.0254)
		(filled_areas_thickness no)
		(fill yes
			(thermal_gap 0.5)
			(thermal_bridge_width 0.5)
			(island_removal_mode 1)
			(island_area_min 10)
		)
		(polygon
			(pts
				(xy 114.299148 143.8175) (xy 114.222005 143.812856) (xy 114.163898 143.800345) (xy 114.082876 143.766026)
				(xy 113.965229 143.717745) (xy 113.9 143.93) (xy 114.026003 144.117081) (xy 114.101925 144.049275)
				(xy 114.116668 144.032418) (xy 114.184757 143.968892) (xy 114.232532 143.949587) (xy 114.299148 143.9425)
			)
		)
	)
	(zone
		(net 1)
		(net_name "GND")
		(layer "F.Cu")
		(name "$teardrop_padvia$")
		(hatch none 0.1)
		(priority 30533)
		(attr
			(teardrop
				(type padvia)
			)
		)
		(connect_pads yes
			(clearance 0)
		)
		(min_thickness 0.0254)
		(filled_areas_thickness no)
		(fill yes
			(thermal_gap 0.5)
			(thermal_bridge_width 0.5)
			(island_removal_mode 1)
			(island_area_min 10)
		)
		(polygon
			(pts
				(xy 216.925 162.2) (xy 216.928333 162.214486) (xy 216.93119 162.24461) (xy 216.919036 162.255651)
				(xy 216.89 162.26) (xy 217.025 163.136) (xy 217.16 162.26) (xy 217.130666 162.255525) (xy 217.118642 162.244199)
				(xy 217.121667 162.214486) (xy 217.125 162.2)
			)
		)
	)
	(zone
		(net 249)
		(net_name "/Com Express 7 Interfaces/PCIe_{B2Bx4}.TX2+")
		(layer "F.Cu")
		(name "$teardrop_padvia$")
		(hatch none 0.1)
		(priority 31396)
		(attr
			(teardrop
				(type padvia)
			)
		)
		(connect_pads yes
			(clearance 0)
		)
		(min_thickness 0.0254)
		(filled_areas_thickness no)
		(fill yes
			(thermal_gap 0.5)
			(thermal_bridge_width 0.5)
			(island_removal_mode 1)
			(island_area_min 10)
		)
		(polygon
			(pts
				(xy 188.1815 167.367496) (xy 188.176105 167.205964) (xy 188.172555 167.121553) (xy 188.177177 167.019859)
				(xy 187.9565 166.999) (xy 187.793268 167.148852) (xy 187.861936 167.202992) (xy 187.878392 167.212884)
				(xy 187.917064 167.237384) (xy 187.949279 167.26689) (xy 187.971327 167.308046) (xy 187.9795 167.367496)
			)
		)
	)
	(zone
		(net 1)
		(net_name "GND")
		(layer "F.Cu")
		(name "$teardrop_padvia$")
		(hatch none 0.1)
		(priority 31311)
		(attr
			(teardrop
				(type padvia)
			)
		)
		(connect_pads yes
			(clearance 0)
		)
		(min_thickness 0.0254)
		(filled_areas_thickness no)
		(fill yes
			(thermal_gap 0.5)
			(thermal_bridge_width 0.5)
			(island_removal_mode 1)
			(island_area_min 10)
		)
		(polygon
			(pts
				(xy 185.925 151.826852) (xy 185.920254 151.889648) (xy 185.907029 151.937423) (xy 185.861545 152.00848)
				(xy 185.845539 152.027013) (xy 185.787919 152.099997) (xy 185.975 152.226) (xy 186.187254 152.16077)
				(xy 186.16758 152.098309) (xy 186.136007 151.982972) (xy 186.125 151.826852)
			)
		)
	)
	(zone
		(net 748)
		(net_name "Net-(U45C-AMUXA)")
		(layer "F.Cu")
		(name "$teardrop_padvia$")
		(hatch none 0.1)
		(priority 30131)
		(attr
			(teardrop
				(type padvia)
			)
		)
		(connect_pads yes
			(clearance 0)
		)
		(min_thickness 0.0254)
		(filled_areas_thickness no)
		(fill yes
			(thermal_gap 0.5)
			(thermal_bridge_width 0.5)
			(island_removal_mode 1)
			(island_area_min 10)
		)
		(polygon
			(pts
				(xy 129.8025 129.377794) (xy 129.807315 129.295733) (xy 129.821019 129.230388) (xy 129.867576 129.13712)
				(xy 129.935787 129.058657) (xy 129.991942 128.997158) (xy 130.051801 128.918339) (xy 129.74 128.709)
				(xy 129.428199 128.918339) (xy 129.525219 129.038517) (xy 129.544214 129.058658) (xy 129.597366 129.117541)
				(xy 129.639591 129.181624) (xy 129.667449 129.264008) (xy 129.6775 129.377794)
			)
		)
	)
	(zone
		(net 210)
		(net_name "/Com Express 7 Interfaces/PCIe_{B1x4}.RX3+")
		(layer "F.Cu")
		(name "$teardrop_padvia$")
		(hatch none 0.1)
		(priority 30256)
		(attr
			(teardrop
				(type padvia)
			)
		)
		(connect_pads yes
			(clearance 0)
		)
		(min_thickness 0.0254)
		(filled_areas_thickness no)
		(fill yes
			(thermal_gap 0.5)
			(thermal_bridge_width 0.5)
			(island_removal_mode 1)
			(island_area_min 10)
		)
		(polygon
			(pts
				(xy 204.4795 162.2) (xy 204.48258 162.214227) (xy 204.484749 162.244527) (xy 204.471877 162.255628)
				(xy 204.441705 162.26) (xy 204.525 163.136) (xy 204.675 162.887021) (xy 204.655644 162.645818) (xy 204.670401 162.373112)
				(xy 204.6815 162.2)
			)
		)
	)
	(zone
		(net 62)
		(net_name "+12V_AON")
		(layer "F.Cu")
		(hatch edge 0.5)
		(priority 1)
		(connect_pads yes
			(clearance 0.15)
		)
		(min_thickness 0.25)
		(filled_areas_thickness no)
		(fill yes
			(thermal_gap 0.2)
			(thermal_bridge_width 0.5)
			(smoothing fillet)
			(radius 0.2)
		)
		(polygon
			(pts
				(xy 318.75 110.55) (xy 314.984999 110.55) (xy 314.984999 105.63) (xy 314.464999 105.11) (xy 313.794999 105.11)
				(xy 313.604999 105.3) (xy 313.544998 105.3) (xy 313.544999 103.31) (xy 318.75 103.309999)
			)
		)
	)
	(zone
		(net 1)
		(net_name "GND")
		(layer "F.Cu")
		(name "$teardrop_padvia$")
		(hatch none 0.1)
		(priority 30754)
		(attr
			(teardrop
				(type padvia)
			)
		)
		(connect_pads yes
			(clearance 0)
		)
		(min_thickness 0.0254)
		(filled_areas_thickness no)
		(fill yes
			(thermal_gap 0.5)
			(thermal_bridge_width 0.5)
			(island_removal_mode 1)
			(island_area_min 10)
		)
		(polygon
			(pts
				(xy 309.774323 82.47) (xy 309.9319 82.476932) (xy 310.045434 82.505456) (xy 310.087222 82.5225)
				(xy 310.176 82.32) (xy 310.087222 82.1175) (xy 309.991177 82.151883) (xy 309.889296 82.167101) (xy 309.774323 82.17)
			)
		)
	)
	(zone
		(net 489)
		(net_name "Net-(J12K-10G_SDP1)")
		(layer "F.Cu")
		(name "$teardrop_padvia$")
		(hatch none 0.1)
		(priority 31882)
		(attr
			(teardrop
				(type padvia)
			)
		)
		(connect_pads yes
			(clearance 0)
		)
		(min_thickness 0.0254)
		(filled_areas_thickness no)
		(fill yes
			(thermal_gap 0.5)
			(thermal_bridge_width 0.5)
			(island_removal_mode 1)
			(island_area_min 10)
		)
		(polygon
			(pts
				(xy 195.327515 149.739127) (xy 195.281819 149.686618) (xy 195.255231 149.640623) (xy 195.234847 149.554175)
				(xy 195.233011 149.53884) (xy 195.220677 149.456105) (xy 194.999293 149.499293) (xy 194.956105 149.720677)
				(xy 195.03884 149.733011) (xy 195.136119 149.753349) (xy 195.184159 149.780057) (xy 195.239127 149.827515)
			)
		)
	)
	(zone
		(net 329)
		(net_name "/Com Express 7 Interfaces/PCIe_{B2Ax4}.TX2-")
		(layer "F.Cu")
		(name "$teardrop_padvia$")
		(hatch none 0.1)
		(priority 30520)
		(attr
			(teardrop
				(type padvia)
			)
		)
		(connect_pads yes
			(clearance 0)
		)
		(min_thickness 0.0254)
		(filled_areas_thickness no)
		(fill yes
			(thermal_gap 0.5)
			(thermal_bridge_width 0.5)
			(island_removal_mode 1)
			(island_area_min 10)
		)
		(polygon
			(pts
				(xy 214.424 167.75) (xy 214.427537 167.764678) (xy 214.430808 167.794685) (xy 214.418857 167.805673)
				(xy 214.39 167.81) (xy 214.525 168.686) (xy 214.66 167.81) (xy 214.630796 167.805525) (xy 214.619003 167.794203)
				(xy 214.622463 167.764678) (xy 214.626 167.75)
			)
		)
	)
	(zone
		(net 752)
		(net_name "Net-(U45C-CLKOUTB+)")
		(layer "F.Cu")
		(name "$teardrop_padvia$")
		(hatch none 0.1)
		(priority 31468)
		(attr
			(teardrop
				(type padvia)
			)
		)
		(connect_pads yes
			(clearance 0)
		)
		(min_thickness 0.0254)
		(filled_areas_thickness no)
		(fill yes
			(thermal_gap 0.5)
			(thermal_bridge_width 0.5)
			(island_removal_mode 1)
			(island_area_min 10)
		)
		(polygon
			(pts
				(xy 138.560607 139.501005) (xy 138.506866 139.547948) (xy 138.459353 139.576167) (xy 138.372203 139.598018)
				(xy 138.341545 139.601163) (xy 138.241227 139.614804) (xy 138.289293 139.860707) (xy 138.535196 139.908773)
				(xy 138.548837 139.808455) (xy 138.568924 139.702345) (xy 138.597485 139.649517) (xy 138.648995 139.589393)
			)
		)
	)
	(zone
		(net 490)
		(net_name "/2xSFP+/MDIO1.MDIO")
		(layer "F.Cu")
		(name "$teardrop_padvia$")
		(hatch none 0.1)
		(priority 31801)
		(attr
			(teardrop
				(type padvia)
			)
		)
		(connect_pads yes
			(clearance 0)
		)
		(min_thickness 0.0254)
		(filled_areas_thickness no)
		(fill yes
			(thermal_gap 0.5)
			(thermal_bridge_width 0.5)
			(island_removal_mode 1)
			(island_area_min 10)
		)
		(polygon
			(pts
				(xy 173.900677 139.6375) (xy 173.831236 139.632682) (xy 173.779913 139.61896) (xy 173.704371 139.572246)
				(xy 173.692231 139.562701) (xy 173.625003 139.512919) (xy 173.499 139.7) (xy 173.625003 139.887081)
				(xy 173.692229 139.837299) (xy 173.775396 139.782894) (xy 173.828251 139.76781) (xy 173.900677 139.7625)
			)
		)
	)
	(zone
		(net 619)
		(net_name "/PCIe misc/DIF4+")
		(layer "F.Cu")
		(name "$teardrop_padvia$")
		(hatch none 0.1)
		(priority 30421)
		(attr
			(teardrop
				(type padvia)
			)
		)
		(connect_pads yes
			(clearance 0)
		)
		(min_thickness 0.0254)
		(filled_areas_thickness no)
		(fill yes
			(thermal_gap 0.5)
			(thermal_bridge_width 0.5)
			(island_removal_mode 1)
			(island_area_min 10)
		)
		(polygon
			(pts
				(xy 220.314479 130.4455) (xy 220.342061 130.468758) (xy 220.362724 130.499997) (xy 220.385599 130.591916)
				(xy 220.385 130.748914) (xy 220.681 130.65) (xy 220.711754 130.33) (xy 220.596623 130.339439) (xy 220.468284 130.314667)
				(xy 220.336719 130.256792) (xy 220.314479 130.2435)
			)
		)
	)
	(zone
		(net 538)
		(net_name "Net-(Q5-D)")
		(layer "F.Cu")
		(name "$teardrop_padvia$")
		(hatch none 0.1)
		(priority 30204)
		(attr
			(teardrop
				(type padvia)
			)
		)
		(connect_pads yes
			(clearance 0)
		)
		(min_thickness 0.0254)
		(filled_areas_thickness no)
		(fill yes
			(thermal_gap 0.5)
			(thermal_bridge_width 0.5)
			(island_removal_mode 1)
			(island_area_min 10)
		)
		(polygon
			(pts
				(xy 265.562 91.93) (xy 265.581721 91.87274) (xy 265.644533 91.820216) (xy 265.693153 91.800449)
				(xy 265.752451 91.787923) (xy 265.7695 91.786072) (xy 265.4995 91.309) (xy 265.2295 91.786072) (xy 265.290744 91.796248)
				(xy 265.341671 91.813925) (xy 265.382514 91.837823) (xy 265.412197 91.866022) (xy 265.43013 91.896012)
				(xy 265.436941 91.926862) (xy 265.437 91.93)
			)
		)
	)
	(zone
		(net 562)
		(net_name "/2xSFP+/~{LED0_0}")
		(layer "F.Cu")
		(name "$teardrop_padvia$")
		(hatch none 0.1)
		(priority 32013)
		(attr
			(teardrop
				(type padvia)
			)
		)
		(connect_pads yes
			(clearance 0)
		)
		(min_thickness 0.0254)
		(filled_areas_thickness no)
		(fill yes
			(thermal_gap 0.5)
			(thermal_bridge_width 0.5)
			(island_removal_mode 1)
			(island_area_min 10)
		)
		(polygon
			(pts
				(xy 156.8995 159.4225) (xy 156.905822 159.422404) (xy 156.945325 159.427989) (xy 156.963547 159.442922)
				(xy 156.976495 159.4725) (xy 157.363 159.36) (xy 156.976495 159.2475) (xy 156.965379 159.274493)
				(xy 156.949852 159.289595) (xy 156.905822 159.297596) (xy 156.8995 159.2975)
			)
		)
	)
	(zone
		(net 2)
		(net_name "+3V3")
		(layer "F.Cu")
		(name "$teardrop_padvia$")
		(hatch none 0.1)
		(priority 30911)
		(attr
			(teardrop
				(type padvia)
			)
		)
		(connect_pads yes
			(clearance 0)
		)
		(min_thickness 0.0254)
		(filled_areas_thickness no)
		(fill yes
			(thermal_gap 0.5)
			(thermal_bridge_width 0.5)
			(island_removal_mode 1)
			(island_area_min 10)
		)
		(polygon
			(pts
				(xy 231.600139 78.273) (xy 231.480953 78.289591) (xy 231.387862 78.329867) (xy 231.326277 78.358545)
				(xy 231.255079 78.374323) (xy 231.269707 78.595) (xy 231.457788 78.720003) (xy 231.484112 78.668039)
				(xy 231.521975 78.602381) (xy 231.553432 78.581048) (xy 231.600139 78.573)
			)
		)
	)
	(zone
		(net 218)
		(net_name "/Com Express 7 Interfaces/PCIe_{B1x4}.RX1+")
		(layer "F.Cu")
		(name "$teardrop_padvia$")
		(hatch none 0.1)
		(priority 30507)
		(attr
			(teardrop
				(type padvia)
			)
		)
		(connect_pads yes
			(clearance 0)
		)
		(min_thickness 0.0254)
		(filled_areas_thickness no)
		(fill yes
			(thermal_gap 0.5)
			(thermal_bridge_width 0.5)
			(island_removal_mode 1)
			(island_area_min 10)
		)
		(polygon
			(pts
				(xy 207.424 162.2) (xy 207.427537 162.214678) (xy 207.430808 162.244685) (xy 207.418857 162.255673)
				(xy 207.39 162.26) (xy 207.525 163.136) (xy 207.66 162.26) (xy 207.630796 162.255525) (xy 207.619003 162.244203)
				(xy 207.622463 162.214678) (xy 207.626 162.2)
			)
		)
	)
	(zone
		(net 1)
		(net_name "GND")
		(layer "F.Cu")
		(name "$teardrop_padvia$")
		(hatch none 0.1)
		(priority 31187)
		(attr
			(teardrop
				(type padvia)
			)
		)
		(connect_pads yes
			(clearance 0)
		)
		(min_thickness 0.0254)
		(filled_areas_thickness no)
		(fill yes
			(thermal_gap 0.5)
			(thermal_bridge_width 0.5)
			(island_removal_mode 1)
			(island_area_min 10)
		)
		(polygon
			(pts
				(xy 196.125 155.825677) (xy 196.12972 155.756353) (xy 196.142756 155.703449) (xy 196.194658 155.61086)
				(xy 196.246458 155.527363) (xy 196.05 155.424) (xy 195.842355 155.500358) (xy 195.874583 155.580861)
				(xy 195.910965 155.682318) (xy 195.925 155.825677)
			)
		)
	)
	(zone
		(net 374)
		(net_name "/2xUSB3.0+RJ45/USB_2.D-")
		(layer "F.Cu")
		(name "$teardrop_padvia$")
		(hatch none 0.1)
		(priority 31541)
		(attr
			(teardrop
				(type padvia)
			)
		)
		(connect_pads yes
			(clearance 0)
		)
		(min_thickness 0.0254)
		(filled_areas_thickness no)
		(fill yes
			(thermal_gap 0.5)
			(thermal_bridge_width 0.5)
			(island_removal_mode 1)
			(island_area_min 10)
		)
		(polygon
			(pts
				(xy 152.735637 115.254506) (xy 152.710157 115.222309) (xy 152.69865 115.192065) (xy 152.70478 115.135185)
				(xy 152.720898 115.095455) (xy 152.748719 115.015853) (xy 152.527335 114.971251) (xy 152.373236 115.129236)
				(xy 152.477993 115.245058) (xy 152.604822 115.385321)
			)
		)
	)
	(zone
		(net 122)
		(net_name "/2xSFP+/KR to SFI #2/KR_C.TX-")
		(layer "F.Cu")
		(name "$teardrop_padvia$")
		(hatch none 0.1)
		(priority 31969)
		(attr
			(teardrop
				(type padvia)
			)
		)
		(connect_pads yes
			(clearance 0)
		)
		(min_thickness 0.0254)
		(filled_areas_thickness no)
		(fill yes
			(thermal_gap 0.5)
			(thermal_bridge_width 0.5)
			(island_removal_mode 1)
			(island_area_min 10)
		)
		(polygon
			(pts
				(xy 137.9 146.717279) (xy 137.924062 146.786651) (xy 137.960577 146.896598) (xy 137.970888 146.956686)
				(xy 137.97 147.018536) (xy 138.17 146.991) (xy 138.228769 146.76) (xy 138.147423 146.765298) (xy 138.095406 146.756508)
				(xy 138.073886 146.742657) (xy 138.061647 146.722599) (xy 138.06 146.717279)
			)
		)
	)
	(zone
		(net 326)
		(net_name "/Com Express 7 Interfaces/PCIe_{B2Ax4}.TX1+")
		(layer "F.Cu")
		(name "$teardrop_padvia$")
		(hatch none 0.1)
		(priority 31596)
		(attr
			(teardrop
				(type padvia)
			)
		)
		(connect_pads yes
			(clearance 0)
		)
		(min_thickness 0.0254)
		(filled_areas_thickness no)
		(fill yes
			(thermal_gap 0.5)
			(thermal_bridge_width 0.5)
			(island_removal_mode 1)
			(island_area_min 10)
		)
		(polygon
			(pts
				(xy 212.616211 167.424123) (xy 212.652728 167.380889) (xy 212.674756 167.340129) (xy 212.687384 167.262836)
				(xy 212.679773 167.195028) (xy 212.671481 167.124235) (xy 212.676995 167.044332) (xy 212.457207 166.999293)
				(xy 212.331497 167.187081) (xy 212.413542 167.216935) (xy 212.4778 167.239792) (xy 212.487777 167.256866)
				(xy 212.473376 167.281288)
			)
		)
	)
	(zone
		(net 1)
		(net_name "GND")
		(layer "F.Cu")
		(name "$teardrop_padvia$")
		(hatch none 0.1)
		(priority 30752)
		(attr
			(teardrop
				(type padvia)
			)
		)
		(connect_pads yes
			(clearance 0)
		)
		(min_thickness 0.0254)
		(filled_areas_thickness no)
		(fill yes
			(thermal_gap 0.5)
			(thermal_bridge_width 0.5)
			(island_removal_mode 1)
			(island_area_min 10)
		)
		(polygon
			(pts
				(xy 285.799323 75.11) (xy 285.9569 75.116932) (xy 286.070434 75.145456) (xy 286.112222 75.1625)
				(xy 286.201 74.96) (xy 286.112222 74.7575) (xy 286.016177 74.791883) (xy 285.914296 74.807101) (xy 285.799323 74.81)
			)
		)
	)
	(zone
		(net 221)
		(net_name "/Com Express 7 Interfaces/PCIe_{B1x4}.RX0-")
		(layer "F.Cu")
		(name "$teardrop_padvia$")
		(hatch none 0.1)
		(priority 31368)
		(attr
			(teardrop
				(type padvia)
			)
		)
		(connect_pads yes
			(clearance 0)
		)
		(min_thickness 0.0254)
		(filled_areas_thickness no)
		(fill yes
			(thermal_gap 0.5)
			(thermal_bridge_width 0.5)
			(island_removal_mode 1)
			(island_area_min 10)
		)
		(polygon
			(pts
				(xy 210.0705 159.617496) (xy 210.075235 159.57071) (xy 210.088379 159.535257) (xy 210.133387 159.48706)
				(xy 210.171608 159.462883) (xy 210.214774 159.435514) (xy 210.256731 159.398852) (xy 210.0935 159.249)
				(xy 209.872823 159.269859) (xy 209.877452 159.370536) (xy 209.874019 159.453908) (xy 209.873895 159.455963)
				(xy 209.8685 159.617496)
			)
		)
	)
	(zone
		(net 288)
		(net_name "/2xUSB3.0+RJ45/~{GBE0_LINK_1000}")
		(layer "F.Cu")
		(name "$teardrop_padvia$")
		(hatch none 0.1)
		(priority 31848)
		(attr
			(teardrop
				(type padvia)
			)
		)
		(connect_pads yes
			(clearance 0)
		)
		(min_thickness 0.0254)
		(filled_areas_thickness no)
		(fill yes
			(thermal_gap 0.5)
			(thermal_bridge_width 0.5)
			(island_removal_mode 1)
			(island_area_min 10)
		)
		(polygon
			(pts
				(xy 124.739127 111.482485) (xy 124.686618 111.528181) (xy 124.640623 111.554768) (xy 124.554174 111.575152)
				(xy 124.538841 111.576988) (xy 124.456105 111.589323) (xy 124.499293 111.810707) (xy 124.720677 111.853895)
				(xy 124.733011 111.77116) (xy 124.753349 111.673881) (xy 124.780057 111.625841) (xy 124.827515 111.570873)
			)
		)
	)
	(zone
		(net 637)
		(net_name "Net-(U41-~{RESET})")
		(layer "F.Cu")
		(name "$teardrop_padvia$")
		(hatch none 0.1)
		(priority 31085)
		(attr
			(teardrop
				(type padvia)
			)
		)
		(connect_pads yes
			(clearance 0)
		)
		(min_thickness 0.0254)
		(filled_areas_thickness no)
		(fill yes
			(thermal_gap 0.5)
			(thermal_bridge_width 0.5)
			(island_removal_mode 1)
			(island_area_min 10)
		)
		(polygon
			(pts
				(xy 127.9625 82.653001) (xy 127.982273 82.593589) (xy 128.045547 82.537504) (xy 128.094172 82.515802)
				(xy 128.153532 82.501128) (xy 128.1655 82.499348) (xy 127.9 82.239001) (xy 127.6345 82.499348) (xy 127.694639 82.512198)
				(xy 127.744523 82.532132) (xy 127.784642 82.558057) (xy 127.813655 82.587877) (xy 127.831146 82.619295)
				(xy 127.837479 82.651106) (xy 127.8375 82.653001)
			)
		)
	)
	(zone
		(net 708)
		(net_name "Net-(U32-~{MR})")
		(layer "F.Cu")
		(name "$teardrop_padvia$")
		(hatch none 0.1)
		(priority 30321)
		(attr
			(teardrop
				(type padvia)
			)
		)
		(connect_pads yes
			(clearance 0)
		)
		(min_thickness 0.0254)
		(filled_areas_thickness no)
		(fill yes
			(thermal_gap 0.5)
			(thermal_bridge_width 0.5)
			(island_removal_mode 1)
			(island_area_min 10)
		)
		(polygon
			(pts
				(xy 257.785 128.0465) (xy 257.733069 128.026455) (xy 257.709949 128.000594) (xy 257.691433 127.964121)
				(xy 257.675 127.8615) (xy 257.174 128.109) (xy 257.675 128.3565) (xy 257.679701 128.298118) (xy 257.692606 128.25082)
				(xy 257.711916 128.214575) (xy 257.735838 128.189332) (xy 257.785 128.1715)
			)
		)
	)
	(zone
		(net 434)
		(net_name "/Com Express 7 MGMT/~{TYPE1}")
		(layer "F.Cu")
		(name "$teardrop_padvia$")
		(hatch none 0.1)
		(priority 31873)
		(attr
			(teardrop
				(type padvia)
			)
		)
		(connect_pads yes
			(clearance 0)
		)
		(min_thickness 0.0254)
		(filled_areas_thickness no)
		(fill yes
			(thermal_gap 0.5)
			(thermal_bridge_width 0.5)
			(island_removal_mode 1)
			(island_area_min 10)
		)
		(polygon
			(pts
				(xy 245.460873 149.927515) (xy 245.513382 149.881819) (xy 245.559376 149.855231) (xy 245.645824 149.834847)
				(xy 245.66116 149.833011) (xy 245.743895 149.820677) (xy 245.700707 149.599293) (xy 245.479323 149.556105)
				(xy 245.466988 149.638841) (xy 245.446651 149.736119) (xy 245.419943 149.784159) (xy 245.372485 149.839127)
			)
		)
	)
	(zone
		(net 772)
		(net_name "/Backplane/PCIe_{x2}.RX1-")
		(layer "F.Cu")
		(name "$teardrop_padvia$")
		(hatch none 0.1)
		(priority 32048)
		(attr
			(teardrop
				(type padvia)
			)
		)
		(connect_pads yes
			(clearance 0)
		)
		(min_thickness 0.0254)
		(filled_areas_thickness no)
		(fill yes
			(thermal_gap 0.5)
			(thermal_bridge_width 0.5)
			(island_removal_mode 1)
			(island_area_min 10)
		)
		(polygon
			(pts
				(xy 314.688 161.809) (xy 314.667928 161.816104) (xy 314.63631 161.825575) (xy 314.622742 161.818649)
				(xy 314.613308 161.797039) (xy 314.362 161.908) (xy 314.608735 162.022015) (xy 314.618866 162.001124)
				(xy 314.632745 161.994069) (xy 314.666773 162.003702) (xy 314.688 162.011)
			)
		)
	)
	(zone
		(net 192)
		(net_name "/OCuLink/PCIe_{REF0}.CK+")
		(layer "F.Cu")
		(name "$teardrop_padvia$")
		(hatch none 0.1)
		(priority 32078)
		(attr
			(teardrop
				(type padvia)
			)
		)
		(connect_pads yes
			(clearance 0)
		)
		(min_thickness 0.0254)
		(filled_areas_thickness no)
		(fill yes
			(thermal_gap 0.5)
			(thermal_bridge_width 0.5)
			(island_removal_mode 1)
			(island_area_min 10)
		)
		(polygon
			(pts
				(xy 111.599 151.488) (xy 111.606198 151.508648) (xy 111.615792 151.540984) (xy 111.608965 151.555007)
				(xy 111.5875 151.564995) (xy 111.7 151.814) (xy 111.8125 151.564995) (xy 111.791324 151.555271)
				(xy 111.784269 151.541643) (xy 111.793802 151.508648) (xy 111.801 151.488)
			)
		)
	)
	(zone
		(net 1)
		(net_name "GND")
		(layer "F.Cu")
		(name "$teardrop_padvia$")
		(hatch none 0.1)
		(priority 31183)
		(attr
			(teardrop
				(type padvia)
			)
		)
		(connect_pads yes
			(clearance 0)
		)
		(min_thickness 0.0254)
		(filled_areas_thickness no)
		(fill yes
			(thermal_gap 0.5)
			(thermal_bridge_width 0.5)
			(island_removal_mode 1)
			(island_area_min 10)
		)
		(polygon
			(pts
				(xy 182.625 150.375677) (xy 182.62972 150.306353) (xy 182.642756 150.253449) (xy 182.694658 150.16086)
				(xy 182.746458 150.077363) (xy 182.55 149.974) (xy 182.342355 150.050358) (xy 182.374583 150.130861)
				(xy 182.410965 150.232318) (xy 182.425 150.375677)
			)
		)
	)
	(zone
		(net 208)
		(net_name "/Backplane/UART.RX")
		(layer "F.Cu")
		(name "$teardrop_padvia$")
		(hatch none 0.1)
		(priority 30638)
		(attr
			(teardrop
				(type padvia)
			)
		)
		(connect_pads yes
			(clearance 0)
		)
		(min_thickness 0.0254)
		(filled_areas_thickness no)
		(fill yes
			(thermal_gap 0.5)
			(thermal_bridge_width 0.5)
			(island_removal_mode 1)
			(island_area_min 10)
		)
		(polygon
			(pts
				(xy 226.5875 169.62) (xy 226.598438 169.581177) (xy 226.620195 169.566067) (xy 226.66 169.56) (xy 226.525 168.684)
				(xy 226.39 169.56) (xy 226.425281 169.564517) (xy 226.446797 169.576138) (xy 226.461995 169.608961)
				(xy 226.4625 169.62)
			)
		)
	)
	(zone
		(net 543)
		(net_name "Net-(Q10-B)")
		(layer "F.Cu")
		(name "$teardrop_padvia$")
		(hatch none 0.1)
		(priority 31773)
		(attr
			(teardrop
				(type padvia)
			)
		)
		(connect_pads yes
			(clearance 0)
		)
		(min_thickness 0.0254)
		(filled_areas_thickness no)
		(fill yes
			(thermal_gap 0.5)
			(thermal_bridge_width 0.5)
			(island_removal_mode 1)
			(island_area_min 10)
		)
		(polygon
			(pts
				(xy 255.849323 85.792498) (xy 255.918763 85.797316) (xy 255.970087 85.811038) (xy 256.045628 85.857753)
				(xy 256.057769 85.867297) (xy 256.124997 85.91708) (xy 256.251 85.729999) (xy 256.124997 85.542918)
				(xy 256.057769 85.5927) (xy 255.974603 85.647104) (xy 255.921748 85.662188) (xy 255.849323 85.667498)
			)
		)
	)
	(zone
		(net 1)
		(net_name "GND")
		(layer "F.Cu")
		(name "$teardrop_padvia$")
		(hatch none 0.1)
		(priority 31937)
		(attr
			(teardrop
				(type padvia)
			)
		)
		(connect_pads yes
			(clearance 0)
		)
		(min_thickness 0.0254)
		(filled_areas_thickness no)
		(fill yes
			(thermal_gap 0.5)
			(thermal_bridge_width 0.5)
			(island_removal_mode 1)
			(island_area_min 10)
		)
		(polygon
			(pts
				(xy 314.008 164.06) (xy 314.018115 164.059847) (xy 314.048832 164.06046) (xy 314.08132 164.068782)
				(xy 314.110475 164.092675) (xy 314.131191 164.14) (xy 314.364 163.96) (xy 314.131191 163.78) (xy 314.117833 163.815901)
				(xy 314.099601 163.839199) (xy 314.054276 163.858899) (xy 314.018115 163.860153) (xy 314.008 163.86)
			)
		)
	)
	(zone
		(net 649)
		(net_name "/2xSFP+/KR to SFI #1/MDIO")
		(layer "F.Cu")
		(name "$teardrop_padvia$")
		(hatch none 0.1)
		(priority 31629)
		(attr
			(teardrop
				(type padvia)
			)
		)
		(connect_pads yes
			(clearance 0)
		)
		(min_thickness 0.0254)
		(filled_areas_thickness no)
		(fill yes
			(thermal_gap 0.5)
			(thermal_bridge_width 0.5)
			(island_removal_mode 1)
			(island_area_min 10)
		)
		(polygon
			(pts
				(xy 143.3825 143.411715) (xy 143.377946 143.314588) (xy 143.366069 143.244294) (xy 143.350812 143.18744)
				(xy 143.320677 143.062364) (xy 143.1 143.101165) (xy 142.989262 143.295154) (xy 143.060321 143.317267)
				(xy 143.127337 143.32081) (xy 143.177551 143.322931) (xy 143.218975 143.333269) (xy 143.247121 143.360104)
				(xy 143.2575 143.411715)
			)
		)
	)
	(zone
		(net 113)
		(net_name "/2xSFP+/10GKR_SFP0.TX-")
		(layer "F.Cu")
		(name "$teardrop_padvia$")
		(hatch none 0.1)
		(priority 31618)
		(attr
			(teardrop
				(type padvia)
			)
		)
		(connect_pads yes
			(clearance 0)
		)
		(min_thickness 0.0254)
		(filled_areas_thickness no)
		(fill yes
			(thermal_gap 0.5)
			(thermal_bridge_width 0.5)
			(island_removal_mode 1)
			(island_area_min 10)
		)
		(polygon
			(pts
				(xy 197.542643 154.047207) (xy 197.414035 153.92223) (xy 197.295676 153.806354) (xy 197.137412 153.960174)
				(xy 197.182014 154.181558) (xy 197.269294 154.148935) (xy 197.309227 154.131145) (xy 197.347727 154.122324)
				(xy 197.387063 154.12966) (xy 197.429506 154.160344)
			)
		)
	)
	(zone
		(net 196)
		(net_name "/OCuLink/PCIe_{x4}.RX3+")
		(layer "F.Cu")
		(name "$teardrop_padvia$")
		(hatch none 0.1)
		(priority 32063)
		(attr
			(teardrop
				(type padvia)
			)
		)
		(connect_pads yes
			(clearance 0)
		)
		(min_thickness 0.0254)
		(filled_areas_thickness no)
		(fill yes
			(thermal_gap 0.5)
			(thermal_bridge_width 0.5)
			(island_removal_mode 1)
			(island_area_min 10)
		)
		(polygon
			(pts
				(xy 107.203 152.138) (xy 107.195802 152.117352) (xy 107.186208 152.085016) (xy 107.193035 152.070993)
				(xy 107.2145 152.061004) (xy 107.102 151.812) (xy 106.9895 152.061004) (xy 107.010676 152.070729)
				(xy 107.017731 152.084357) (xy 107.008198 152.117352) (xy 107.001 152.138)
			)
		)
	)
	(zone
		(net 1)
		(net_name "GND")
		(layer "F.Cu")
		(name "$teardrop_padvia$")
		(hatch none 0.1)
		(priority 30034)
		(attr
			(teardrop
				(type padvia)
			)
		)
		(connect_pads yes
			(clearance 0)
		)
		(min_thickness 0.0254)
		(filled_areas_thickness no)
		(fill yes
			(thermal_gap 0.5)
			(thermal_bridge_width 0.5)
			(island_removal_mode 1)
			(island_area_min 10)
		)
		(polygon
			(pts
				(xy 108.415 133.76) (xy 108.451731 133.7486) (xy 108.486854 133.735847) (xy 108.520243 133.735008)
				(xy 108.545193 133.760065) (xy 108.555 133.825) (xy 109.506 133.51) (xy 108.555 133.195) (xy 108.550346 133.243969)
				(xy 108.537768 133.272616) (xy 108.505006 133.286964) (xy 108.451731 133.2714) (xy 108.415 133.26)
			)
		)
	)
	(zone
		(net 296)
		(net_name "/2xUSB3.0+RJ45/GbE.CTREF")
		(layer "F.Cu")
		(name "$teardrop_padvia$")
		(hatch none 0.1)
		(priority 31613)
		(attr
			(teardrop
				(type padvia)
			)
		)
		(connect_pads yes
			(clearance 0)
		)
		(min_thickness 0.0254)
		(filled_areas_thickness no)
		(fill yes
			(thermal_gap 0.5)
			(thermal_bridge_width 0.5)
			(island_removal_mode 1)
			(island_area_min 10)
		)
		(polygon
			(pts
				(xy 182.4625 169.499323) (xy 182.457747 169.560452) (xy 182.44448 169.606552) (xy 182.399229 169.673244)
				(xy 182.38137 169.692341) (xy 182.312919 169.774997) (xy 182.5 169.901) (xy 182.707644 169.824641)
				(xy 182.649334 169.709581) (xy 182.605855 169.62547) (xy 182.592451 169.571061) (xy 182.5875 169.499323)
			)
		)
	)
	(zone
		(net 894)
		(net_name "Net-(J2B-MOD_{ABS})")
		(layer "F.Cu")
		(name "$teardrop_padvia$")
		(hatch none 0.1)
		(priority 31110)
		(attr
			(teardrop
				(type padvia)
			)
		)
		(connect_pads yes
			(clearance 0)
		)
		(min_thickness 0.0254)
		(filled_areas_thickness no)
		(fill yes
			(thermal_gap 0.5)
			(thermal_bridge_width 0.5)
			(island_removal_mode 1)
			(island_area_min 10)
		)
		(polygon
			(pts
				(xy 177.507 146.0625) (xy 177.566412 146.082273) (xy 177.622497 146.145547) (xy 177.644199 146.194171)
				(xy 177.658873 146.253531) (xy 177.660653 146.265499) (xy 177.921 145.999999) (xy 177.660652 145.734499)
				(xy 177.647803 145.794638) (xy 177.627869 145.844522) (xy 177.601944 145.884641) (xy 177.572125 145.913655)
				(xy 177.540706 145.931146) (xy 177.508895 145.937479) (xy 177.507 145.9375)
			)
		)
	)
	(zone
		(net 973)
		(net_name "/PCIe redriver/RX_SW")
		(layer "F.Cu")
		(name "$teardrop_padvia$")
		(hatch none 0.1)
		(priority 31850)
		(attr
			(teardrop
				(type padvia)
			)
		)
		(connect_pads yes
			(clearance 0)
		)
		(min_thickness 0.0254)
		(filled_areas_thickness no)
		(fill yes
			(thermal_gap 0.5)
			(thermal_bridge_width 0.5)
			(island_removal_mode 1)
			(island_area_min 10)
		)
		(polygon
			(pts
				(xy 188.739127 135.472485) (xy 188.686618 135.518181) (xy 188.640623 135.544768) (xy 188.554174 135.565152)
				(xy 188.538841 135.566988) (xy 188.456105 135.579323) (xy 188.499293 135.800707) (xy 188.720677 135.843895)
				(xy 188.733011 135.76116) (xy 188.753349 135.663881) (xy 188.780057 135.615841) (xy 188.827515 135.560873)
			)
		)
	)
	(zone
		(net 1)
		(net_name "GND")
		(layer "F.Cu")
		(name "$teardrop_padvia$")
		(hatch none 0.1)
		(priority 30601)
		(attr
			(teardrop
				(type padvia)
			)
		)
		(connect_pads yes
			(clearance 0)
		)
		(min_thickness 0.0254)
		(filled_areas_thickness no)
		(fill yes
			(thermal_gap 0.5)
			(thermal_bridge_width 0.5)
			(island_removal_mode 1)
			(island_area_min 10)
		)
		(polygon
			(pts
				(xy 214.925 167.75) (xy 214.928333 167.764486) (xy 214.93119 167.79461) (xy 214.919036 167.805651)
				(xy 214.89 167.81) (xy 215.025 168.686) (xy 215.16 167.81) (xy 215.130666 167.805525) (xy 215.118642 167.794199)
				(xy 215.121667 167.764486) (xy 215.125 167.75)
			)
		)
	)
	(zone
		(net 110)
		(net_name "/2xSFP+/KR to SFI #1/REFCLK-")
		(layer "F.Cu")
		(name "$teardrop_padvia$")
		(hatch none 0.1)
		(priority 30635)
		(attr
			(teardrop
				(type padvia)
			)
		)
		(connect_pads yes
			(clearance 0)
		)
		(min_thickness 0.0254)
		(filled_areas_thickness no)
		(fill yes
			(thermal_gap 0.5)
			(thermal_bridge_width 0.5)
			(island_removal_mode 1)
			(island_area_min 10)
		)
		(polygon
			(pts
				(xy 143.843657 141.47) (xy 143.726743 141.525303) (xy 143.651162 141.54403) (xy 143.569242 141.552398)
				(xy 143.445508 141.54) (xy 143.479 141.86) (xy 143.775 141.956839) (xy 143.771699 141.819913) (xy 143.786222 141.716731)
				(xy 143.804263 141.673329) (xy 143.830638 141.640284) (xy 143.843657 141.63)
			)
		)
	)
	(zone
		(net 553)
		(net_name "/2xUSB3.0+RJ45/FLG_1B")
		(layer "F.Cu")
		(name "$teardrop_padvia$")
		(hatch none 0.1)
		(priority 31125)
		(attr
			(teardrop
				(type padvia)
			)
		)
		(connect_pads yes
			(clearance 0)
		)
		(min_thickness 0.0254)
		(filled_areas_thickness no)
		(fill yes
			(thermal_gap 0.5)
			(thermal_bridge_width 0.5)
			(island_removal_mode 1)
			(island_area_min 10)
		)
		(polygon
			(pts
				(xy 121.157 88.1225) (xy 121.216412 88.142273) (xy 121.272497 88.205547) (xy 121.294199 88.254172)
				(xy 121.308873 88.313531) (xy 121.310653 88.3255) (xy 121.571 88.06) (xy 121.310653 87.7945) (xy 121.297804 87.854638)
				(xy 121.27787 87.904522) (xy 121.251945 87.944641) (xy 121.222125 87.973654) (xy 121.190707 87.991146)
				(xy 121.158896 87.997479) (xy 121.157 87.9975)
			)
		)
	)
	(zone
		(net 166)
		(net_name "Net-(J2A-MOD_{ABS})")
		(layer "F.Cu")
		(name "$teardrop_padvia$")
		(hatch none 0.1)
		(priority 31808)
		(attr
			(teardrop
				(type padvia)
			)
		)
		(connect_pads yes
			(clearance 0)
		)
		(min_thickness 0.0254)
		(filled_areas_thickness no)
		(fill yes
			(thermal_gap 0.5)
			(thermal_bridge_width 0.5)
			(island_removal_mode 1)
			(island_area_min 10)
		)
		(polygon
			(pts
				(xy 177.600677 144.9375) (xy 177.531236 144.932682) (xy 177.479913 144.91896) (xy 177.404371 144.872246)
				(xy 177.392231 144.862701) (xy 177.325003 144.812919) (xy 177.199 145) (xy 177.325003 145.187081)
				(xy 177.392229 145.137299) (xy 177.475396 145.082894) (xy 177.528251 145.06781) (xy 177.600677 145.0625)
			)
		)
	)
	(zone
		(net 152)
		(net_name "/2xUSB3.0+RJ45/DD+")
		(layer "F.Cu")
		(name "$teardrop_padvia$")
		(hatch none 0.1)
		(priority 30014)
		(attr
			(teardrop
				(type padvia)
			)
		)
		(connect_pads yes
			(clearance 0)
		)
		(min_thickness 0.0254)
		(filled_areas_thickness no)
		(fill yes
			(thermal_gap 0.5)
			(thermal_bridge_width 0.5)
			(island_removal_mode 1)
			(island_area_min 10)
		)
		(polygon
			(pts
				(xy 117.325 101.29863) (xy 117.329805 101.504281) (xy 117.343439 101.664354) (xy 117.389653 101.907055)
				(xy 117.411451 101.992909) (xy 117.48797 102.321686) (xy 118.15 102.191) (xy 118.281686 101.52797)
				(xy 118.126123 101.514392) (xy 117.903278 101.530171) (xy 117.736874 101.543431) (xy 117.664137 101.540845)
				(xy 117.600707 101.527545) (xy 117.548331 101.500102) (xy 117.508756 101.455088) (xy 117.48373 101.389073)
				(xy 117.475 101.29863)
			)
		)
	)
	(zone
		(net 1)
		(net_name "GND")
		(layer "F.Cu")
		(name "$teardrop_padvia$")
		(hatch none 0.1)
		(priority 30871)
		(attr
			(teardrop
				(type padvia)
			)
		)
		(connect_pads yes
			(clearance 0)
		)
		(min_thickness 0.0254)
		(filled_areas_thickness no)
		(fill yes
			(thermal_gap 0.5)
			(thermal_bridge_width 0.5)
			(island_removal_mode 1)
			(island_area_min 10)
		)
		(polygon
			(pts
				(xy 195.80861 78.045163) (xy 195.814382 78.004426) (xy 195.834786 77.962511) (xy 195.861961 77.93421)
				(xy 195.901507 77.910781) (xy 195.97411 77.89151) (xy 195.70861 77.631163) (xy 195.44311 77.89151)
				(xy 195.496252 77.903377) (xy 195.537291 77.921825) (xy 195.588992 77.972499) (xy 195.608328 78.036068)
				(xy 195.60861 78.045163)
			)
		)
	)
	(zone
		(net 289)
		(net_name "/2xUSB3.0+RJ45/GbE.MDI2-")
		(layer "F.Cu")
		(name "$teardrop_padvia$")
		(hatch none 0.1)
		(priority 31684)
		(attr
			(teardrop
				(type padvia)
			)
		)
		(connect_pads yes
			(clearance 0)
		)
		(min_thickness 0.0254)
		(filled_areas_thickness no)
		(fill yes
			(thermal_gap 0.5)
			(thermal_bridge_width 0.5)
			(island_removal_mode 1)
			(island_area_min 10)
		)
		(polygon
			(pts
				(xy 135.354702 106.998637) (xy 135.345124 106.989883) (xy 135.314041 106.953668) (xy 135.309141 106.928311)
				(xy 135.32 106.896886) (xy 134.834293 106.839293) (xy 134.840002 107.005) (xy 134.984183 107.010399)
				(xy 135.09938 107.028192) (xy 135.164093 107.049214) (xy 135.217071 107.078243) (xy 135.248637 107.104702)
			)
		)
	)
	(zone
		(net 84)
		(net_name "/Com Express 7 MGMT/PWRBTN")
		(layer "F.Cu")
		(name "$teardrop_padvia$")
		(hatch none 0.1)
		(priority 31028)
		(attr
			(teardrop
				(type padvia)
			)
		)
		(connect_pads yes
			(clearance 0)
		)
		(min_thickness 0.0254)
		(filled_areas_thickness no)
		(fill yes
			(thermal_gap 0.5)
			(thermal_bridge_width 0.5)
			(island_removal_mode 1)
			(island_area_min 10)
		)
		(polygon
			(pts
				(xy 247.788 128.7275) (xy 247.725134 128.707531) (xy 247.693156 128.681079) (xy 247.664642 128.643668)
				(xy 247.642118 128.596473) (xy 247.626908 128.538832) (xy 247.626799 128.538203) (xy 247.349002 128.790001)
				(xy 247.626799 129.041799) (xy 247.641096 128.986366) (xy 247.662176 128.940481) (xy 247.689542 128.902798)
				(xy 247.72045 128.875565) (xy 247.753736 128.858527) (xy 247.786567 128.85251) (xy 247.788001 128.852499)
			)
		)
	)
	(zone
		(net 1)
		(net_name "GND")
		(layer "F.Cu")
		(name "$teardrop_padvia$")
		(hatch none 0.1)
		(priority 30560)
		(attr
			(teardrop
				(type padvia)
			)
		)
		(connect_pads yes
			(clearance 0)
		)
		(min_thickness 0.0254)
		(filled_areas_thickness no)
		(fill yes
			(thermal_gap 0.5)
			(thermal_bridge_width 0.5)
			(island_removal_mode 1)
			(island_area_min 10)
		)
		(polygon
			(pts
				(xy 216.925 167.75) (xy 216.928333 167.764486) (xy 216.93119 167.79461) (xy 216.919036 167.805651)
				(xy 216.89 167.81) (xy 217.025 168.686) (xy 217.16 167.81) (xy 217.130666 167.805525) (xy 217.118642 167.794199)
				(xy 217.121667 167.764486) (xy 217.125 167.75)
			)
		)
	)
	(zone
		(net 1)
		(net_name "GND")
		(layer "F.Cu")
		(name "$teardrop_padvia$")
		(hatch none 0.1)
		(priority 31264)
		(attr
			(teardrop
				(type padvia)
			)
		)
		(connect_pads yes
			(clearance 0)
		)
		(min_thickness 0.0254)
		(filled_areas_thickness no)
		(fill yes
			(thermal_gap 0.5)
			(thermal_bridge_width 0.5)
			(island_removal_mode 1)
			(island_area_min 10)
		)
		(polygon
			(pts
				(xy 196.125 167.875677) (xy 196.129713 167.797764) (xy 196.1427 167.73898) (xy 196.184802 167.647947)
				(xy 196.2275 167.562778) (xy 196.025 167.474) (xy 195.8225 167.562778) (xy 195.865198 167.647949)
				(xy 195.907867 167.740783) (xy 195.920444 167.798922) (xy 195.925 167.875677)
			)
		)
	)
	(zone
		(net 1)
		(net_name "GND")
		(layer "F.Cu")
		(name "$teardrop_padvia$")
		(hatch none 0.1)
		(priority 31292)
		(attr
			(teardrop
				(type padvia)
			)
		)
		(connect_pads yes
			(clearance 0)
		)
		(min_thickness 0.0254)
		(filled_areas_thickness no)
		(fill yes
			(thermal_gap 0.5)
			(thermal_bridge_width 0.5)
			(island_removal_mode 1)
			(island_area_min 10)
		)
		(polygon
			(pts
				(xy 187.86261 152.145969) (xy 187.804186 152.197728) (xy 187.753436 152.23011) (xy 187.659299 152.264708)
				(xy 187.56888 152.294741) (xy 187.649293 152.500707) (xy 187.855257 152.581121) (xy 187.88529 152.490703)
				(xy 187.920762 152.394889) (xy 187.952979 152.344885) (xy 188.004031 152.28739)
			)
		)
	)
	(zone
		(net 633)
		(net_name "Net-(U41-A0)")
		(layer "F.Cu")
		(name "$teardrop_padvia$")
		(hatch none 0.1)
		(priority 31109)
		(attr
			(teardrop
				(type padvia)
			)
		)
		(connect_pads yes
			(clearance 0)
		)
		(min_thickness 0.0254)
		(filled_areas_thickness no)
		(fill yes
			(thermal_gap 0.5)
			(thermal_bridge_width 0.5)
			(island_removal_mode 1)
			(island_area_min 10)
		)
		(polygon
			(pts
				(xy 133.532 84.3725) (xy 133.591412 84.392273) (xy 133.647496 84.455547) (xy 133.669198 84.504172)
				(xy 133.683872 84.563531) (xy 133.685652 84.5755) (xy 133.946 84.310001) (xy 133.685653 84.0445)
				(xy 133.672804 84.104638) (xy 133.65287 84.154522) (xy 133.626945 84.194641) (xy 133.597125 84.223654)
				(xy 133.565707 84.241146) (xy 133.533896 84.247479) (xy 133.532 84.2475)
			)
		)
	)
	(zone
		(net 192)
		(net_name "/OCuLink/PCIe_{REF0}.CK+")
		(layer "F.Cu")
		(name "$teardrop_padvia$")
		(hatch none 0.1)
		(priority 32075)
		(attr
			(teardrop
				(type padvia)
			)
		)
		(connect_pads yes
			(clearance 0)
		)
		(min_thickness 0.0254)
		(filled_areas_thickness no)
		(fill yes
			(thermal_gap 0.5)
			(thermal_bridge_width 0.5)
			(island_removal_mode 1)
			(island_area_min 10)
		)
		(polygon
			(pts
				(xy 111.599 152.26) (xy 111.606198 152.280648) (xy 111.615792 152.312984) (xy 111.608965 152.327007)
				(xy 111.5875 152.336995) (xy 111.7 152.586) (xy 111.8125 152.336995) (xy 111.791324 152.327271)
				(xy 111.784269 152.313643) (xy 111.793802 152.280648) (xy 111.801 152.26)
			)
		)
	)
	(zone
		(net 65)
		(net_name "+12V")
		(layers "F.Cu" "B.Cu")
		(hatch edge 0.5)
		(priority 21)
		(connect_pads yes
			(clearance 0.15)
		)
		(min_thickness 0.25)
		(filled_areas_thickness no)
		(fill yes
			(thermal_gap 0.5)
			(thermal_bridge_width 0.5)
			(smoothing fillet)
			(radius 0.2)
		)
		(polygon
			(pts
				(xy 306.675 144.21) (xy 306.675 140.36) (xy 299.675 140.36) (xy 299.675 144.21)
			)
		)
	)
	(zone
		(net 144)
		(net_name "VCC")
		(layers "F.Cu" "B.Cu")
		(hatch edge 0.5)
		(priority 1)
		(connect_pads yes
			(clearance 0.15)
		)
		(min_thickness 0.25)
		(filled_areas_thickness no)
		(fill yes
			(thermal_gap 0.2)
			(thermal_bridge_width 0.5)
			(smoothing fillet)
			(radius 0.5)
		)
		(polygon
			(pts
				(xy 317.6 149.91) (xy 309.8 149.91) (xy 309.8 153.61) (xy 312.575 156.385) (xy 317.6 156.385)
			)
		)
	)
	(zone
		(net 0)
		(net_name "")
		(layers "F.Cu" "B.Cu" "In1.Cu" "In2.Cu" "In3.Cu" "In4.Cu" "In5.Cu" "In6.Cu")
		(hatch edge 0.5)
		(connect_pads
			(clearance 0)
		)
		(min_thickness 0.25)
		(filled_areas_thickness no)
		(keepout
			(tracks allowed)
			(vias allowed)
			(pads allowed)
			(copperpour not_allowed)
			(footprints allowed)
		)
		(placement
			(enabled no)
			(sheetname "")
		)
		(fill
			(thermal_gap 0.5)
			(thermal_bridge_width 0.5)
		)
		(polygon
			(pts
				(xy 304.45 167.2) (xy 305.655 167.2) (xy 305.655 168.85) (xy 304.45 168.85)
			)
		)
	)
	(zone
		(net 1)
		(net_name "GND")
		(layer "B.Cu")
		(name "$teardrop_padvia$")
		(hatch none 0.1)
		(priority 30871)
		(attr
			(teardrop
				(type padvia)
			)
		)
		(connect_pads yes
			(clearance 0)
		)
		(min_thickness 0.0254)
		(filled_areas_thickness no)
		(fill yes
			(thermal_gap 0.5)
			(thermal_bridge_width 0.5)
			(island_removal_mode 1)
			(island_area_min 10)
		)
		(polygon
			(pts
				(xy 104.797002 162.71) (xy 104.807117 162.709847) (xy 104.837834 162.71046) (xy 104.870322 162.718782)
				(xy 104.899477 162.742675) (xy 104.920193 162.79) (xy 105.153002 162.61) (xy 104.920193 162.43)
				(xy 104.906835 162.465901) (xy 104.888603 162.489199) (xy 104.843278 162.508899) (xy 104.807117 162.510153)
				(xy 104.797002 162.51)
			)
		)
	)
	(zone
		(net 679)
		(net_name "Net-(U45C-PRTAD2)")
		(layer "B.Cu")
		(name "$teardrop_padvia$")
		(hatch none 0.1)
		(priority 30710)
		(attr
			(teardrop
				(type padvia)
			)
		)
		(connect_pads yes
			(clearance 0)
		)
		(min_thickness 0.0254)
		(filled_areas_thickness no)
		(fill yes
			(thermal_gap 0.5)
			(thermal_bridge_width 0.5)
			(island_removal_mode 1)
			(island_area_min 10)
		)
		(polygon
			(pts
				(xy 127.889323 139.9225) (xy 127.958764 139.927318) (xy 128.010088 139.94104) (xy 128.085629 139.987755)
				(xy 128.097769 139.997299) (xy 128.164997 140.047081) (xy 128.291 139.86) (xy 128.164997 139.672919)
				(xy 128.097768 139.722702) (xy 128.014602 139.777106) (xy 127.961748 139.79219) (xy 127.889323 139.7975)
			)
		)
	)
	(zone
		(net 1)
		(net_name "GND")
		(layer "B.Cu")
		(name "$teardrop_padvia$")
		(hatch none 0.1)
		(priority 30255)
		(attr
			(teardrop
				(type padvia)
			)
		)
		(connect_pads yes
			(clearance 0)
		)
		(min_thickness 0.0254)
		(filled_areas_thickness no)
		(fill yes
			(thermal_gap 0.5)
			(thermal_bridge_width 0.5)
			(island_removal_mode 1)
			(island_area_min 10)
		)
		(polygon
			(pts
				(xy 176.779323 110.51) (xy 176.9369 110.516932) (xy 177.050434 110.545456) (xy 177.092222 110.5625)
				(xy 177.181 110.36) (xy 177.092222 110.1575) (xy 176.996177 110.191883) (xy 176.894296 110.207101)
				(xy 176.779323 110.21)
			)
		)
	)
	(zone
		(net 628)
		(net_name "/PCIe redriver/TX_SW")
		(layer "B.Cu")
		(name "$teardrop_padvia$")
		(hatch none 0.1)
		(priority 30916)
		(attr
			(teardrop
				(type padvia)
			)
		)
		(connect_pads yes
			(clearance 0)
		)
		(min_thickness 0.0254)
		(filled_areas_thickness no)
		(fill yes
			(thermal_gap 0.5)
			(thermal_bridge_width 0.5)
			(island_removal_mode 1)
			(island_area_min 10)
		)
		(polygon
			(pts
				(xy 113.8385 145.1855) (xy 113.838596 145.191822) (xy 113.833011 145.231325) (xy 113.818078 145.249547)
				(xy 113.7885 145.262495) (xy 113.901 145.674) (xy 114.0135 145.262495) (xy 113.986507 145.251379)
				(xy 113.971405 145.235852) (xy 113.963404 145.191822) (xy 113.9635 145.1855)
			)
		)
	)
	(zone
		(net 969)
		(net_name "/M.2 key M #1/M2_3V3")
		(layer "B.Cu")
		(name "$teardrop_padvia$")
		(hatch none 0.1)
		(priority 30276)
		(attr
			(teardrop
				(type padvia)
			)
		)
		(connect_pads yes
			(clearance 0)
		)
		(min_thickness 0.0254)
		(filled_areas_thickness no)
		(fill yes
			(thermal_gap 0.5)
			(thermal_bridge_width 0.5)
			(island_removal_mode 1)
			(island_area_min 10)
		)
		(polygon
			(pts
				(xy 178.260676 110.96) (xy 178.103105 110.953069) (xy 177.989577 110.924549) (xy 177.947777 110.9075)
				(xy 177.858999 111.11) (xy 177.947777 111.3125) (xy 178.043816 111.278118) (xy 178.145688 111.2629)
				(xy 178.260676 111.26)
			)
		)
	)
	(zone
		(net 867)
		(net_name "/Backplane/PCIe_{x2}.TX0-")
		(layer "B.Cu")
		(name "$teardrop_padvia$")
		(hatch none 0.1)
		(priority 30564)
		(attr
			(teardrop
				(type padvia)
			)
		)
		(connect_pads yes
			(clearance 0)
		)
		(min_thickness 0.0254)
		(filled_areas_thickness no)
		(fill yes
			(thermal_gap 0.5)
			(thermal_bridge_width 0.5)
			(island_removal_mode 1)
			(island_area_min 10)
		)
		(polygon
			(pts
				(xy 269.367496 139.1935) (xy 269.205964 139.198895) (xy 269.121554 139.202445) (xy 269.01986 139.197823)
				(xy 268.999 139.4185) (xy 269.148852 139.581731) (xy 269.202992 139.513062) (xy 269.212883 139.496608)
				(xy 269.237383 139.457935) (xy 269.26689 139.425721) (xy 269.308046 139.403673) (xy 269.367496 139.3955)
			)
		)
	)
	(zone
		(net 98)
		(net_name "/OCuLink/PCIe_{x4}.TX3-")
		(layer "B.Cu")
		(name "$teardrop_padvia$")
		(hatch none 0.1)
		(priority 30986)
		(attr
			(teardrop
				(type padvia)
			)
		)
		(connect_pads yes
			(clearance 0)
		)
		(min_thickness 0.0254)
		(filled_areas_thickness no)
		(fill yes
			(thermal_gap 0.5)
			(thermal_bridge_width 0.5)
			(island_removal_mode 1)
			(island_area_min 10)
		)
		(polygon
			(pts
				(xy 104.058 158.713) (xy 104.078648 158.705802) (xy 104.110984 158.696208) (xy 104.125007 158.703035)
				(xy 104.134995 158.7245) (xy 104.384 158.612) (xy 104.134995 158.4995) (xy 104.125271 158.520676)
				(xy 104.111643 158.527731) (xy 104.078648 158.518198) (xy 104.058 158.511)
			)
		)
	)
	(zone
		(net 159)
		(net_name "/2xUSB3.0+RJ45/USBSS_1.RX+")
		(layer "B.Cu")
		(name "$teardrop_padvia$")
		(hatch none 0.1)
		(priority 30962)
		(attr
			(teardrop
				(type padvia)
			)
		)
		(connect_pads yes
			(clearance 0)
		)
		(min_thickness 0.0254)
		(filled_areas_thickness no)
		(fill yes
			(thermal_gap 0.5)
			(thermal_bridge_width 0.5)
			(island_removal_mode 1)
			(island_area_min 10)
		)
		(polygon
			(pts
				(xy 101 106.0145) (xy 101.077915 105.999581) (xy 101.165049 105.981001) (xy 101.213254 105.980096)
				(xy 101.264271 105.99) (xy 101.326 105.865) (xy 101.05071 105.798926) (xy 101.046118 105.827097)
				(xy 101.035057 105.836843) (xy 101.012655 105.83285) (xy 101 105.8295)
			)
		)
	)
	(zone
		(net 365)
		(net_name "/Com Express 7 MGMT/PWR_OK")
		(layer "B.Cu")
		(name "$teardrop_padvia$")
		(hatch none 0.1)
		(priority 30123)
		(attr
			(teardrop
				(type padvia)
			)
		)
		(connect_pads yes
			(clearance 0)
		)
		(min_thickness 0.0254)
		(filled_areas_thickness no)
		(fill yes
			(thermal_gap 0.5)
			(thermal_bridge_width 0.5)
			(island_removal_mode 1)
			(island_area_min 10)
		)
		(polygon
			(pts
				(xy 102.314699 72.406913) (xy 102.273678 72.440659) (xy 102.220642 72.47106) (xy 102.158146 72.494783)
				(xy 102.087625 72.50907) (xy 102.000473 72.51) (xy 102.000293 73.010707) (xy 102.301 73.041875)
				(xy 102.297378 72.866544) (xy 102.309345 72.715563) (xy 102.327408 72.632786) (xy 102.354999 72.562517)
				(xy 102.403087 72.495301)
			)
		)
	)
	(zone
		(net 216)
		(net_name "/Com Express 7 Interfaces/PCIe_{B1x4}.TX2+")
		(layer "B.Cu")
		(name "$teardrop_padvia$")
		(hatch none 0.1)
		(priority 30852)
		(attr
			(teardrop
				(type padvia)
			)
		)
		(connect_pads yes
			(clearance 0)
		)
		(min_thickness 0.0254)
		(filled_areas_thickness no)
		(fill yes
			(thermal_gap 0.5)
			(thermal_bridge_width 0.5)
			(island_removal_mode 1)
			(island_area_min 10)
		)
		(polygon
			(pts
				(xy 116.7445 145.1855) (xy 116.76193 145.297903) (xy 116.783683 145.421778) (xy 116.785642 145.492695)
				(xy 116.776 145.570348) (xy 116.901 145.674) (xy 116.964425 145.235684) (xy 116.938818 145.231225)
				(xy 116.932399 145.220281) (xy 116.940542 145.19966) (xy 116.9465 145.1855)
			)
		)
	)
	(zone
		(net 143)
		(net_name "/2xSFP+/KR to SFI #2/~{RESET}")
		(layer "B.Cu")
		(name "$teardrop_padvia$")
		(hatch none 0.1)
		(priority 30683)
		(attr
			(teardrop
				(type padvia)
			)
		)
		(connect_pads yes
			(clearance 0)
		)
		(min_thickness 0.0254)
		(filled_areas_thickness no)
		(fill yes
			(thermal_gap 0.5)
			(thermal_bridge_width 0.5)
			(island_removal_mode 1)
			(island_area_min 10)
		)
		(polygon
			(pts
				(xy 140.1875 135.409323) (xy 140.182682 135.478763) (xy 140.16896 135.530087) (xy 140.122245 135.605628)
				(xy 140.112702 135.617768) (xy 140.062919 135.684997) (xy 140.25 135.811) (xy 140.437081 135.684997)
				(xy 140.387299 135.617769) (xy 140.332894 135.534603) (xy 140.31781 135.481748) (xy 140.3125 135.409323)
			)
		)
	)
	(zone
		(net 428)
		(net_name "/2xSFP+/10GKR_SFP1.RX-")
		(layer "B.Cu")
		(name "$teardrop_padvia$")
		(hatch none 0.1)
		(priority 30611)
		(attr
			(teardrop
				(type padvia)
			)
		)
		(connect_pads yes
			(clearance 0)
		)
		(min_thickness 0.0254)
		(filled_areas_thickness no)
		(fill yes
			(thermal_gap 0.5)
			(thermal_bridge_width 0.5)
			(island_removal_mode 1)
			(island_area_min 10)
		)
		(polygon
			(pts
				(xy 134.675 147.980042) (xy 134.671973 147.804213) (xy 134.670677 147.625115) (xy 134.45 147.619)
				(xy 134.324997 147.807081) (xy 134.406497 147.847016) (xy 134.448754 147.865329) (xy 134.48324 147.888932)
				(xy 134.506481 147.924833) (xy 134.515 147.980042)
			)
		)
	)
	(zone
		(net 976)
		(net_name "/PCIe redriver/RX_EQ2")
		(layer "B.Cu")
		(name "$teardrop_padvia$")
		(hatch none 0.1)
		(priority 30747)
		(attr
			(teardrop
				(type padvia)
			)
		)
		(connect_pads yes
			(clearance 0)
		)
		(min_thickness 0.0254)
		(filled_areas_thickness no)
		(fill yes
			(thermal_gap 0.5)
			(thermal_bridge_width 0.5)
			(island_removal_mode 1)
			(island_area_min 10)
		)
		(polygon
			(pts
				(xy 188.900677 136.9875) (xy 188.831236 136.982682) (xy 188.779913 136.96896) (xy 188.704371 136.922246)
				(xy 188.692231 136.912701) (xy 188.625003 136.862919) (xy 188.499 137.05) (xy 188.625003 137.237081)
				(xy 188.692229 137.187299) (xy 188.775396 137.132894) (xy 188.828251 137.11781) (xy 188.900677 137.1125)
			)
		)
	)
	(zone
		(net 221)
		(net_name "/Com Express 7 Interfaces/PCIe_{B1x4}.RX0-")
		(layer "B.Cu")
		(name "$teardrop_padvia$")
		(hatch none 0.1)
		(priority 30167)
		(attr
			(teardrop
				(type padvia)
			)
		)
		(connect_pads yes
			(clearance 0)
		)
		(min_thickness 0.0254)
		(filled_areas_thickness no)
		(fill yes
			(thermal_gap 0.5)
			(thermal_bridge_width 0.5)
			(island_removal_mode 1)
			(island_area_min 10)
		)
		(polygon
			(pts
				(xy 199.011275 137.763224) (xy 199.004301 137.731579) (xy 199.007974 137.69901) (xy 199.047723 137.627423)
				(xy 199.17787 137.502278) (xy 198.8994 137.362142) (xy 198.650353 137.565643) (xy 198.732948 137.642165)
				(xy 198.804854 137.755728) (xy 198.860922 137.886692) (xy 198.86844 137.906059)
			)
		)
	)
	(zone
		(net 257)
		(net_name "/Com Express 7 Interfaces/PCIe_{B2Bx4}.TX1-")
		(layer "B.Cu")
		(name "$teardrop_padvia$")
		(hatch none 0.1)
		(priority 30568)
		(attr
			(teardrop
				(type padvia)
			)
		)
		(connect_pads yes
			(clearance 0)
		)
		(min_thickness 0.0254)
		(filled_areas_thickness no)
		(fill yes
			(thermal_gap 0.5)
			(thermal_bridge_width 0.5)
			(island_removal_mode 1)
			(island_area_min 10)
		)
		(polygon
			(pts
				(xy 174.667496 101.7035) (xy 174.505964 101.708895) (xy 174.421554 101.712445) (xy 174.31986 101.707823)
				(xy 174.299 101.9285) (xy 174.448852 102.091731) (xy 174.502992 102.023062) (xy 174.512883 102.006608)
				(xy 174.537383 101.967935) (xy 174.56689 101.935721) (xy 174.608046 101.913673) (xy 174.667496 101.9055)
			)
		)
	)
	(zone
		(net 63)
		(net_name "Net-(U18-V_{CC})")
		(layer "B.Cu")
		(name "$teardrop_padvia$")
		(hatch none 0.1)
		(priority 30341)
		(attr
			(teardrop
				(type padvia)
			)
		)
		(connect_pads yes
			(clearance 0)
		)
		(min_thickness 0.0254)
		(filled_areas_thickness no)
		(fill yes
			(thermal_gap 0.5)
			(thermal_bridge_width 0.5)
			(island_removal_mode 1)
			(island_area_min 10)
		)
		(polygon
			(pts
				(xy 310.262999 122.3775) (xy 310.200133 122.357531) (xy 310.168155 122.331079) (xy 310.139641 122.293668)
				(xy 310.117117 122.246473) (xy 310.101906 122.188833) (xy 310.101797 122.188202) (xy 309.823999 122.44)
				(xy 310.101797 122.691798) (xy 310.116094 122.636365) (xy 310.137174 122.59048) (xy 310.164539 122.552799)
				(xy 310.195447 122.525566) (xy 310.228734 122.508528) (xy 310.261565 122.502511) (xy 310.262999 122.5025)
			)
		)
	)
	(zone
		(net 709)
		(net_name "Net-(U37-SCLK)")
		(layer "B.Cu")
		(name "$teardrop_padvia$")
		(hatch none 0.1)
		(priority 30117)
		(attr
			(teardrop
				(type padvia)
			)
		)
		(connect_pads yes
			(clearance 0)
		)
		(min_thickness 0.0254)
		(filled_areas_thickness no)
		(fill yes
			(thermal_gap 0.5)
			(thermal_bridge_width 0.5)
			(island_removal_mode 1)
			(island_area_min 10)
		)
		(polygon
			(pts
				(xy 214.433181 125.517794) (xy 214.437991 125.437545) (xy 214.45166 125.373453) (xy 214.498209 125.281739)
				(xy 214.569514 125.202534) (xy 214.629007 125.139777) (xy 214.691801 125.058339) (xy 214.38 124.849)
				(xy 214.068199 125.058339) (xy 214.177735 125.19423) (xy 214.230103 125.254682) (xy 214.27139 125.319811)
				(xy 214.298461 125.40304) (xy 214.308181 125.517794)
			)
		)
	)
	(zone
		(net 252)
		(net_name "/Com Express 7 Interfaces/PCIe_{B2Bx4}.RX1-")
		(layer "B.Cu")
		(name "$teardrop_padvia$")
		(hatch none 0.1)
		(priority 30298)
		(attr
			(teardrop
				(type padvia)
			)
		)
		(connect_pads yes
			(clearance 0)
		)
		(min_thickness 0.0254)
		(filled_areas_thickness no)
		(fill yes
			(thermal_gap 0.5)
			(thermal_bridge_width 0.5)
			(island_removal_mode 1)
			(island_area_min 10)
		)
		(polygon
			(pts
				(xy 175.39 100.461) (xy 175.404678 100.457463) (xy 175.434685 100.454192) (xy 175.445673 100.466143)
				(xy 175.45 100.495) (xy 176.201 100.36) (xy 175.45 100.225) (xy 175.445525 100.254204) (xy 175.434203 100.265997)
				(xy 175.404678 100.262537) (xy 175.39 100.259)
			)
		)
	)
	(zone
		(net 2)
		(net_name "+3V3")
		(layer "B.Cu")
		(name "$teardrop_padvia$")
		(hatch none 0.1)
		(priority 30265)
		(attr
			(teardrop
				(type padvia)
			)
		)
		(connect_pads yes
			(clearance 0)
		)
		(min_thickness 0.0254)
		(filled_areas_thickness no)
		(fill yes
			(thermal_gap 0.5)
			(thermal_bridge_width 0.5)
			(island_removal_mode 1)
			(island_area_min 10)
		)
		(polygon
			(pts
				(xy 121.900677 73.94) (xy 121.743106 73.933069) (xy 121.629578 73.904549) (xy 121.587778 73.8875)
				(xy 121.499 74.09) (xy 121.587778 74.2925) (xy 121.683817 74.258118) (xy 121.785689 74.2429) (xy 121.900677 74.24)
			)
		)
	)
	(zone
		(net 945)
		(net_name "/GPIO expander/GPIOEX5")
		(layer "B.Cu")
		(name "$teardrop_padvia$")
		(hatch none 0.1)
		(priority 30406)
		(attr
			(teardrop
				(type padvia)
			)
		)
		(connect_pads yes
			(clearance 0)
		)
		(min_thickness 0.0254)
		(filled_areas_thickness no)
		(fill yes
			(thermal_gap 0.5)
			(thermal_bridge_width 0.5)
			(island_removal_mode 1)
			(island_area_min 10)
		)
		(polygon
			(pts
				(xy 122.593 160.4975) (xy 122.533588 160.477727) (xy 122.477503 160.414453) (xy 122.455801 160.365828)
				(xy 122.441127 160.306468) (xy 122.439347 160.2945) (xy 122.179 160.56) (xy 122.439347 160.8255)
				(xy 122.452197 160.765361) (xy 122.472131 160.715477) (xy 122.498056 160.675358) (xy 122.527876 160.646345)
				(xy 122.559294 160.628854) (xy 122.591105 160.622521) (xy 122.593 160.6225)
			)
		)
	)
	(zone
		(net 259)
		(net_name "/Com Express 7 Interfaces/PCIe_{B2Bx4}.TX1+")
		(layer "B.Cu")
		(name "$teardrop_padvia$")
		(hatch none 0.1)
		(priority 30515)
		(attr
			(teardrop
				(type padvia)
			)
		)
		(connect_pads yes
			(clearance 0)
		)
		(min_thickness 0.0254)
		(filled_areas_thickness no)
		(fill yes
			(thermal_gap 0.5)
			(thermal_bridge_width 0.5)
			(island_removal_mode 1)
			(island_area_min 10)
		)
		(polygon
			(pts
				(xy 174.667496 101.3145) (xy 174.62071 101.309765) (xy 174.585258 101.296621) (xy 174.53706 101.251613)
				(xy 174.512884 101.213392) (xy 174.485514 101.170225) (xy 174.448852 101.128268) (xy 174.299 101.2915)
				(xy 174.31986 101.512177) (xy 174.420531 101.507548) (xy 174.503897 101.51098) (xy 174.505964 101.511105)
				(xy 174.667496 101.5165)
			)
		)
	)
	(zone
		(net 2)
		(net_name "+3V3")
		(layer "B.Cu")
		(hatch edge 0.5)
		(priority 1)
		(connect_pads yes
			(clearance 0.15)
		)
		(min_thickness 0.25)
		(filled_areas_thickness no)
		(fill yes
			(thermal_gap 0.2)
			(thermal_bridge_width 0.5)
			(smoothing fillet)
			(radius 0.2)
		)
		(polygon
			(pts
				(xy 137.1 164.11) (xy 137.8 164.11) (xy 138.4 163.51) (xy 139.7 163.51) (xy 140.85 162.36) (xy 140.85 161.51)
				(xy 138.45 161.51) (xy 138 161.06) (xy 137.1 161.06)
			)
		)
	)
	(zone
		(net 53)
		(net_name "/2xSFP+/SH")
		(layer "B.Cu")
		(name "$teardrop_padvia$")
		(hatch none 0.1)
		(priority 30234)
		(attr
			(teardrop
				(type padvia)
			)
		)
		(connect_pads yes
			(clearance 0)
		)
		(min_thickness 0.0254)
		(filled_areas_thickness no)
		(fill yes
			(thermal_gap 0.5)
			(thermal_bridge_width 0.5)
			(island_removal_mode 1)
			(island_area_min 10)
		)
		(polygon
			(pts
				(xy 123.443 169.285) (xy 123.42791 169.285337) (xy 123.387674 169.28476) (xy 123.34613 169.272946)
				(xy 123.310835 169.238367) (xy 123.289347 169.1695) (xy 123.029 169.435) (xy 123.289347 169.7005)
				(xy 123.300291 169.654062) (xy 123.317391 169.621865) (xy 123.361856 169.590422) (xy 123.42791 169.584663)
				(xy 123.443 169.585)
			)
		)
	)
	(zone
		(net 698)
		(net_name "Net-(U5-IO0_7)")
		(layer "B.Cu")
		(name "$teardrop_padvia$")
		(hatch none 0.1)
		(priority 30701)
		(attr
			(teardrop
				(type padvia)
			)
		)
		(connect_pads yes
			(clearance 0)
		)
		(min_thickness 0.0254)
		(filled_areas_thickness no)
		(fill yes
			(thermal_gap 0.5)
			(thermal_bridge_width 0.5)
			(island_removal_mode 1)
			(island_area_min 10)
		)
		(polygon
			(pts
				(xy 158.6875 162.909323) (xy 158.682682 162.978763) (xy 158.66896 163.030087) (xy 158.622245 163.105628)
				(xy 158.612702 163.117768) (xy 158.562919 163.184997) (xy 158.75 163.311) (xy 158.937081 163.184997)
				(xy 158.887299 163.117769) (xy 158.832894 163.034603) (xy 158.81781 162.981748) (xy 158.8125 162.909323)
			)
		)
	)
	(zone
		(net 956)
		(net_name "/PCIe redriver/PCIe_{I}_C.RX3-")
		(layer "B.Cu")
		(name "$teardrop_padvia$")
		(hatch none 0.1)
		(priority 30192)
		(attr
			(teardrop
				(type padvia)
			)
		)
		(connect_pads yes
			(clearance 0)
		)
		(min_thickness 0.0254)
		(filled_areas_thickness no)
		(fill yes
			(thermal_gap 0.5)
			(thermal_bridge_width 0.5)
			(island_removal_mode 1)
			(island_area_min 10)
		)
		(polygon
			(pts
				(xy 195.829834 141.231416) (xy 195.914831 141.257076) (xy 196.009983 141.301299) (xy 196.075202 141.344797)
				(xy 196.133807 141.399707) (xy 196.171914 141.451167) (xy 196.376442 141.203147) (xy 196.237081 140.9239)
				(xy 196.15112 141.013843) (xy 196.077998 141.069255) (xy 196.036263 141.086964) (xy 195.996313 141.091768)
				(xy 195.972669 141.088581)
			)
		)
	)
	(zone
		(net 945)
		(net_name "/GPIO expander/GPIOEX5")
		(layer "B.Cu")
		(name "$teardrop_padvia$")
		(hatch none 0.1)
		(priority 30888)
		(attr
			(teardrop
				(type padvia)
			)
		)
		(connect_pads yes
			(clearance 0)
		)
		(min_thickness 0.0254)
		(filled_areas_thickness no)
		(fill yes
			(thermal_gap 0.5)
			(thermal_bridge_width 0.5)
			(island_removal_mode 1)
			(island_area_min 10)
		)
		(polygon
			(pts
				(xy 197.212039 132.599574) (xy 197.20829 132.603428) (xy 197.17854 132.624948) (xy 197.156464 132.625473)
				(xy 197.128006 132.611363) (xy 196.905359 132.983737) (xy 197.273653 132.783534) (xy 197.264681 132.755756)
				(xy 197.266374 132.733235) (xy 197.29503 132.693177) (xy 197.300426 132.687961)
			)
		)
	)
	(zone
		(net 532)
		(net_name "/Backplane/PCIe_{x2}.RX0+")
		(layer "B.Cu")
		(name "$teardrop_padvia$")
		(hatch none 0.1)
		(priority 30512)
		(attr
			(teardrop
				(type padvia)
			)
		)
		(connect_pads yes
			(clearance 0)
		)
		(min_thickness 0.0254)
		(filled_areas_thickness no)
		(fill yes
			(thermal_gap 0.5)
			(thermal_bridge_width 0.5)
			(island_removal_mode 1)
			(island_area_min 10)
		)
		(polygon
			(pts
				(xy 220.767496 153.0545) (xy 220.72071 153.049765) (xy 220.685258 153.036621) (xy 220.63706 152.991613)
				(xy 220.612884 152.953392) (xy 220.585514 152.910225) (xy 220.548852 152.868268) (xy 220.399 153.0315)
				(xy 220.41986 153.252177) (xy 220.520531 153.247548) (xy 220.603897 153.25098) (xy 220.605964 153.251105)
				(xy 220.767496 153.2565)
			)
		)
	)
	(zone
		(net 289)
		(net_name "/2xUSB3.0+RJ45/GbE.MDI2-")
		(layer "B.Cu")
		(name "$teardrop_padvia$")
		(hatch none 0.1)
		(priority 30658)
		(attr
			(teardrop
				(type padvia)
			)
		)
		(connect_pads yes
			(clearance 0)
		)
		(min_thickness 0.0254)
		(filled_areas_thickness no)
		(fill yes
			(thermal_gap 0.5)
			(thermal_bridge_width 0.5)
			(island_removal_mode 1)
			(island_area_min 10)
		)
		(polygon
			(pts
				(xy 178.675 167.742084) (xy 178.672797 167.536718) (xy 178.670677 167.398242) (xy 178.45 167.399)
				(xy 178.324997 167.587081) (xy 178.401138 167.620995) (xy 178.417738 167.62605) (xy 178.459281 167.639844)
				(xy 178.493398 167.659262) (xy 178.516501 167.691083) (xy 178.525 167.742084)
			)
		)
	)
	(zone
		(net 2)
		(net_name "+3V3")
		(layer "B.Cu")
		(name "$teardrop_padvia$")
		(hatch none 0.1)
		(priority 30152)
		(attr
			(teardrop
				(type padvia)
			)
		)
		(connect_pads yes
			(clearance 0)
		)
		(min_thickness 0.0254)
		(filled_areas_thickness no)
		(fill yes
			(thermal_gap 0.5)
			(thermal_bridge_width 0.5)
			(island_removal_mode 1)
			(island_area_min 10)
		)
		(polygon
			(pts
				(xy 180.785962 89.034539) (xy 180.741401 88.981815) (xy 180.70172 88.913277) (xy 180.678536 88.849711)
				(xy 180.664926 88.776625) (xy 180.665001 88.679526) (xy 180.369294 88.759293) (xy 180.314527 89.08)
				(xy 180.437662 89.075545) (xy 180.544415 89.105949) (xy 180.63331 89.165231) (xy 180.64454 89.175961)
			)
		)
	)
	(zone
		(net 94)
		(net_name "/PCIe redriver/PCIe_{O}_C.TX3+")
		(layer "B.Cu")
		(name "$teardrop_padvia$")
		(hatch none 0.1)
		(priority 30837)
		(attr
			(teardrop
				(type padvia)
			)
		)
		(connect_pads yes
			(clearance 0)
		)
		(min_thickness 0.0254)
		(filled_areas_thickness no)
		(fill yes
			(thermal_gap 0.5)
			(thermal_bridge_width 0.5)
			(island_removal_mode 1)
			(island_area_min 10)
		)
		(polygon
			(pts
				(xy 115.4465 149.5355) (xy 115.440542 149.52134) (xy 115.43269 149.497405) (xy 115.440913 149.488742)
				(xy 115.464425 149.485315) (xy 115.401 149.047) (xy 115.276 149.150651) (xy 115.28528 149.277829)
				(xy 115.26193 149.423096) (xy 115.2445 149.5355)
			)
		)
	)
	(zone
		(net 935)
		(net_name "Net-(D13-C)")
		(layer "B.Cu")
		(name "$teardrop_padvia$")
		(hatch none 0.1)
		(priority 30637)
		(attr
			(teardrop
				(type padvia)
			)
		)
		(connect_pads yes
			(clearance 0)
		)
		(min_thickness 0.0254)
		(filled_areas_thickness no)
		(fill yes
			(thermal_gap 0.5)
			(thermal_bridge_width 0.5)
			(island_removal_mode 1)
			(island_area_min 10)
		)
		(polygon
			(pts
				(xy 177.68 94.710677) (xy 177.684676 94.642726) (xy 177.69741 94.590678) (xy 177.744888 94.502707)
				(xy 177.775957 94.453016) (xy 177.806173 94.388909) (xy 177.6 94.309) (xy 177.412919 94.435003)
				(xy 177.47618 94.514049) (xy 177.532649 94.590646) (xy 177.549081 94.641245) (xy 177.555 94.710677)
			)
		)
	)
	(zone
		(net 2)
		(net_name "+3V3")
		(layer "B.Cu")
		(name "$teardrop_padvia$")
		(hatch none 0.1)
		(priority 30791)
		(attr
			(teardrop
				(type padvia)
			)
		)
		(connect_pads yes
			(clearance 0)
		)
		(min_thickness 0.0254)
		(filled_areas_thickness no)
		(fill yes
			(thermal_gap 0.5)
			(thermal_bridge_width 0.5)
			(island_removal_mode 1)
			(island_area_min 10)
		)
		(polygon
			(pts
				(xy 118.8375 149.500323) (xy 118.832687 149.569322) (xy 118.818999 149.620376) (xy 118.772394 149.695477)
				(xy 118.762545 149.70792) (xy 118.711919 149.775997) (xy 118.899 149.902) (xy 119.086081 149.775997)
				(xy 119.037154 149.709644) (xy 118.982791 149.626) (xy 118.967776 149.572982) (xy 118.9625 149.500323)
			)
		)
	)
	(zone
		(net 315)
		(net_name "Net-(J12H-VCC_RTC)")
		(layer "B.Cu")
		(name "$teardrop_padvia$")
		(hatch none 0.1)
		(priority 30726)
		(attr
			(teardrop
				(type padvia)
			)
		)
		(connect_pads yes
			(clearance 0)
		)
		(min_thickness 0.0254)
		(filled_areas_thickness no)
		(fill yes
			(thermal_gap 0.5)
			(thermal_bridge_width 0.5)
			(island_removal_mode 1)
			(island_area_min 10)
		)
		(polygon
			(pts
				(xy 219.8625 143.300677) (xy 219.867318 143.231236) (xy 219.88104 143.179912) (xy 219.927755 143.10437)
				(xy 219.937299 143.092229) (xy 219.987081 143.025003) (xy 219.8 142.899) (xy 219.612919 143.025003)
				(xy 219.662701 143.092231) (xy 219.717106 143.175397) (xy 219.73219 143.228251) (xy 219.7375 143.300677)
			)
		)
	)
	(zone
		(net 678)
		(net_name "Net-(U45A-~{PDTRXA})")
		(layer "B.Cu")
		(name "$teardrop_padvia$")
		(hatch none 0.1)
		(priority 30788)
		(attr
			(teardrop
				(type padvia)
			)
		)
		(connect_pads yes
			(clearance 0)
		)
		(min_thickness 0.0254)
		(filled_areas_thickness no)
		(fill yes
			(thermal_gap 0.5)
			(thermal_bridge_width 0.5)
			(island_removal_mode 1)
			(island_area_min 10)
		)
		(polygon
			(pts
				(xy 138.617515 139.099127) (xy 138.571819 139.046618) (xy 138.545231 139.000623) (xy 138.524847 138.914175)
				(xy 138.523011 138.89884) (xy 138.510677 138.816105) (xy 138.289293 138.859293) (xy 138.246105 139.080677)
				(xy 138.32884 139.093011) (xy 138.426119 139.113349) (xy 138.474159 139.140057) (xy 138.529127 139.187515)
			)
		)
	)
	(zone
		(net 1)
		(net_name "GND")
		(layer "B.Cu")
		(name "$teardrop_padvia$")
		(hatch none 0.1)
		(priority 30258)
		(attr
			(teardrop
				(type padvia)
			)
		)
		(connect_pads yes
			(clearance 0)
		)
		(min_thickness 0.0254)
		(filled_areas_thickness no)
		(fill yes
			(thermal_gap 0.5)
			(thermal_bridge_width 0.5)
			(island_removal_mode 1)
			(island_area_min 10)
		)
		(polygon
			(pts
				(xy 176.779323 96.51) (xy 176.9369 96.516932) (xy 177.050434 96.545456) (xy 177.092222 96.5625)
				(xy 177.181 96.36) (xy 177.092222 96.1575) (xy 176.996177 96.191883) (xy 176.894296 96.207101) (xy 176.779323 96.21)
			)
		)
	)
	(zone
		(net 2)
		(net_name "+3V3")
		(layer "B.Cu")
		(name "$teardrop_padvia$")
		(hatch none 0.1)
		(priority 30803)
		(attr
			(teardrop
				(type padvia)
			)
		)
		(connect_pads yes
			(clearance 0)
		)
		(min_thickness 0.0254)
		(filled_areas_thickness no)
		(fill yes
			(thermal_gap 0.5)
			(thermal_bridge_width 0.5)
			(island_removal_mode 1)
			(island_area_min 10)
		)
		(polygon
			(pts
				(xy 192.939072 139.62193) (xy 192.984459 139.674123) (xy 193.01088 139.719903) (xy 193.03103 139.805962)
				(xy 193.032865 139.821726) (xy 193.045203 139.905659) (xy 193.266587 139.862471) (xy 193.309775 139.641087)
				(xy 193.228261 139.628765) (xy 193.130675 139.608061) (xy 193.082568 139.581189) (xy 193.02746 139.533542)
			)
		)
	)
	(zone
		(net 1)
		(net_name "GND")
		(layer "B.Cu")
		(name "$teardrop_padvia$")
		(hatch none 0.1)
		(priority 30614)
		(attr
			(teardrop
				(type padvia)
			)
		)
		(connect_pads yes
			(clearance 0)
		)
		(min_thickness 0.0254)
		(filled_areas_thickness no)
		(fill yes
			(thermal_gap 0.5)
			(thermal_bridge_width 0.5)
			(island_removal_mode 1)
			(island_area_min 10)
		)
		(polygon
			(pts
				(xy 311.076851 120.9725) (xy 311.153996 120.977144) (xy 311.212103 120.989655) (xy 311.293125 121.023974)
				(xy 311.410769 121.072254) (xy 311.475999 120.86) (xy 311.349996 120.672919) (xy 311.274073 120.740724)
				(xy 311.25933 120.757582) (xy 311.19124 120.821108) (xy 311.143466 120.840413) (xy 311.076851 120.8475)
			)
		)
	)
	(zone
		(net 294)
		(net_name "/2xUSB3.0+RJ45/GbE.MDI0-")
		(layer "B.Cu")
		(name "$teardrop_padvia$")
		(hatch none 0.1)
		(priority 30646)
		(attr
			(teardrop
				(type padvia)
			)
		)
		(connect_pads yes
			(clearance 0)
		)
		(min_thickness 0.0254)
		(filled_areas_thickness no)
		(fill yes
			(thermal_gap 0.5)
			(thermal_bridge_width 0.5)
			(island_removal_mode 1)
			(island_area_min 10)
		)
		(polygon
			(pts
				(xy 164.45 150.142084) (xy 164.454756 150.102162) (xy 164.46805 150.073745) (xy 164.512129 150.041329)
				(xy 164.557262 150.02605) (xy 164.603541 150.010756) (xy 164.650003 149.987081) (xy 164.525 149.799)
				(xy 164.304323 149.798242) (xy 164.302203 149.936699) (xy 164.3 150.142084)
			)
		)
	)
	(zone
		(net 707)
		(net_name "Net-(U24-TACH3)")
		(layer "B.Cu")
		(name "$teardrop_padvia$")
		(hatch none 0.1)
		(priority 30612)
		(attr
			(teardrop
				(type padvia)
			)
		)
		(connect_pads yes
			(clearance 0)
		)
		(min_thickness 0.0254)
		(filled_areas_thickness no)
		(fill yes
			(thermal_gap 0.5)
			(thermal_bridge_width 0.5)
			(island_removal_mode 1)
			(island_area_min 10)
		)
		(polygon
			(pts
				(xy 260.441851 84.4725) (xy 260.497624 84.477238) (xy 260.540063 84.490402) (xy 260.600145 84.535325)
				(xy 260.624331 84.562417) (xy 260.663059 84.604633) (xy 260.714997 84.64708) (xy 260.841 84.459999)
				(xy 260.775769 84.247745) (xy 260.658123 84.296026) (xy 260.570494 84.332294) (xy 260.441851 84.3475)
			)
		)
	)
	(zone
		(net 622)
		(net_name "/PCIe misc/DIF5-")
		(layer "B.Cu")
		(name "$teardrop_padvia$")
		(hatch none 0.1)
		(priority 30507)
		(attr
			(teardrop
				(type padvia)
			)
		)
		(connect_pads yes
			(clearance 0)
		)
		(min_thickness 0.0254)
		(filled_areas_thickness no)
		(fill yes
			(thermal_gap 0.5)
			(thermal_bridge_width 0.5)
			(island_removal_mode 1)
			(island_area_min 10)
		)
		(polygon
			(pts
				(xy 220.735562 127.3795) (xy 220.688776 127.374765) (xy 220.653324 127.361621) (xy 220.605126 127.316613)
				(xy 220.58095 127.278392) (xy 220.55358 127.235225) (xy 220.516918 127.193268) (xy 220.367066 127.3565)
				(xy 220.387926 127.577177) (xy 220.488597 127.572548) (xy 220.571963 127.57598) (xy 220.57403 127.576105)
				(xy 220.735562 127.5815)
			)
		)
	)
	(zone
		(net 1)
		(net_name "GND")
		(layer "B.Cu")
		(name "$teardrop_padvia$")
		(hatch none 0.1)
		(priority 30335)
		(attr
			(teardrop
				(type padvia)
			)
		)
		(connect_pads yes
			(clearance 0)
		)
		(min_thickness 0.0254)
		(filled_areas_thickness no)
		(fill yes
			(thermal_gap 0.5)
			(thermal_bridge_width 0.5)
			(island_removal_mode 1)
			(island_area_min 10)
		)
		(polygon
			(pts
				(xy 147.612 169.7025) (xy 147.674866 169.722469) (xy 147.706844 169.748921) (xy 147.735358 169.786332)
				(xy 147.757882 169.833527) (xy 147.773093 169.891167) (xy 147.773202 169.891798) (xy 148.051 169.64)
				(xy 147.773202 169.388202) (xy 147.758905 169.443635) (xy 147.737825 169.48952) (xy 147.71046 169.527201)
				(xy 147.679552 169.554434) (xy 147.646265 169.571472) (xy 147.613434 169.577489) (xy 147.612 169.5775)
			)
		)
	)
	(zone
		(net 105)
		(net_name "/PCIe redriver/PCIe_{I}_C.RX2-")
		(layer "B.Cu")
		(name "$teardrop_padvia$")
		(hatch none 0.1)
		(priority 30195)
		(attr
			(teardrop
				(type padvia)
			)
		)
		(connect_pads yes
			(clearance 0)
		)
		(min_thickness 0.0254)
		(filled_areas_thickness no)
		(fill yes
			(thermal_gap 0.5)
			(thermal_bridge_width 0.5)
			(island_removal_mode 1)
			(island_area_min 10)
		)
		(polygon
			(pts
				(xy 195.537849 138.825182) (xy 195.611592 138.844053) (xy 195.694359 138.877824) (xy 195.762945 138.917923)
				(xy 195.826384 138.969985) (xy 195.884152 139.042083) (xy 196.086529 138.791912) (xy 195.945538 138.514295)
				(xy 195.859349 138.604581) (xy 195.785755 138.660577) (xy 195.743273 138.678941) (xy 195.702356 138.684499)
				(xy 195.680685 138.682348)
			)
		)
	)
	(zone
		(net 539)
		(net_name "/Misc/~{PWR_OK}")
		(layer "B.Cu")
		(name "$teardrop_padvia$")
		(hatch none 0.1)
		(priority 30129)
		(attr
			(teardrop
				(type padvia)
			)
		)
		(connect_pads yes
			(clearance 0)
		)
		(min_thickness 0.0254)
		(filled_areas_thickness no)
		(fill yes
			(thermal_gap 0.5)
			(thermal_bridge_width 0.5)
			(island_removal_mode 1)
			(island_area_min 10)
		)
		(polygon
			(pts
				(xy 98.7635 73.58) (xy 98.783221 73.52274) (xy 98.846033 73.470216) (xy 98.894653 73.450449) (xy 98.953951 73.437923)
				(xy 98.971 73.436072) (xy 98.701 72.959) (xy 98.431 73.436072) (xy 98.492244 73.446248) (xy 98.543171 73.463925)
				(xy 98.584014 73.487823) (xy 98.613697 73.516022) (xy 98.63163 73.546012) (xy 98.638441 73.576862)
				(xy 98.6385 73.58)
			)
		)
	)
	(zone
		(net 655)
		(net_name "Net-(U43C-PRTAD0)")
		(layer "B.Cu")
		(name "$teardrop_padvia$")
		(hatch none 0.1)
		(priority 30371)
		(attr
			(teardrop
				(type padvia)
			)
		)
		(connect_pads yes
			(clearance 0)
		)
		(min_thickness 0.0254)
		(filled_areas_thickness no)
		(fill yes
			(thermal_gap 0.5)
			(thermal_bridge_width 0.5)
			(island_removal_mode 1)
			(island_area_min 10)
		)
		(polygon
			(pts
				(xy 157.3575 141.922) (xy 157.337531 141.984866) (xy 157.311079 142.016844) (xy 157.273668 142.045358)
				(xy 157.226473 142.067882) (xy 157.168833 142.083093) (xy 157.168202 142.083202) (xy 157.42 142.361)
				(xy 157.671798 142.083202) (xy 157.616365 142.068905) (xy 157.57048 142.047825) (xy 157.532799 142.02046)
				(xy 157.505566 141.989552) (xy 157.488528 141.956265) (xy 157.482511 141.923434) (xy 157.4825 141.922)
			)
		)
	)
	(zone
		(net 2)
		(net_name "+3V3")
		(layer "B.Cu")
		(name "$teardrop_padvia$")
		(hatch none 0.1)
		(priority 30795)
		(attr
			(teardrop
				(type padvia)
			)
		)
		(connect_pads yes
			(clearance 0)
		)
		(min_thickness 0.0254)
		(filled_areas_thickness no)
		(fill yes
			(thermal_gap 0.5)
			(thermal_bridge_width 0.5)
			(island_removal_mode 1)
			(island_area_min 10)
		)
		(polygon
			(pts
				(xy 114.4635 145.220677) (xy 114.468313 145.151677) (xy 114.482002 145.100623) (xy 114.528606 145.025522)
				(xy 114.538456 145.013077) (xy 114.589081 144.945003) (xy 114.402 144.819) (xy 114.214919 144.945003)
				(xy 114.263846 145.011356) (xy 114.318209 145.094999) (xy 114.333224 145.148018) (xy 114.3385 145.220677)
			)
		)
	)
	(zone
		(net 574)
		(net_name "Net-(U19-EN)")
		(layer "B.Cu")
		(name "$teardrop_padvia$")
		(hatch none 0.1)
		(priority 30200)
		(attr
			(teardrop
				(type padvia)
			)
		)
		(connect_pads yes
			(clearance 0)
		)
		(min_thickness 0.0254)
		(filled_areas_thickness no)
		(fill yes
			(thermal_gap 0.5)
			(thermal_bridge_width 0.5)
			(island_removal_mode 1)
			(island_area_min 10)
		)
		(polygon
			(pts
				(xy 309.235437 101.56205) (xy 309.179806 101.478082) (xy 309.158417 101.417847) (xy 309.144927 101.348938)
				(xy 309.144999 101.209441) (xy 308.824292 101.279293) (xy 308.757073 101.575) (xy 308.847839 101.566406)
				(xy 308.931198 101.56817) (xy 309.004176 101.579316) (xy 309.067262 101.599181) (xy 309.147049 101.650438)
			)
		)
	)
	(zone
		(net 771)
		(net_name "/Backplane/PCIe_{x2}.RX1+")
		(layer "B.Cu")
		(name "$teardrop_padvia$")
		(hatch none 0.1)
		(priority 30538)
		(attr
			(teardrop
				(type padvia)
			)
		)
		(connect_pads yes
			(clearance 0)
		)
		(min_thickness 0.0254)
		(filled_areas_thickness no)
		(fill yes
			(thermal_gap 0.5)
			(thermal_bridge_width 0.5)
			(island_removal_mode 1)
			(island_area_min 10)
		)
		(polygon
			(pts
				(xy 269.832504 159.9065) (xy 269.994035 159.901105) (xy 270.078445 159.897554) (xy 270.18014 159.902177)
				(xy 270.201 159.6815) (xy 270.051147 159.518268) (xy 269.997007 159.586935) (xy 269.987115 159.603393)
				(xy 269.962615 159.642065) (xy 269.933109 159.674279) (xy 269.891953 159.696327) (xy 269.832504 159.7045)
			)
		)
	)
	(zone
		(net 2)
		(net_name "+3V3")
		(layer "B.Cu")
		(name "$teardrop_padvia$")
		(hatch none 0.1)
		(priority 30206)
		(attr
			(teardrop
				(type padvia)
			)
		)
		(connect_pads yes
			(clearance 0)
		)
		(min_thickness 0.0254)
		(filled_areas_thickness no)
		(fill yes
			(thermal_gap 0.5)
			(thermal_bridge_width 0.5)
			(island_removal_mode 1)
			(island_area_min 10)
		)
		(polygon
			(pts
				(xy 116.888 70.19) (xy 116.87113 70.190338) (xy 116.826174 70.189759) (xy 116.778831 70.177941)
				(xy 116.736427 70.143362) (xy 116.706292 70.0745) (xy 116.449 70.34) (xy 116.706292 70.6055) (xy 116.721849 70.560731)
				(xy 116.742565 70.529115) (xy 116.793701 70.496381) (xy 116.87113 70.489662) (xy 116.888 70.49)
			)
		)
	)
	(zone
		(net 52)
		(net_name "+5V")
		(layer "B.Cu")
		(name "$teardrop_padvia$")
		(hatch none 0.1)
		(priority 30034)
		(attr
			(teardrop
				(type padvia)
			)
		)
		(connect_pads yes
			(clearance 0)
		)
		(min_thickness 0.0254)
		(filled_areas_thickness no)
		(fill yes
			(thermal_gap 0.5)
			(thermal_bridge_width 0.5)
			(island_removal_mode 1)
			(island_area_min 10)
		)
		(polygon
			(pts
				(xy 105.22531 152.178863) (xy 105.228181 152.181733) (xy 105.333882 152.292862) (xy 105.438683 152.435748)
				(xy 105.482498 152.521058) (xy 105.516188 152.616656) (xy 105.536456 152.723326) (xy 105.54 152.841851)
				(xy 106.140707 152.650707) (xy 106.218085 152) (xy 106.130463 152.018318) (xy 106.049179 152.025812)
				(xy 105.900341 152.012415) (xy 105.766798 151.964879) (xy 105.645087 151.885411) (xy 105.578863 151.82531)
			)
		)
	)
	(zone
		(net 377)
		(net_name "/Com Express 7 Interfaces/USB1.D-")
		(layer "B.Cu")
		(name "$teardrop_padvia$")
		(hatch none 0.1)
		(priority 30593)
		(attr
			(teardrop
				(type padvia)
			)
		)
		(connect_pads yes
			(clearance 0)
		)
		(min_thickness 0.0254)
		(filled_areas_thickness no)
		(fill yes
			(thermal_gap 0.5)
			(thermal_bridge_width 0.5)
			(island_removal_mode 1)
			(island_area_min 10)
		)
		(polygon
			(pts
				(xy 159.009584 71.8975) (xy 158.845141 71.901684) (xy 158.662438 71.901823) (xy 158.649 72.1225)
				(xy 158.802895 72.281688) (xy 158.851774 72.214162) (xy 158.865148 72.18782) (xy 158.886523 72.147557)
				(xy 158.913231 72.113998) (xy 158.952007 72.091021) (xy 159.009584 72.0825)
			)
		)
	)
	(zone
		(net 2)
		(net_name "+3V3")
		(layer "B.Cu")
		(name "$teardrop_padvia$")
		(hatch none 0.1)
		(priority 30675)
		(attr
			(teardrop
				(type padvia)
			)
		)
		(connect_pads yes
			(clearance 0)
		)
		(min_thickness 0.0254)
		(filled_areas_thickness no)
		(fill yes
			(thermal_gap 0.5)
			(thermal_bridge_width 0.5)
			(island_removal_mode 1)
			(island_area_min 10)
		)
		(polygon
			(pts
				(xy 123.9425 106.901296) (xy 123.933177 106.556909) (xy 123.7125 106.569) (xy 123.587497 106.757081)
				(xy 123.659746 106.786831) (xy 123.702021 106.795296) (xy 123.746674 106.804641) (xy 123.783413 106.820561)
				(xy 123.808326 106.850348) (xy 123.8175 106.901296)
			)
		)
	)
	(zone
		(net 64)
		(net_name "Net-(U19-V_{CC})")
		(layer "B.Cu")
		(name "$teardrop_padvia$")
		(hatch none 0.1)
		(priority 30387)
		(attr
			(teardrop
				(type padvia)
			)
		)
		(connect_pads yes
			(clearance 0)
		)
		(min_thickness 0.0254)
		(filled_areas_thickness no)
		(fill yes
			(thermal_gap 0.5)
			(thermal_bridge_width 0.5)
			(island_removal_mode 1)
			(island_area_min 10)
		)
		(polygon
			(pts
				(xy 311.712999 106.5675) (xy 311.650133 106.547531) (xy 311.618155 106.521079) (xy 311.589641 106.483668)
				(xy 311.567117 106.436473) (xy 311.551906 106.378833) (xy 311.551797 106.378202) (xy 311.273999 106.63)
				(xy 311.551797 106.881798) (xy 311.566094 106.826365) (xy 311.587174 106.78048) (xy 311.614539 106.742799)
				(xy 311.645447 106.715566) (xy 311.678734 106.698528) (xy 311.711565 106.692511) (xy 311.712999 106.6925)
			)
		)
	)
	(zone
		(net 539)
		(net_name "/Misc/~{PWR_OK}")
		(layer "B.Cu")
		(name "$teardrop_padvia$")
		(hatch none 0.1)
		(priority 30126)
		(attr
			(teardrop
				(type padvia)
			)
		)
		(connect_pads yes
			(clearance 0)
		)
		(min_thickness 0.0254)
		(filled_areas_thickness no)
		(fill yes
			(thermal_gap 0.5)
			(thermal_bridge_width 0.5)
			(island_removal_mode 1)
			(island_area_min 10)
		)
		(polygon
			(pts
				(xy 101.113 71.43) (xy 101.132721 71.37274) (xy 101.195533 71.320216) (xy 101.244153 71.300449)
				(xy 101.303451 71.287923) (xy 101.3205 71.286072) (xy 101.0505 70.809) (xy 100.7805 71.286072) (xy 100.841744 71.296248)
				(xy 100.892671 71.313925) (xy 100.933514 71.337823) (xy 100.963197 71.366022) (xy 100.98113 71.396012)
				(xy 100.987941 71.426862) (xy 100.988 71.43)
			)
		)
	)
	(zone
		(net 78)
		(net_name "+1V8")
		(layer "B.Cu")
		(name "$teardrop_padvia$")
		(hatch none 0.1)
		(priority 30460)
		(attr
			(teardrop
				(type padvia)
			)
		)
		(connect_pads yes
			(clearance 0)
		)
		(min_thickness 0.0254)
		(filled_areas_thickness no)
		(fill yes
			(thermal_gap 0.5)
			(thermal_bridge_width 0.5)
			(island_removal_mode 1)
			(island_area_min 10)
		)
		(polygon
			(pts
				(xy 143.713078 135.671466) (xy 143.710739 135.694498) (xy 143.698602 135.714961) (xy 143.64144 135.75125)
				(xy 143.518202 135.783202) (xy 143.770707 136.060707) (xy 144.021798 135.783202) (xy 143.927925 135.749017)
				(xy 143.849701 135.68331) (xy 143.821416 135.641962) (xy 143.804861 135.601041) (xy 143.801466 135.583078)
			)
		)
	)
	(zone
		(net 698)
		(net_name "Net-(U5-IO0_7)")
		(layer "B.Cu")
		(name "$teardrop_padvia$")
		(hatch none 0.1)
		(priority 30082)
		(attr
			(teardrop
				(type padvia)
			)
		)
		(connect_pads yes
			(clearance 0)
		)
		(min_thickness 0.0254)
		(filled_areas_thickness no)
		(fill yes
			(thermal_gap 0.5)
			(thermal_bridge_width 0.5)
			(island_removal_mode 1)
			(island_area_min 10)
		)
		(polygon
			(pts
				(xy 158.8125 163.095966) (xy 158.817308 163.031918) (xy 158.830965 162.980437) (xy 158.877598 162.908999)
				(xy 158.955502 162.85407) (xy 158.998608 162.831613) (xy 159.098248 162.775242) (xy 159.147128 162.73684)
				(xy 159.193009 162.68713) (xy 158.9 162.459) (xy 158.534499 162.538696) (xy 158.584483 162.698318)
				(xy 158.612106 162.760217) (xy 158.66478 162.895912) (xy 158.681336 162.982961) (xy 158.6875 163.095966)
			)
		)
	)
	(zone
		(net 2)
		(net_name "+3V3")
		(layer "B.Cu")
		(name "$teardrop_padvia$")
		(hatch none 0.1)
		(priority 30894)
		(attr
			(teardrop
				(type padvia)
			)
		)
		(connect_pads yes
			(clearance 0)
		)
		(min_thickness 0.0254)
		(filled_areas_thickness no)
		(fill yes
			(thermal_gap 0.5)
			(thermal_bridge_width 0.5)
			(island_removal_mode 1)
			(island_area_min 10)
		)
		(polygon
			(pts
				(xy 196.233607 136.377143) (xy 196.229169 136.372836) (xy 196.205522 136.341243) (xy 196.203441 136.317981)
				(xy 196.215522 136.288126) (xy 195.844699 136.075208) (xy 196.054644 136.44544) (xy 196.081702 136.434515)
				(xy 196.103477 136.434995) (xy 196.140721 136.46089) (xy 196.14522 136.46553)
			)
		)
	)
	(zone
		(net 78)
		(net_name "+1V8")
		(layer "B.Cu")
		(name "$teardrop_padvia$")
		(hatch none 0.1)
		(priority 30722)
		(attr
			(teardrop
				(type padvia)
			)
		)
		(connect_pads yes
			(clearance 0)
		)
		(min_thickness 0.0254)
		(filled_areas_thickness no)
		(fill yes
			(thermal_gap 0.5)
			(thermal_bridge_width 0.5)
			(island_removal_mode 1)
			(island_area_min 10)
		)
		(polygon
			(pts
				(xy 140.2825 140.760677) (xy 140.287318 140.691236) (xy 140.30104 140.639912) (xy 140.347755 140.56437)
				(xy 140.357299 140.552229) (xy 140.407081 140.485003) (xy 140.22 140.359) (xy 140.032919 140.485003)
				(xy 140.082701 140.552231) (xy 140.137106 140.635397) (xy 140.15219 140.688251) (xy 140.1575 140.760677)
			)
		)
	)
	(zone
		(net 895)
		(net_name "Net-(J2B-RS0)")
		(layer "B.Cu")
		(name "$teardrop_padvia$")
		(hatch none 0.1)
		(priority 30435)
		(attr
			(teardrop
				(type padvia)
			)
		)
		(connect_pads yes
			(clearance 0)
		)
		(min_thickness 0.0254)
		(filled_areas_thickness no)
		(fill yes
			(thermal_gap 0.5)
			(thermal_bridge_width 0.5)
			(island_removal_mode 1)
			(island_area_min 10)
		)
		(polygon
			(pts
				(xy 138.9875 168.267) (xy 138.967727 168.326412) (xy 138.904453 168.382496) (xy 138.855828 168.404198)
				(xy 138.796469 168.418872) (xy 138.7845 168.420652) (xy 139.05 168.681) (xy 139.3155 168.420652)
				(xy 139.255362 168.407803) (xy 139.205478 168.387869) (xy 139.165358 168.361944) (xy 139.136345 168.332124)
				(xy 139.118854 168.300706) (xy 139.112521 168.268895) (xy 139.1125 168.267)
			)
		)
	)
	(zone
		(net 632)
		(net_name "Net-(U40-EN_{I2C})")
		(layer "B.Cu")
		(name "$teardrop_padvia$")
		(hatch none 0.1)
		(priority 30933)
		(attr
			(teardrop
				(type padvia)
			)
		)
		(connect_pads yes
			(clearance 0)
		)
		(min_thickness 0.0254)
		(filled_areas_thickness no)
		(fill yes
			(thermal_gap 0.5)
			(thermal_bridge_width 0.5)
			(island_removal_mode 1)
			(island_area_min 10)
		)
		(polygon
			(pts
				(xy 197.558727 132.94626) (xy 197.554127 132.951005) (xy 197.521677 132.975658) (xy 197.497875 132.97847)
				(xy 197.467384 132.96735) (xy 197.258913 133.33729) (xy 197.631479 133.115612) (xy 197.619278 133.090723)
				(xy 197.619223 133.07092) (xy 197.641836 133.039647) (xy 197.647114 133.034647)
			)
		)
	)
	(zone
		(net 156)
		(net_name "Net-(J1A-LED_D3)")
		(layer "B.Cu")
		(name "$teardrop_padvia$")
		(hatch none 0.1)
		(priority 30383)
		(attr
			(teardrop
				(type padvia)
			)
		)
		(connect_pads yes
			(clearance 0)
		)
		(min_thickness 0.0254)
		(filled_areas_thickness no)
		(fill yes
			(thermal_gap 0.5)
			(thermal_bridge_width 0.5)
			(island_removal_mode 1)
			(island_area_min 10)
		)
		(polygon
			(pts
				(xy 122.8575 109.372) (xy 122.837531 109.434866) (xy 122.811079 109.466844) (xy 122.773668 109.495358)
				(xy 122.726473 109.517882) (xy 122.668833 109.533093) (xy 122.668202 109.533202) (xy 122.92 109.811)
				(xy 123.171798 109.533202) (xy 123.116365 109.518905) (xy 123.07048 109.497825) (xy 123.032799 109.47046)
				(xy 123.005566 109.439552) (xy 122.988528 109.406265) (xy 122.982511 109.373434) (xy 122.9825 109.372)
			)
		)
	)
	(zone
		(net 121)
		(net_name "/2xSFP+/10GKR_SFP1.TX-")
		(layer "B.Cu")
		(name "$teardrop_padvia$")
		(hatch none 0.1)
		(priority 30872)
		(attr
			(teardrop
				(type padvia)
			)
		)
		(connect_pads yes
			(clearance 0)
		)
		(min_thickness 0.0254)
		(filled_areas_thickness no)
		(fill yes
			(thermal_gap 0.5)
			(thermal_bridge_width 0.5)
			(island_removal_mode 1)
			(island_area_min 10)
		)
		(polygon
			(pts
				(xy 197.045 152.854438) (xy 197.049662 152.833006) (xy 197.062295 152.822602) (xy 197.105777 152.821029)
				(xy 197.153895 152.820677) (xy 197.11 152.599) (xy 196.889323 152.577553) (xy 196.883598 152.749628)
				(xy 196.885 152.854438)
			)
		)
	)
	(zone
		(net 652)
		(net_name "/2xSFP+/KR to SFI #1/PRBSEN")
		(layer "B.Cu")
		(name "$teardrop_padvia$")
		(hatch none 0.1)
		(priority 30448)
		(attr
			(teardrop
				(type padvia)
			)
		)
		(connect_pads yes
			(clearance 0)
		)
		(min_thickness 0.0254)
		(filled_areas_thickness no)
		(fill yes
			(thermal_gap 0.5)
			(thermal_bridge_width 0.5)
			(island_removal_mode 1)
			(island_area_min 10)
		)
		(polygon
			(pts
				(xy 157.007 138.4225) (xy 157.066412 138.442273) (xy 157.122497 138.505547) (xy 157.144199 138.554172)
				(xy 157.158873 138.613531) (xy 157.160653 138.6255) (xy 157.421 138.36) (xy 157.160653 138.0945)
				(xy 157.147804 138.154638) (xy 157.12787 138.204522) (xy 157.101945 138.244641) (xy 157.072125 138.273654)
				(xy 157.040707 138.291146) (xy 157.008896 138.297479) (xy 157.007 138.2975)
			)
		)
	)
	(zone
		(net 189)
		(net_name "/OCuLink/PCIe_{x4}.RX1-")
		(layer "B.Cu")
		(name "$teardrop_padvia$")
		(hatch none 0.1)
		(priority 30847)
		(attr
			(teardrop
				(type padvia)
			)
		)
		(connect_pads yes
			(clearance 0)
		)
		(min_thickness 0.0254)
		(filled_areas_thickness no)
		(fill yes
			(thermal_gap 0.5)
			(thermal_bridge_width 0.5)
			(island_removal_mode 1)
			(island_area_min 10)
		)
		(polygon
			(pts
				(xy 192.649991 133.80893) (xy 192.741798 133.876087) (xy 192.844773 133.948299) (xy 192.896304 133.99706)
				(xy 192.944396 134.058787) (xy 193.106075 134.04369) (xy 192.840987 133.688905) (xy 192.819727 133.70386)
				(xy 192.807449 133.70066) (xy 192.798626 133.68032) (xy 192.792826 133.666095)
			)
		)
	)
	(zone
		(net 103)
		(net_name "/PCIe redriver/PCIe_{I}_C.RX1-")
		(layer "B.Cu")
		(name "$teardrop_padvia$")
		(hatch none 0.1)
		(priority 30883)
		(attr
			(teardrop
				(type padvia)
			)
		)
		(connect_pads yes
			(clearance 0)
		)
		(min_thickness 0.0254)
		(filled_areas_thickness no)
		(fill yes
			(thermal_gap 0.5)
			(thermal_bridge_width 0.5)
			(island_removal_mode 1)
			(island_area_min 10)
		)
		(polygon
			(pts
				(xy 195.907985 136.702765) (xy 195.888294 136.693254) (xy 195.858646 136.677173) (xy 195.853558 136.66243)
				(xy 195.861673 136.640188) (xy 195.491146 136.428761) (xy 195.702573 136.799288) (xy 195.724424 136.791191)
				(xy 195.739049 136.795839) (xy 195.755639 136.825909) (xy 195.76515 136.8456)
			)
		)
	)
	(zone
		(net 91)
		(net_name "/Com Express 7 Interfaces/PCIe_{B2Ax4}.RX1+")
		(layer "B.Cu")
		(name "$teardrop_padvia$")
		(hatch none 0.1)
		(priority 30540)
		(attr
			(teardrop
				(type padvia)
			)
		)
		(connect_pads yes
			(clearance 0)
		)
		(min_thickness 0.0254)
		(filled_areas_thickness no)
		(fill yes
			(thermal_gap 0.5)
			(thermal_bridge_width 0.5)
			(island_removal_mode 1)
			(island_area_min 10)
		)
		(polygon
			(pts
				(xy 212.593744 160.925973) (xy 212.475707 160.815566) (xy 212.41351 160.75839) (xy 212.34487 160.683214)
				(xy 212.174079 160.824507) (xy 212.164619 161.045891) (xy 212.251457 161.035617) (xy 212.270087 161.030976)
				(xy 212.314757 161.020954) (xy 212.358399 161.019039) (xy 212.403091 161.032551) (xy 212.450908 161.068809)
			)
		)
	)
	(zone
		(net 200)
		(net_name "/OCuLink/~{PERST_D0}")
		(layer "B.Cu")
		(name "$teardrop_padvia$")
		(hatch none 0.1)
		(priority 30745)
		(attr
			(teardrop
				(type padvia)
			)
		)
		(connect_pads yes
			(clearance 0)
		)
		(min_thickness 0.0254)
		(filled_areas_thickness no)
		(fill yes
			(thermal_gap 0.5)
			(thermal_bridge_width 0.5)
			(island_removal_mode 1)
			(island_area_min 10)
		)
		(polygon
			(pts
				(xy 104.020677 162.0575) (xy 103.951236 162.052682) (xy 103.899913 162.03896) (xy 103.824371 161.992246)
				(xy 103.812231 161.982701) (xy 103.745003 161.932919) (xy 103.619 162.12) (xy 103.745003 162.307081)
				(xy 103.812229 162.257299) (xy 103.895396 162.202894) (xy 103.948251 162.18781) (xy 104.020677 162.1825)
			)
		)
	)
	(zone
		(net 969)
		(net_name "/M.2 key M #1/M2_3V3")
		(layer "B.Cu")
		(name "$teardrop_padvia$")
		(hatch none 0.1)
		(priority 30275)
		(attr
			(teardrop
				(type padvia)
			)
		)
		(connect_pads yes
			(clearance 0)
		)
		(min_thickness 0.0254)
		(filled_areas_thickness no)
		(fill yes
			(thermal_gap 0.5)
			(thermal_bridge_width 0.5)
			(island_removal_mode 1)
			(island_area_min 10)
		)
		(polygon
			(pts
				(xy 178.260676 110.46) (xy 178.103105 110.453069) (xy 177.989577 110.424549) (xy 177.947777 110.4075)
				(xy 177.858999 110.61) (xy 177.947777 110.8125) (xy 178.043816 110.778118) (xy 178.145688 110.7629)
				(xy 178.260676 110.76)
			)
		)
	)
	(zone
		(net 2)
		(net_name "+3V3")
		(layer "B.Cu")
		(name "$teardrop_padvia$")
		(hatch none 0.1)
		(priority 30924)
		(attr
			(teardrop
				(type padvia)
			)
		)
		(connect_pads yes
			(clearance 0)
		)
		(min_thickness 0.0254)
		(filled_areas_thickness no)
		(fill yes
			(thermal_gap 0.5)
			(thermal_bridge_width 0.5)
			(island_removal_mode 1)
			(island_area_min 10)
		)
		(polygon
			(pts
				(xy 118.8375 145.1855) (xy 118.837599 145.191963) (xy 118.83205 145.231906) (xy 118.817161 145.250428)
				(xy 118.787659 145.263752) (xy 118.901 145.674) (xy 119.012655 145.261231) (xy 118.985524 145.25041)
				(xy 118.97038 145.235092) (xy 118.962407 145.191683) (xy 118.9625 145.1855)
			)
		)
	)
	(zone
		(net 365)
		(net_name "/Com Express 7 MGMT/PWR_OK")
		(layer "B.Cu")
		(name "$teardrop_padvia$")
		(hatch none 0.1)
		(priority 30685)
		(attr
			(teardrop
				(type padvia)
			)
		)
		(connect_pads yes
			(clearance 0)
		)
		(min_thickness 0.0254)
		(filled_areas_thickness no)
		(fill yes
			(thermal_gap 0.5)
			(thermal_bridge_width 0.5)
			(island_removal_mode 1)
			(island_area_min 10)
		)
		(polygon
			(pts
				(xy 187.4875 163.899323) (xy 187.482682 163.968763) (xy 187.46896 164.020087) (xy 187.422245 164.095628)
				(xy 187.412702 164.107768) (xy 187.362919 164.174997) (xy 187.55 164.301) (xy 187.737081 164.174997)
				(xy 187.687299 164.107769) (xy 187.632894 164.024603) (xy 187.61781 163.971748) (xy 187.6125 163.899323)
			)
		)
	)
	(zone
		(net 53)
		(net_name "/2xSFP+/SH")
		(layer "B.Cu")
		(name "$teardrop_padvia$")
		(hatch none 0.1)
		(priority 30240)
		(attr
			(teardrop
				(type padvia)
			)
		)
		(connect_pads yes
			(clearance 0)
		)
		(min_thickness 0.0254)
		(filled_areas_thickness no)
		(fill yes
			(thermal_gap 0.5)
			(thermal_bridge_width 0.5)
			(island_removal_mode 1)
			(island_area_min 10)
		)
		(polygon
			(pts
				(xy 132.3 156.247) (xy 132.300337 156.26209) (xy 132.29976 156.302326) (xy 132.287946 156.34387)
				(xy 132.253367 156.379164) (xy 132.1845 156.400652) (xy 132.45 156.661) (xy 132.7155 156.400652)
				(xy 132.669062 156.389708) (xy 132.636865 156.372609) (xy 132.605422 156.328144) (xy 132.599663 156.26209)
				(xy 132.6 156.247)
			)
		)
	)
	(zone
		(net 2)
		(net_name "+3V3")
		(layer "B.Cu")
		(name "$teardrop_padvia$")
		(hatch none 0.1)
		(priority 30212)
		(attr
			(teardrop
				(type padvia)
			)
		)
		(connect_pads yes
			(clearance 0)
		)
		(min_thickness 0.0254)
		(filled_areas_thickness no)
		(fill yes
			(thermal_gap 0.5)
			(thermal_bridge_width 0.5)
			(island_removal_mode 1)
			(island_area_min 10)
		)
		(polygon
			(pts
				(xy 121.938 73.94) (xy 121.92113 73.940338) (xy 121.876174 73.939759) (xy 121.828831 73.927941)
				(xy 121.786427 73.893362) (xy 121.756292 73.8245) (xy 121.499 74.09) (xy 121.756292 74.3555) (xy 121.771849 74.310731)
				(xy 121.792565 74.279115) (xy 121.843701 74.246381) (xy 121.92113 74.239662) (xy 121.938 74.24)
			)
		)
	)
	(zone
		(net 311)
		(net_name "Net-(J12D-~{THRMTRIP})")
		(layer "B.Cu")
		(name "$teardrop_padvia$")
		(hatch none 0.1)
		(priority 30105)
		(attr
			(teardrop
				(type padvia)
			)
		)
		(connect_pads yes
			(clearance 0)
		)
		(min_thickness 0.0254)
		(filled_areas_thickness no)
		(fill yes
			(thermal_gap 0.5)
			(thermal_bridge_width 0.5)
			(island_removal_mode 1)
			(island_area_min 10)
		)
		(polygon
			(pts
				(xy 187.367794 169.8375) (xy 187.285734 169.832685) (xy 187.220388 169.818981) (xy 187.127121 169.772424)
				(xy 187.048658 169.704214) (xy 186.987159 169.648058) (xy 186.908339 169.588199) (xy 186.699 169.9)
				(xy 186.908339 170.211801) (xy 187.028517 170.11478) (xy 187.048657 170.095787) (xy 187.107541 170.042634)
				(xy 187.171624 170.000409) (xy 187.254008 169.972551) (xy 187.367794 169.9625)
			)
		)
	)
	(zone
		(net 143)
		(net_name "/2xSFP+/KR to SFI #2/~{RESET}")
		(layer "B.Cu")
		(name "$teardrop_padvia$")
		(hatch none 0.1)
		(priority 30486)
		(attr
			(teardrop
				(type padvia)
			)
		)
		(connect_pads yes
			(clearance 0)
		)
		(min_thickness 0.0254)
		(filled_areas_thickness no)
		(fill yes
			(thermal_gap 0.5)
			(thermal_bridge_width 0.5)
			(island_removal_mode 1)
			(island_area_min 10)
		)
		(polygon
			(pts
				(xy 126.566819 135.594794) (xy 126.510821 135.677993) (xy 126.465418 135.718067) (xy 126.41029 135.75085)
				(xy 126.330781 135.774796) (xy 126.569293 136.060707) (xy 126.821798 135.783202) (xy 126.734811 135.763174)
				(xy 126.678188 135.738026) (xy 126.657724 135.718141) (xy 126.65206 135.695936) (xy 126.655206 135.683181)
			)
		)
	)
	(zone
		(net 156)
		(net_name "Net-(J1A-LED_D3)")
		(layer "B.Cu")
		(name "$teardrop_padvia$")
		(hatch none 0.1)
		(priority 30378)
		(attr
			(teardrop
				(type padvia)
			)
		)
		(connect_pads yes
			(clearance 0)
		)
		(min_thickness 0.0254)
		(filled_areas_thickness no)
		(fill yes
			(thermal_gap 0.5)
			(thermal_bridge_width 0.5)
			(island_removal_mode 1)
			(island_area_min 10)
		)
		(polygon
			(pts
				(xy 122.8575 110.372) (xy 122.837531 110.434866) (xy 122.811079 110.466844) (xy 122.773668 110.495358)
				(xy 122.726473 110.517882) (xy 122.668833 110.533093) (xy 122.668202 110.533202) (xy 122.92 110.811)
				(xy 123.171798 110.533202) (xy 123.116365 110.518905) (xy 123.07048 110.497825) (xy 123.032799 110.47046)
				(xy 123.005566 110.439552) (xy 122.988528 110.406265) (xy 122.982511 110.373434) (xy 122.9825 110.372)
			)
		)
	)
	(zone
		(net 975)
		(net_name "/PCIe redriver/RX_FG0")
		(layer "B.Cu")
		(name "$teardrop_padvia$")
		(hatch none 0.1)
		(priority 30601)
		(attr
			(teardrop
				(type padvia)
			)
		)
		(connect_pads yes
			(clearance 0)
		)
		(min_thickness 0.0254)
		(filled_areas_thickness no)
		(fill yes
			(thermal_gap 0.5)
			(thermal_bridge_width 0.5)
			(island_removal_mode 1)
			(island_area_min 10)
		)
		(polygon
			(pts
				(xy 192.6275 140.315402) (xy 192.615564 140.447631) (xy 192.592782 140.520084) (xy 192.551804 140.584013)
				(xy 192.907377 140.634218) (xy 192.925055 140.259444) (xy 192.8408 140.315742) (xy 192.785016 140.339513)
				(xy 192.764 140.338539) (xy 192.753706 140.325696) (xy 192.7525 140.315402)
			)
		)
	)
	(zone
		(net 715)
		(net_name "Net-(U39-~{I2C_{RESET}})")
		(layer "B.Cu")
		(name "$teardrop_padvia$")
		(hatch none 0.1)
		(priority 30098)
		(attr
			(teardrop
				(type padvia)
			)
		)
		(connect_pads yes
			(clearance 0)
		)
		(min_thickness 0.0254)
		(filled_areas_thickness no)
		(fill yes
			(thermal_gap 0.5)
			(thermal_bridge_width 0.5)
			(island_removal_mode 1)
			(island_area_min 10)
		)
		(polygon
			(pts
				(xy 122.732206 144.7225) (xy 122.814266 144.727315) (xy 122.879612 144.741019) (xy 122.972879 144.787576)
				(xy 123.051341 144.855786) (xy 123.112841 144.911942) (xy 123.191661 144.971801) (xy 123.401 144.66)
				(xy 123.191661 144.348199) (xy 123.071483 144.445219) (xy 123.051341 144.464214) (xy 122.992458 144.517366)
				(xy 122.928375 144.559592) (xy 122.845991 144.58745) (xy 122.732206 144.5975)
			)
		)
	)
	(zone
		(net 102)
		(net_name "/OCuLink/PCIe_{x4}.TX1+")
		(layer "B.Cu")
		(name "$teardrop_padvia$")
		(hatch none 0.1)
		(priority 31008)
		(attr
			(teardrop
				(type padvia)
			)
		)
		(connect_pads yes
			(clearance 0)
		)
		(min_thickness 0.0254)
		(filled_areas_thickness no)
		(fill yes
			(thermal_gap 0.5)
			(thermal_bridge_width 0.5)
			(island_removal_mode 1)
			(island_area_min 10)
		)
		(polygon
			(pts
				(xy 105.48 165.011) (xy 105.459352 165.018199) (xy 105.427017 165.027792) (xy 105.412994 165.020965)
				(xy 105.403005 164.9995) (xy 105.154 165.112) (xy 105.403005 165.2245) (xy 105.41273 165.203324)
				(xy 105.426358 165.196269) (xy 105.459352 165.205801) (xy 105.48 165.213)
			)
		)
	)
	(zone
		(net 52)
		(net_name "+5V")
		(layer "B.Cu")
		(name "$teardrop_padvia$")
		(hatch none 0.1)
		(priority 30744)
		(attr
			(teardrop
				(type padvia)
			)
		)
		(connect_pads yes
			(clearance 0)
		)
		(min_thickness 0.0254)
		(filled_areas_thickness no)
		(fill yes
			(thermal_gap 0.5)
			(thermal_bridge_width 0.5)
			(island_removal_mode 1)
			(island_area_min 10)
		)
		(polygon
			(pts
				(xy 294.500677 100.877) (xy 294.431236 100.872182) (xy 294.379913 100.85846) (xy 294.304371 100.811746)
				(xy 294.292231 100.802201) (xy 294.225003 100.752419) (xy 294.099 100.9395) (xy 294.225003 101.126581)
				(xy 294.292229 101.076799) (xy 294.375396 101.022394) (xy 294.428251 101.00731) (xy 294.500677 101.002)
			)
		)
	)
	(zone
		(net 49)
		(net_name "/2xUSB3.0+RJ45/USBSS_2.TX-")
		(layer "B.Cu")
		(name "$teardrop_padvia$")
		(hatch none 0.1)
		(priority 30581)
		(attr
			(teardrop
				(type padvia)
			)
		)
		(connect_pads yes
			(clearance 0)
		)
		(min_thickness 0.0254)
		(filled_areas_thickness no)
		(fill yes
			(thermal_gap 0.5)
			(thermal_bridge_width 0.5)
			(island_removal_mode 1)
			(island_area_min 10)
		)
		(polygon
			(pts
				(xy 126.410152 103.8345) (xy 126.454764 103.83924) (xy 126.48816 103.852418) (xy 126.531755 103.897201)
				(xy 126.554587 103.939819) (xy 126.580245 103.987662) (xy 126.61684 104.033688) (xy 126.770736 103.8745)
				(xy 126.757298 103.653823) (xy 126.574594 103.653684) (xy 126.410152 103.6495)
			)
		)
	)
	(zone
		(net 676)
		(net_name "Net-(U45C-PRTAD0)")
		(layer "B.Cu")
		(name "$teardrop_padvia$")
		(hatch none 0.1)
		(priority 30446)
		(attr
			(teardrop
				(type padvia)
			)
		)
		(connect_pads yes
			(clearance 0)
		)
		(min_thickness 0.0254)
		(filled_areas_thickness no)
		(fill yes
			(thermal_gap 0.5)
			(thermal_bridge_width 0.5)
			(island_removal_mode 1)
			(island_area_min 10)
		)
		(polygon
			(pts
				(xy 138.847 141.4225) (xy 138.906412 141.442273) (xy 138.962497 141.505547) (xy 138.984199 141.554172)
				(xy 138.998873 141.613531) (xy 139.000653 141.6255) (xy 139.261 141.36) (xy 139.000653 141.0945)
				(xy 138.987804 141.154638) (xy 138.96787 141.204522) (xy 138.941945 141.244641) (xy 138.912125 141.273654)
				(xy 138.880707 141.291146) (xy 138.848896 141.297479) (xy 138.847 141.2975)
			)
		)
	)
	(zone
		(net 45)
		(net_name "/2xUSB3.0+RJ45/USBSS_2.TX+")
		(layer "B.Cu")
		(name "$teardrop_padvia$")
		(hatch none 0.1)
		(priority 30953)
		(attr
			(teardrop
				(type padvia)
			)
		)
		(connect_pads yes
			(clearance 0)
		)
		(min_thickness 0.0254)
		(filled_areas_thickness no)
		(fill yes
			(thermal_gap 0.5)
			(thermal_bridge_width 0.5)
			(island_removal_mode 1)
			(island_area_min 10)
		)
		(polygon
			(pts
				(xy 122.688 103.4545) (xy 122.768309 103.438748) (xy 122.856167 103.419329) (xy 122.904805 103.417846)
				(xy 122.956351 103.427) (xy 123.014 103.302) (xy 122.738225 103.238366) (xy 122.733746 103.2668)
				(xy 122.722735 103.276653) (xy 122.700525 103.27278) (xy 122.688 103.2695)
			)
		)
	)
	(zone
		(net 868)
		(net_name "/Backplane/PCIe_{x2}.TX1+")
		(layer "B.Cu")
		(name "$teardrop_padvia$")
		(hatch none 0.1)
		(priority 30513)
		(attr
			(teardrop
				(type padvia)
			)
		)
		(connect_pads yes
			(clearance 0)
		)
		(min_thickness 0.0254)
		(filled_areas_thickness no)
		(fill yes
			(thermal_gap 0.5)
			(thermal_bridge_width 0.5)
			(island_removal_mode 1)
			(island_area_min 10)
		)
		(polygon
			(pts
				(xy 269.367496 140.4045) (xy 269.32071 140.399765) (xy 269.285258 140.386621) (xy 269.23706 140.341613)
				(xy 269.212884 140.303392) (xy 269.185514 140.260225) (xy 269.148852 140.218268) (xy 268.999 140.3815)
				(xy 269.01986 140.602177) (xy 269.120531 140.597548) (xy 269.203897 140.60098) (xy 269.205964 140.601105)
				(xy 269.367496 140.6065)
			)
		)
	)
	(zone
		(net 1)
		(net_name "GND")
		(layer "B.Cu")
		(name "$teardrop_padvia$")
		(hatch none 0.1)
		(priority 30465)
		(attr
			(teardrop
				(type padvia)
			)
		)
		(connect_pads yes
			(clearance 0)
		)
		(min_thickness 0.0254)
		(filled_areas_thickness no)
		(fill yes
			(thermal_gap 0.5)
			(thermal_bridge_width 0.5)
			(island_removal_mode 1)
			(island_area_min 10)
		)
		(polygon
			(pts
				(xy 143.15439 149.122031) (xy 143.209112 149.073976) (xy 143.257379 149.044097) (xy 143.356299 149.012559)
				(xy 143.450204 148.986536) (xy 143.377707 148.777293) (xy 143.174738 148.689645) (xy 143.141769 148.774908)
				(xy 143.100546 148.871282) (xy 143.066079 148.921747) (xy 143.012969 148.98061)
			)
		)
	)
	(zone
		(net 100)
		(net_name "/OCuLink/PCIe_{x4}.TX0+")
		(layer "B.Cu")
		(name "$teardrop_padvia$")
		(hatch none 0.1)
		(priority 30991)
		(attr
			(teardrop
				(type padvia)
			)
		)
		(connect_pads yes
			(clearance 0)
		)
		(min_thickness 0.0254)
		(filled_areas_thickness no)
		(fill yes
			(thermal_gap 0.5)
			(thermal_bridge_width 0.5)
			(island_removal_mode 1)
			(island_area_min 10)
		)
		(polygon
			(pts
				(xy 104.83 166.711) (xy 104.850648 166.703802) (xy 104.882984 166.694208) (xy 104.897007 166.701035)
				(xy 104.906995 166.7225) (xy 105.156 166.61) (xy 104.906995 166.4975) (xy 104.897271 166.518676)
				(xy 104.883643 166.525731) (xy 104.850648 166.516198) (xy 104.83 166.509)
			)
		)
	)
	(zone
		(net 78)
		(net_name "+1V8")
		(layer "B.Cu")
		(name "$teardrop_padvia$")
		(hatch none 0.1)
		(priority 30081)
		(attr
			(teardrop
				(type padvia)
			)
		)
		(connect_pads yes
			(clearance 0)
		)
		(min_thickness 0.0254)
		(filled_areas_thickness no)
		(fill yes
			(thermal_gap 0.5)
			(thermal_bridge_width 0.5)
			(island_removal_mode 1)
			(island_area_min 10)
		)
		(polygon
			(pts
				(xy 147.68 133.338) (xy 147.669605 133.289516) (xy 147.657682 133.24177) (xy 147.657938 133.194597)
				(xy 147.684579 133.15551) (xy 147.751808 133.132024) (xy 147.3 132.777) (xy 147.023384 133.178)
				(xy 147.089171 133.182692) (xy 147.134536 133.195533) (xy 147.16066 133.212316) (xy 147.176011 133.232784)
				(xy 147.184434 133.283836) (xy 147.182105 133.310495) (xy 147.18 133.338)
			)
		)
	)
	(zone
		(net 2)
		(net_name "+3V3")
		(layer "B.Cu")
		(name "$teardrop_padvia$")
		(hatch none 0.1)
		(priority 30459)
		(attr
			(teardrop
				(type padvia)
			)
		)
		(connect_pads yes
			(clearance 0)
		)
		(min_thickness 0.0254)
		(filled_areas_thickness no)
		(fill yes
			(thermal_gap 0.5)
			(thermal_bridge_width 0.5)
			(island_removal_mode 1)
			(island_area_min 10)
		)
		(polygon
			(pts
				(xy 193.820685 140.997055) (xy 193.802745 141.011687) (xy 193.779693 141.017574) (xy 193.713614 141.002815)
				(xy 193.603877 140.938266) (xy 193.586199 141.31304) (xy 193.959973 141.294362) (xy 193.917767 141.203811)
				(xy 193.908917 141.102036) (xy 193.918154 141.052798) (xy 193.935384 141.012157) (xy 193.945685 140.997055)
			)
		)
	)
	(zone
		(net 631)
		(net_name "Net-(U39-RXDET)")
		(layer "B.Cu")
		(name "$teardrop_padvia$")
		(hatch none 0.1)
		(priority 30891)
		(attr
			(teardrop
				(type padvia)
			)
		)
		(connect_pads yes
			(clearance 0)
		)
		(min_thickness 0.0254)
		(filled_areas_thickness no)
		(fill yes
			(thermal_gap 0.5)
			(thermal_bridge_width 0.5)
			(island_removal_mode 1)
			(island_area_min 10)
		)
		(polygon
			(pts
				(xy 120.9625 149.5355) (xy 120.962407 149.529317) (xy 120.968026 149.490256) (xy 120.983003 149.472337)
				(xy 121.012655 149.459768) (xy 120.901 149.047) (xy 120.787659 149.457247) (xy 120.814517 149.468655)
				(xy 120.829575 149.484391) (xy 120.837599 149.529037) (xy 120.8375 149.5355)
			)
		)
	)
	(zone
		(net 0)
		(net_name "")
		(layer "B.Cu")
		(hatch edge 0.5)
		(connect_pads
			(clearance 0)
		)
		(min_thickness 0.15)
		(filled_areas_thickness no)
		(keepout
			(tracks allowed)
			(vias allowed)
			(pads allowed)
			(copperpour not_allowed)
			(footprints allowed)
		)
		(placement
			(enabled no)
			(sheetname "")
		)
		(fill
			(thermal_gap 0.2)
			(thermal_bridge_width 0.5)
		)
		(polygon
			(pts
				(xy 99.96 167) (xy 99.96 157.15) (xy 98.41 157.15) (xy 98.41 167)
			)
		)
	)
	(zone
		(net 655)
		(net_name "Net-(U43C-PRTAD0)")
		(layer "B.Cu")
		(name "$teardrop_padvia$")
		(hatch none 0.1)
		(priority 30789)
		(attr
			(teardrop
				(type padvia)
			)
		)
		(connect_pads yes
			(clearance 0)
		)
		(min_thickness 0.0254)
		(filled_areas_thickness no)
		(fill yes
			(thermal_gap 0.5)
			(thermal_bridge_width 0.5)
			(island_removal_mode 1)
			(island_area_min 10)
		)
		(polygon
			(pts
				(xy 152.777515 141.099127) (xy 152.731819 141.046618) (xy 152.705231 141.000623) (xy 152.684847 140.914175)
				(xy 152.683011 140.89884) (xy 152.670677 140.816105) (xy 152.449293 140.859293) (xy 152.406105 141.080677)
				(xy 152.48884 141.093011) (xy 152.586119 141.113349) (xy 152.634159 141.140057) (xy 152.689127 141.187515)
			)
		)
	)
	(zone
		(net 681)
		(net_name "Net-(U45B-~{PDTRXB})")
		(layer "B.Cu")
		(name "$teardrop_padvia$")
		(hatch none 0.1)
		(priority 30222)
		(attr
			(teardrop
				(type padvia)
			)
		)
		(connect_pads yes
			(clearance 0)
		)
		(min_thickness 0.0254)
		(filled_areas_thickness no)
		(fill yes
			(thermal_gap 0.5)
			(thermal_bridge_width 0.5)
			(island_removal_mode 1)
			(island_area_min 10)
		)
		(polygon
			(pts
				(xy 130.878944 134.259444) (xy 130.956761 134.209591) (xy 131.078204 134.181471) (xy 131.152476 134.180257)
				(xy 131.232762 134.189508) (xy 131.235474 134.19) (xy 131.180707 133.869293) (xy 130.885 133.789526)
				(xy 130.888538 133.875966) (xy 130.882454 133.955599) (xy 130.867419 134.028138) (xy 130.844456 134.090952)
				(xy 130.790556 134.171056)
			)
		)
	)
	(zone
		(net 203)
		(net_name "/Backplane/PCIe_{REF}.CK+")
		(layer "B.Cu")
		(name "$teardrop_padvia$")
		(hatch none 0.1)
		(priority 30941)
		(attr
			(teardrop
				(type padvia)
			)
		)
		(connect_pads yes
			(clearance 0)
		)
		(min_thickness 0.0254)
		(filled_areas_thickness no)
		(fill yes
			(thermal_gap 0.5)
			(thermal_bridge_width 0.5)
			(island_removal_mode 1)
			(island_area_min 10)
		)
		(polygon
			(pts
				(xy 314.04 164.8665) (xy 314.119272 164.848854) (xy 314.204896 164.827263) (xy 314.252145 164.825372)
				(xy 314.302083 164.835) (xy 314.366 164.71) (xy 314.090953 164.642707) (xy 314.08632 164.66951)
				(xy 314.075289 164.677052) (xy 314.053941 164.669832) (xy 314.04 164.6645)
			)
		)
	)
	(zone
		(net 1)
		(net_name "GND")
		(layer "B.Cu")
		(name "$teardrop_padvia$")
		(hatch none 0.1)
		(priority 30252)
		(attr
			(teardrop
				(type padvia)
			)
		)
		(connect_pads yes
			(clearance 0)
		)
		(min_thickness 0.0254)
		(filled_areas_thickness no)
		(fill yes
			(thermal_gap 0.5)
			(thermal_bridge_width 0.5)
			(island_removal_mode 1)
			(island_area_min 10)
		)
		(polygon
			(pts
				(xy 176.779323 101.01) (xy 176.9369 101.016932) (xy 177.050434 101.045456) (xy 177.092222 101.0625)
				(xy 177.181 100.86) (xy 177.092222 100.6575) (xy 176.996177 100.691883) (xy 176.894296 100.707101)
				(xy 176.779323 100.71)
			)
		)
	)
	(zone
		(net 61)
		(net_name "/OCuLink/5V_CONN0")
		(layer "B.Cu")
		(name "$teardrop_padvia$")
		(hatch none 0.1)
		(priority 30259)
		(attr
			(teardrop
				(type padvia)
			)
		)
		(connect_pads yes
			(clearance 0)
		)
		(min_thickness 0.0254)
		(filled_areas_thickness no)
		(fill yes
			(thermal_gap 0.5)
			(thermal_bridge_width 0.5)
			(island_removal_mode 1)
			(island_area_min 10)
		)
		(polygon
			(pts
				(xy 104.09 153.235677) (xy 104.096932 153.0781) (xy 104.125456 152.964565) (xy 104.1425 152.922778)
				(xy 103.94 152.834) (xy 103.7375 152.922778) (xy 103.771883 153.018822) (xy 103.787101 153.120702)
				(xy 103.79 153.235677)
			)
		)
	)
	(zone
		(net 529)
		(net_name "/M.2 key M #1/~{CLKREQ}")
		(layer "B.Cu")
		(name "$teardrop_padvia$")
		(hatch none 0.1)
		(priority 30815)
		(attr
			(teardrop
				(type padvia)
			)
		)
		(connect_pads yes
			(clearance 0)
		)
		(min_thickness 0.0254)
		(filled_areas_thickness no)
		(fill yes
			(thermal_gap 0.5)
			(thermal_bridge_width 0.5)
			(island_removal_mode 1)
			(island_area_min 10)
		)
		(polygon
			(pts
				(xy 178.028748 105.5475) (xy 177.951025 105.552079) (xy 177.892462 105.564136) (xy 177.820704 105.591119)
				(xy 177.762281 105.61434) (xy 177.68592 105.634953) (xy 177.728815 105.85563) (xy 177.950492 105.899525)
				(xy 177.953351 105.800967) (xy 177.952026 105.75151) (xy 177.958857 105.710615) (xy 177.981783 105.682778)
				(xy 178.028748 105.6725)
			)
		)
	)
	(zone
		(net 347)
		(net_name "/2xUSB3.0+RJ45/~{GBE0_ACT}")
		(layer "B.Cu")
		(name "$teardrop_padvia$")
		(hatch none 0.1)
		(priority 30356)
		(attr
			(teardrop
				(type padvia)
			)
		)
		(connect_pads yes
			(clearance 0)
		)
		(min_thickness 0.0254)
		(filled_areas_thickness no)
		(fill yes
			(thermal_gap 0.5)
			(thermal_bridge_width 0.5)
			(island_removal_mode 1)
			(island_area_min 10)
		)
		(polygon
			(pts
				(xy 123.9425 98.298) (xy 123.962469 98.235134) (xy 123.988921 98.203156) (xy 124.026332 98.174642)
				(xy 124.073527 98.152118) (xy 124.131167 98.136907) (xy 124.131798 98.136798) (xy 123.88 97.859)
				(xy 123.628202 98.136798) (xy 123.683635 98.151095) (xy 123.72952 98.172175) (xy 123.767201 98.19954)
				(xy 123.794434 98.230448) (xy 123.811472 98.263735) (xy 123.817489 98.296566) (xy 123.8175 98.298)
			)
		)
	)
	(zone
		(net 65)
		(net_name "+12V")
		(layer "B.Cu")
		(name "$teardrop_padvia$")
		(hatch none 0.1)
		(priority 30694)
		(attr
			(teardrop
				(type padvia)
			)
		)
		(connect_pads yes
			(clearance 0)
		)
		(min_thickness 0.0254)
		(filled_areas_thickness no)
		(fill yes
			(thermal_gap 0.5)
			(thermal_bridge_width 0.5)
			(island_removal_mode 1)
			(island_area_min 10)
		)
		(polygon
			(pts
				(xy 287.4075 101.459323) (xy 287.402682 101.528763) (xy 287.38896 101.580087) (xy 287.342245 101.655628)
				(xy 287.332702 101.667768) (xy 287.282919 101.734997) (xy 287.47 101.861) (xy 287.657081 101.734997)
				(xy 287.607299 101.667769) (xy 287.552894 101.584603) (xy 287.53781 101.531748) (xy 287.5325 101.459323)
			)
		)
	)
	(zone
		(net 142)
		(net_name "/2xSFP+/PHY0_{RESET}")
		(layer "B.Cu")
		(name "$teardrop_padvia$")
		(hatch none 0.1)
		(priority 30125)
		(attr
			(teardrop
				(type padvia)
			)
		)
		(connect_pads yes
			(clearance 0)
		)
		(min_thickness 0.0254)
		(filled_areas_thickness no)
		(fill yes
			(thermal_gap 0.5)
			(thermal_bridge_width 0.5)
			(island_removal_mode 1)
			(island_area_min 10)
		)
		(polygon
			(pts
				(xy 141.18 135.873) (xy 141.23726 135.892721) (xy 141.289784 135.955533) (xy 141.309551 136.004153)
				(xy 141.322077 136.063451) (xy 141.323928 136.0805) (xy 141.801 135.8105) (xy 141.323928 135.5405)
				(xy 141.313752 135.601744) (xy 141.296075 135.652671) (xy 141.272177 135.693514) (xy 141.243978 135.723197)
				(xy 141.213988 135.74113) (xy 141.183138 135.747941) (xy 141.18 135.748)
			)
		)
	)
	(zone
		(net 188)
		(net_name "/OCuLink/PCIe_{x4}.RX1+")
		(layer "B.Cu")
		(name "$teardrop_padvia$")
		(hatch none 0.1)
		(priority 30560)
		(attr
			(teardrop
				(type padvia)
			)
		)
		(connect_pads yes
			(clearance 0)
		)
		(min_thickness 0.0254)
		(filled_areas_thickness no)
		(fill yes
			(thermal_gap 0.5)
			(thermal_bridge_width 0.5)
			(island_removal_mode 1)
			(island_area_min 10)
		)
		(polygon
			(pts
				(xy 99.397496 164.4485) (xy 99.235964 164.453895) (xy 99.151554 164.457445) (xy 99.04986 164.452823)
				(xy 99.029 164.6735) (xy 99.178852 164.836731) (xy 99.232992 164.768062) (xy 99.242883 164.751608)
				(xy 99.267383 164.712935) (xy 99.29689 164.680721) (xy 99.338046 164.658673) (xy 99.397496 164.6505)
			)
		)
	)
	(zone
		(net 291)
		(net_name "/2xUSB3.0+RJ45/~{GBE0_LINK}")
		(layer "B.Cu")
		(name "$teardrop_padvia$")
		(hatch none 0.1)
		(priority 30416)
		(attr
			(teardrop
				(type padvia)
			)
		)
		(connect_pads yes
			(clearance 0)
		)
		(min_thickness 0.0254)
		(filled_areas_thickness no)
		(fill yes
			(thermal_gap 0.5)
			(thermal_bridge_width 0.5)
			(island_removal_mode 1)
			(island_area_min 10)
		)
		(polygon
			(pts
				(xy 124.293 112.7475) (xy 124.233588 112.727727) (xy 124.177503 112.664453) (xy 124.155801 112.615828)
				(xy 124.141127 112.556468) (xy 124.139347 112.5445) (xy 123.879 112.81) (xy 124.139347 113.0755)
				(xy 124.152197 113.015361) (xy 124.172131 112.965477) (xy 124.198056 112.925358) (xy 124.227876 112.896345)
				(xy 124.259294 112.878854) (xy 124.291105 112.872521) (xy 124.293 112.8725)
			)
		)
	)
	(zone
		(net 1)
		(net_name "GND")
		(layer "B.Cu")
		(name "$teardrop_padvia$")
		(hatch none 0.1)
		(priority 30254)
		(attr
			(teardrop
				(type padvia)
			)
		)
		(connect_pads yes
			(clearance 0)
		)
		(min_thickness 0.0254)
		(filled_areas_thickness no)
		(fill yes
			(thermal_gap 0.5)
			(thermal_bridge_width 0.5)
			(island_removal_mode 1)
			(island_area_min 10)
		)
		(polygon
			(pts
				(xy 176.779323 102.51) (xy 176.9369 102.516932) (xy 177.050434 102.545456) (xy 177.092222 102.5625)
				(xy 177.181 102.36) (xy 177.092222 102.1575) (xy 176.996177 102.191883) (xy 176.894296 102.207101)
				(xy 176.779323 102.21)
			)
		)
	)
	(zone
		(net 1)
		(net_name "GND")
		(layer "B.Cu")
		(name "$teardrop_padvia$")
		(hatch none 0.1)
		(priority 30294)
		(attr
			(teardrop
				(type padvia)
			)
		)
		(connect_pads yes
			(clearance 0)
		)
		(min_thickness 0.0254)
		(filled_areas_thickness no)
		(fill yes
			(thermal_gap 0.5)
			(thermal_bridge_width 0.5)
			(island_removal_mode 1)
			(island_area_min 10)
		)
		(polygon
			(pts
				(xy 102.88 105.465) (xy 102.915463 105.470675) (xy 102.950253 105.490403) (xy 102.972866 105.517038)
				(xy 102.989874 105.555709) (xy 103 105.635) (xy 103.301 105.365) (xy 103 105.095) (xy 102.995322 105.151309)
				(xy 102.982578 105.194405) (xy 102.964018 105.225395) (xy 102.941355 105.246448) (xy 102.886236 105.264832)
				(xy 102.88 105.265)
			)
		)
	)
	(zone
		(net 379)
		(net_name "Net-(J12D-~{ESPI_EN})")
		(layer "B.Cu")
		(name "$teardrop_padvia$")
		(hatch none 0.1)
		(priority 30090)
		(attr
			(teardrop
				(type padvia)
			)
		)
		(connect_pads yes
			(clearance 0)
		)
		(min_thickness 0.0254)
		(filled_areas_thickness no)
		(fill yes
			(thermal_gap 0.5)
			(thermal_bridge_width 0.5)
			(island_removal_mode 1)
			(island_area_min 10)
		)
		(polygon
			(pts
				(xy 195.436066 162.625546) (xy 195.365 162.703216) (xy 195.315531 162.770625) (xy 195.24513 162.911708)
				(xy 195.203538 163.00451) (xy 195.138199 163.116661) (xy 195.449293 163.325707) (xy 195.761801 163.116661)
				(xy 195.686228 163.032748) (xy 195.605987 162.967753) (xy 195.534179 162.909425) (xy 195.485752 162.851212)
				(xy 195.475416 162.820493) (xy 195.477059 162.787815) (xy 195.492723 162.752516) (xy 195.524454 162.713934)
			)
		)
	)
	(zone
		(net 304)
		(net_name "Net-(J12D-~{BATLOW})")
		(layer "B.Cu")
		(name "$teardrop_padvia$")
		(hatch none 0.1)
		(priority 30104)
		(attr
			(teardrop
				(type padvia)
			)
		)
		(connect_pads yes
			(clearance 0)
		)
		(min_thickness 0.0254)
		(filled_areas_thickness no)
		(fill yes
			(thermal_gap 0.5)
			(thermal_bridge_width 0.5)
			(island_removal_mode 1)
			(island_area_min 10)
		)
		(polygon
			(pts
				(xy 187.367794 168.6375) (xy 187.285734 168.632685) (xy 187.220388 168.618981) (xy 187.127121 168.572424)
				(xy 187.048658 168.504214) (xy 186.987159 168.448058) (xy 186.908339 168.388199) (xy 186.699 168.7)
				(xy 186.908339 169.011801) (xy 187.028517 168.91478) (xy 187.048657 168.895787) (xy 187.107541 168.842634)
				(xy 187.171624 168.800409) (xy 187.254008 168.772551) (xy 187.367794 168.7625)
			)
		)
	)
	(zone
		(net 2)
		(net_name "+3V3")
		(layer "B.Cu")
		(name "$teardrop_padvia$")
		(hatch none 0.1)
		(priority 30140)
		(attr
			(teardrop
				(type padvia)
			)
		)
		(connect_pads yes
			(clearance 0)
		)
		(min_thickness 0.0254)
		(filled_areas_thickness no)
		(fill yes
			(thermal_gap 0.5)
			(thermal_bridge_width 0.5)
			(island_removal_mode 1)
			(island_area_min 10)
		)
		(polygon
			(pts
				(xy 124.658305 138.266174) (xy 124.646438 138.254412) (xy 124.596135 138.201859) (xy 124.548835 138.134852)
				(xy 124.517477 138.048744) (xy 124.515 137.938889) (xy 124.219293 138.009293) (xy 124.153201 138.33)
				(xy 124.20575 138.327894) (xy 124.252177 138.334939) (xy 124.334873 138.373118) (xy 124.422573 138.453544)
				(xy 124.446174 138.478305)
			)
		)
	)
	(zone
		(net 97)
		(net_name "/OCuLink/PCIe_{x4}.TX2-")
		(layer "B.Cu")
		(name "$teardrop_padvia$")
		(hatch none 0.1)
		(priority 30183)
		(attr
			(teardrop
				(type padvia)
			)
		)
		(connect_pads yes
			(clearance 0)
		)
		(min_thickness 0.0254)
		(filled_areas_thickness no)
		(fill yes
			(thermal_gap 0.5)
			(thermal_bridge_width 0.5)
			(island_removal_mode 1)
			(island_area_min 10)
		)
		(polygon
			(pts
				(xy 108.965556 160.2665) (xy 109.020074 160.246776) (xy 109.179598 160.19577) (xy 109.268436 160.182974)
				(xy 109.358602 160.189) (xy 109.332 159.869) (xy 109.036 159.766977) (xy 109.042099 159.895154)
				(xy 109.031354 159.986378) (xy 109.0157 160.024205) (xy 108.992319 160.050566) (xy 108.965556 160.0645)
			)
		)
	)
	(zone
		(net 878)
		(net_name "/2xSFP+/SFI1.RX+")
		(layer "B.Cu")
		(name "$teardrop_padvia$")
		(hatch none 0.1)
		(priority 30063)
		(attr
			(teardrop
				(type padvia)
			)
		)
		(connect_pads yes
			(clearance 0)
		)
		(min_thickness 0.0254)
		(filled_areas_thickness no)
		(fill yes
			(thermal_gap 0.5)
			(thermal_bridge_width 0.5)
			(island_removal_mode 1)
			(island_area_min 10)
		)
		(polygon
			(pts
				(xy 139.494262 160.59) (xy 139.584366 160.594831) (xy 139.657051 160.608647) (xy 139.761568 160.655698)
				(xy 139.864552 160.740604) (xy 139.933613 160.801857) (xy 140.021105 160.867532) (xy 140.261 160.51)
				(xy 140.021105 160.152468) (xy 139.887383 160.258548) (xy 139.864551 160.279396) (xy 139.795571 160.339701)
				(xy 139.721036 160.387385) (xy 139.625685 160.418726) (xy 139.494262 160.43)
			)
		)
	)
	(zone
		(net 95)
		(net_name "/OCuLink/PCIe_{x4}.TX0-")
		(layer "B.Cu")
		(name "$teardrop_padvia$")
		(hatch none 0.1)
		(priority 31009)
		(attr
			(teardrop
				(type padvia)
			)
		)
		(connect_pads yes
			(clearance 0)
		)
		(min_thickness 0.0254)
		(filled_areas_thickness no)
		(fill yes
			(thermal_gap 0.5)
			(thermal_bridge_width 0.5)
			(island_removal_mode 1)
			(island_area_min 10)
		)
		(polygon
			(pts
				(xy 104.708 166.009) (xy 104.687352 166.016199) (xy 104.655017 166.025792) (xy 104.640994 166.018965)
				(xy 104.631005 165.9975) (xy 104.382 166.11) (xy 104.631005 166.2225) (xy 104.64073 166.201324)
				(xy 104.654358 166.194269) (xy 104.687352 166.203801) (xy 104.708 166.211)
			)
		)
	)
	(zone
		(net 192)
		(net_name "/OCuLink/PCIe_{REF0}.CK+")
		(layer "B.Cu")
		(name "$teardrop_padvia$")
		(hatch none 0.1)
		(priority 30529)
		(attr
			(teardrop
				(type padvia)
			)
		)
		(connect_pads yes
			(clearance 0)
		)
		(min_thickness 0.0254)
		(filled_areas_thickness no)
		(fill yes
			(thermal_gap 0.5)
			(thermal_bridge_width 0.5)
			(island_removal_mode 1)
			(island_area_min 10)
		)
		(polygon
			(pts
				(xy 207.002504 130.2205) (xy 207.04929 130.225235) (xy 207.084742 130.238379) (xy 207.132939 130.283387)
				(xy 207.157116 130.321608) (xy 207.184485 130.364773) (xy 207.221147 130.406731) (xy 207.371 130.2435)
				(xy 207.35014 130.022823) (xy 207.249466 130.027452) (xy 207.166096 130.024019) (xy 207.164035 130.023895)
				(xy 207.002504 130.0185)
			)
		)
	)
	(zone
		(net 78)
		(net_name "+1V8")
		(layer "B.Cu")
		(name "$teardrop_padvia$")
		(hatch none 0.1)
		(priority 30689)
		(attr
			(teardrop
				(type padvia)
			)
		)
		(connect_pads yes
			(clearance 0)
		)
		(min_thickness 0.0254)
		(filled_areas_thickness no)
		(fill yes
			(thermal_gap 0.5)
			(thermal_bridge_width 0.5)
			(island_removal_mode 1)
			(island_area_min 10)
		)
		(polygon
			(pts
				(xy 158.3175 139.959323) (xy 158.312682 140.028763) (xy 158.29896 140.080087) (xy 158.252245 140.155628)
				(xy 158.242702 140.167768) (xy 158.192919 140.234997) (xy 158.38 140.361) (xy 158.567081 140.234997)
				(xy 158.517299 140.167769) (xy 158.462894 140.084603) (xy 158.44781 140.031748) (xy 158.4425 139.959323)
			)
		)
	)
	(zone
		(net 677)
		(net_name "Net-(U45C-PRTAD1)")
		(layer "B.Cu")
		(name "$teardrop_padvia$")
		(hatch none 0.1)
		(priority 30360)
		(attr
			(teardrop
				(type padvia)
			)
		)
		(connect_pads yes
			(clearance 0)
		)
		(min_thickness 0.0254)
		(filled_areas_thickness no)
		(fill yes
			(thermal_gap 0.5)
			(thermal_bridge_width 0.5)
			(island_removal_mode 1)
			(island_area_min 10)
		)
		(polygon
			(pts
				(xy 126.5075 137.622) (xy 126.487531 137.684866) (xy 126.461079 137.716844) (xy 126.423668 137.745358)
				(xy 126.376473 137.767882) (xy 126.318833 137.783093) (xy 126.318202 137.783202) (xy 126.57 138.061)
				(xy 126.821798 137.783202) (xy 126.766365 137.768905) (xy 126.72048 137.747825) (xy 126.682799 137.72046)
				(xy 126.655566 137.689552) (xy 126.638528 137.656265) (xy 126.632511 137.623434) (xy 126.6325 137.622)
			)
		)
	)
	(zone
		(net 160)
		(net_name "/2xUSB3.0+RJ45/USBSS_2.RX-")
		(layer "B.Cu")
		(name "$teardrop_padvia$")
		(hatch none 0.1)
		(priority 31029)
		(attr
			(teardrop
				(type padvia)
			)
		)
		(connect_pads yes
			(clearance 0)
		)
		(min_thickness 0.0254)
		(filled_areas_thickness no)
		(fill yes
			(thermal_gap 0.5)
			(thermal_bridge_width 0.5)
			(island_removal_mode 1)
			(island_area_min 10)
		)
		(polygon
			(pts
				(xy 123.46 105.3925) (xy 123.478847 105.3876) (xy 123.512108 105.381482) (xy 123.526647 105.389841)
				(xy 123.536995 105.4125) (xy 123.786 105.3) (xy 123.536995 105.1875) (xy 123.527025 105.209717)
				(xy 123.51305 105.218331) (xy 123.478847 105.2124) (xy 123.46 105.2075)
			)
		)
	)
	(zone
		(net 889)
		(net_name "/Power/PG_{3V3}")
		(layer "B.Cu")
		(name "$teardrop_padvia$")
		(hatch none 0.1)
		(priority 30734)
		(attr
			(teardrop
				(type padvia)
			)
		)
		(connect_pads yes
			(clearance 0)
		)
		(min_thickness 0.0254)
		(filled_areas_thickness no)
		(fill yes
			(thermal_gap 0.5)
			(thermal_bridge_width 0.5)
			(island_removal_mode 1)
			(island_area_min 10)
		)
		(polygon
			(pts
				(xy 311.665676 102.7875) (xy 311.596235 102.782682) (xy 311.544912 102.76896) (xy 311.46937 102.722246)
				(xy 311.45723 102.712701) (xy 311.390002 102.662919) (xy 311.263999 102.85) (xy 311.390002 103.037081)
				(xy 311.457228 102.987299) (xy 311.540395 102.932894) (xy 311.59325 102.91781) (xy 311.665676 102.9125)
			)
		)
	)
	(zone
		(net 160)
		(net_name "/2xUSB3.0+RJ45/USBSS_2.RX-")
		(layer "B.Cu")
		(name "$teardrop_padvia$")
		(hatch none 0.1)
		(priority 31022)
		(attr
			(teardrop
				(type padvia)
			)
		)
		(connect_pads yes
			(clearance 0)
		)
		(min_thickness 0.0254)
		(filled_areas_thickness no)
		(fill yes
			(thermal_gap 0.5)
			(thermal_bridge_width 0.5)
			(island_removal_mode 1)
			(island_area_min 10)
		)
		(polygon
			(pts
				(xy 123.338 105.2075) (xy 123.319153 105.2124) (xy 123.285892 105.218518) (xy 123.271353 105.210159)
				(xy 123.261005 105.1875) (xy 123.012 105.3) (xy 123.261005 105.4125) (xy 123.270976 105.390283)
				(xy 123.284951 105.381669) (xy 123.319153 105.3876) (xy 123.338 105.3925)
			)
		)
	)
	(zone
		(net 53)
		(net_name "/2xSFP+/SH")
		(layer "B.Cu")
		(name "$teardrop_padvia$")
		(hatch none 0.1)
		(priority 30011)
		(attr
			(teardrop
				(type padvia)
			)
		)
		(connect_pads yes
			(clearance 0)
		)
		(min_thickness 0.0254)
		(filled_areas_thickness no)
		(fill yes
			(thermal_gap 0.5)
			(thermal_bridge_width 0.5)
			(island_removal_mode 1)
			(island_area_min 10)
		)
		(polygon
			(pts
				(xy 131.114411 169.585) (xy 131.238176 169.589874) (xy 131.343135 169.603996) (xy 131.427771 169.625089)
				(xy 131.501356 169.653095) (xy 131.63157 169.731201) (xy 131.766203 169.845057) (xy 131.884598 169.947896)
				(xy 132.033322 170.058602) (xy 132.451 169.435) (xy 132.033322 168.811398) (xy 131.844772 168.955593)
				(xy 131.766202 169.024943) (xy 131.643924 169.129417) (xy 131.51251 169.211718) (xy 131.434951 169.242616)
				(xy 131.344995 169.265646) (xy 131.239272 169.280032) (xy 131.114411 169.285)
			)
		)
	)
	(zone
		(net 201)
		(net_name "/OCuLink/~{CPRSNT_D0}")
		(layer "B.Cu")
		(name "$teardrop_padvia$")
		(hatch none 0.1)
		(priority 30436)
		(attr
			(teardrop
				(type padvia)
			)
		)
		(connect_pads yes
			(clearance 0)
		)
		(min_thickness 0.0254)
		(filled_areas_thickness no)
		(fill yes
			(thermal_gap 0.5)
			(thermal_bridge_width 0.5)
			(island_removal_mode 1)
			(island_area_min 10)
		)
		(polygon
			(pts
				(xy 120.807 161.6225) (xy 120.866412 161.642273) (xy 120.922497 161.705547) (xy 120.944199 161.754172)
				(xy 120.958873 161.813531) (xy 120.960653 161.8255) (xy 121.221 161.56) (xy 120.960653 161.2945)
				(xy 120.947804 161.354638) (xy 120.92787 161.404522) (xy 120.901945 161.444641) (xy 120.872125 161.473654)
				(xy 120.840707 161.491146) (xy 120.808896 161.497479) (xy 120.807 161.4975)
			)
		)
	)
	(zone
		(net 657)
		(net_name "Net-(U43A-~{PDTRXA})")
		(layer "B.Cu")
		(name "$teardrop_padvia$")
		(hatch none 0.1)
		(priority 30779)
		(attr
			(teardrop
				(type padvia)
			)
		)
		(connect_pads yes
			(clearance 0)
		)
		(min_thickness 0.0254)
		(filled_areas_thickness no)
		(fill yes
			(thermal_gap 0.5)
			(thermal_bridge_width 0.5)
			(island_removal_mode 1)
			(island_area_min 10)
		)
		(polygon
			(pts
				(xy 156.777515 139.099127) (xy 156.731819 139.046618) (xy 156.705231 139.000623) (xy 156.684847 138.914175)
				(xy 156.683011 138.89884) (xy 156.670677 138.816105) (xy 156.449293 138.859293) (xy 156.406105 139.080677)
				(xy 156.48884 139.093011) (xy 156.586119 139.113349) (xy 156.634159 139.140057) (xy 156.689127 139.187515)
			)
		)
	)
	(zone
		(net 286)
		(net_name "/2xUSB3.0+RJ45/GbE.MDI3+")
		(layer "B.Cu")
		(name "$teardrop_padvia$")
		(hatch none 0.1)
		(priority 30650)
		(attr
			(teardrop
				(type padvia)
			)
		)
		(connect_pads yes
			(clearance 0)
		)
		(min_thickness 0.0254)
		(filled_areas_thickness no)
		(fill yes
			(thermal_gap 0.5)
			(thermal_bridge_width 0.5)
			(island_removal_mode 1)
			(island_area_min 10)
		)
		(polygon
			(pts
				(xy 177.025 167.742084) (xy 177.029756 167.702162) (xy 177.04305 167.673745) (xy 177.087129 167.641329)
				(xy 177.132262 167.62605) (xy 177.178541 167.610756) (xy 177.225003 167.587081) (xy 177.1 167.399)
				(xy 176.879323 167.398242) (xy 176.877203 167.536699) (xy 176.875 167.742084)
			)
		)
	)
	(zone
		(net 866)
		(net_name "/Backplane/PCIe_{x2}.TX0+")
		(layer "B.Cu")
		(name "$teardrop_padvia$")
		(hatch none 0.1)
		(priority 30994)
		(attr
			(teardrop
				(type padvia)
			)
		)
		(connect_pads yes
			(clearance 0)
		)
		(min_thickness 0.0254)
		(filled_areas_thickness no)
		(fill yes
			(thermal_gap 0.5)
			(thermal_bridge_width 0.5)
			(island_removal_mode 1)
			(island_area_min 10)
		)
		(polygon
			(pts
				(xy 314.812 160.011) (xy 314.832648 160.003802) (xy 314.864984 159.994208) (xy 314.879007 160.001035)
				(xy 314.888995 160.0225) (xy 315.138 159.91) (xy 314.888995 159.7975) (xy 314.879271 159.818676)
				(xy 314.865643 159.825731) (xy 314.832648 159.816198) (xy 314.812 159.809)
			)
		)
	)
	(zone
		(net 310)
		(net_name "/Com Express 7 MGMT/~{BIOS_DIS0}")
		(layer "B.Cu")
		(name "$teardrop_padvia$")
		(hatch none 0.1)
		(priority 30729)
		(attr
			(teardrop
				(type padvia)
			)
		)
		(connect_pads yes
			(clearance 0)
		)
		(min_thickness 0.0254)
		(filled_areas_thickness no)
		(fill yes
			(thermal_gap 0.5)
			(thermal_bridge_width 0.5)
			(island_removal_mode 1)
			(island_area_min 10)
		)
		(polygon
			(pts
				(xy 191.5625 167.450677) (xy 191.567318 167.381236) (xy 191.58104 167.329912) (xy 191.627755 167.25437)
				(xy 191.637299 167.242229) (xy 191.687081 167.175003) (xy 191.5 167.049) (xy 191.312919 167.175003)
				(xy 191.362701 167.242231) (xy 191.417106 167.325397) (xy 191.43219 167.378251) (xy 191.4375 167.450677)
			)
		)
	)
	(zone
		(net 897)
		(net_name "Net-(J2B-RS1)")
		(layer "B.Cu")
		(name "$teardrop_padvia$")
		(hatch none 0.1)
		(priority 30816)
		(attr
			(teardrop
				(type padvia)
			)
		)
		(connect_pads yes
			(clearance 0)
		)
		(min_thickness 0.0254)
		(filled_areas_thickness no)
		(fill yes
			(thermal_gap 0.5)
			(thermal_bridge_width 0.5)
			(island_removal_mode 1)
			(island_area_min 10)
		)
		(polygon
			(pts
				(xy 137.1125 167.857123) (xy 137.117272 167.822385) (xy 137.13068 167.799833) (xy 137.17286 167.782104)
				(xy 137.24204 167.782773) (xy 137.343895 167.780677) (xy 137.3 167.559) (xy 137.079323 167.516105)
				(xy 137.04162 167.633191) (xy 137.033216 167.651868) (xy 137.001383 167.73506) (xy 136.9875 167.857123)
			)
		)
	)
	(zone
		(net 579)
		(net_name "/2xUSB3.0+RJ45/SH")
		(layer "B.Cu")
		(name "$teardrop_padvia$")
		(hatch none 0.1)
		(priority 30000)
		(attr
			(teardrop
				(type padvia)
			)
		)
		(connect_pads yes
			(clearance 0)
		)
		(min_thickness 0.0254)
		(filled_areas_thickness no)
		(fill yes
			(thermal_gap 0.5)
			(thermal_bridge_width 0.5)
			(island_removal_mode 1)
			(island_area_min 10)
		)
		(polygon
			(pts
				(xy 100.836066 96.166065) (xy 100.897975 96.111077) (xy 100.958032 96.071181) (xy 101.012434 96.04672)
				(xy 101.065347 96.033747) (xy 101.165086 96.038651) (xy 101.265532 96.082328) (xy 101.374435 96.172179)
				(xy 101.499475 96.324516) (xy 101.654887 96.568256) (xy 101.711508 96.664859) (xy 101.84085 96.880158)
				(xy 101.965887 97.049059) (xy 103.060707 96.039293) (xy 101.947686 95.049141) (xy 101.802257 95.184942)
				(xy 101.625995 95.300184) (xy 101.42414 95.404196) (xy 101.244798 95.495129) (xy 101.052175 95.607129)
				(xy 100.845482 95.755097) (xy 100.623935 95.953934)
			)
		)
	)
	(zone
		(net 159)
		(net_name "/2xUSB3.0+RJ45/USBSS_1.RX+")
		(layer "B.Cu")
		(name "$teardrop_padvia$")
		(hatch none 0.1)
		(priority 30038)
		(attr
			(teardrop
				(type padvia)
			)
		)
		(connect_pads yes
			(clearance 0)
		)
		(min_thickness 0.0254)
		(filled_areas_thickness no)
		(fill yes
			(thermal_gap 0.5)
			(thermal_bridge_width 0.5)
			(island_removal_mode 1)
			(island_area_min 10)
		)
		(polygon
			(pts
				(xy 107.377985 107.825199) (xy 107.475931 107.890388) (xy 107.561373 107.935403) (xy 107.703099 107.980045)
				(xy 107.857634 107.996055) (xy 107.975499 108.005384) (xy 108.118314 108.02703) (xy 108.250809 107.365587)
				(xy 107.58797 107.233314) (xy 107.579801 107.357413) (xy 107.586126 107.480007) (xy 107.591672 107.58768)
				(xy 107.584788 107.667847) (xy 107.573012 107.692137) (xy 107.553722 107.702975) (xy 107.525448 107.698169)
				(xy 107.486721 107.675529)
			)
		)
	)
	(zone
		(net 159)
		(net_name "/2xUSB3.0+RJ45/USBSS_1.RX+")
		(layer "B.Cu")
		(name "$teardrop_padvia$")
		(hatch none 0.1)
		(priority 30945)
		(attr
			(teardrop
				(type padvia)
			)
		)
		(connect_pads yes
			(clearance 0)
		)
		(min_thickness 0.0254)
		(filled_areas_thickness no)
		(fill yes
			(thermal_gap 0.5)
			(thermal_bridge_width 0.5)
			(island_removal_mode 1)
			(island_area_min 10)
		)
		(polygon
			(pts
				(xy 101.65 105.8325) (xy 101.637475 105.83578) (xy 101.612498 105.838714) (xy 101.603392 105.827753)
				(xy 101.599774 105.801366) (xy 101.324 105.865) (xy 101.381649 105.99) (xy 101.469774 105.981159)
				(xy 101.569692 106.001748) (xy 101.65 106.0175)
			)
		)
	)
	(zone
		(net 676)
		(net_name "Net-(U45C-PRTAD0)")
		(layer "B.Cu")
		(name "$teardrop_padvia$")
		(hatch none 0.1)
		(priority 30783)
		(attr
			(teardrop
				(type padvia)
			)
		)
		(connect_pads yes
			(clearance 0)
		)
		(min_thickness 0.0254)
		(filled_areas_thickness no)
		(fill yes
			(thermal_gap 0.5)
			(thermal_bridge_width 0.5)
			(island_removal_mode 1)
			(island_area_min 10)
		)
		(polygon
			(pts
				(xy 134.617515 141.099127) (xy 134.571819 141.046618) (xy 134.545231 141.000623) (xy 134.524847 140.914175)
				(xy 134.523011 140.89884) (xy 134.510677 140.816105) (xy 134.289293 140.859293) (xy 134.246105 141.080677)
				(xy 134.32884 141.093011) (xy 134.426119 141.113349) (xy 134.474159 141.140057) (xy 134.529127 141.187515)
			)
		)
	)
	(zone
		(net 2)
		(net_name "+3V3")
		(layer "B.Cu")
		(name "$teardrop_padvia$")
		(hatch none 0.1)
		(priority 30912)
		(attr
			(teardrop
				(type padvia)
			)
		)
		(connect_pads yes
			(clearance 0)
		)
		(min_thickness 0.0254)
		(filled_areas_thickness no)
		(fill yes
			(thermal_gap 0.5)
			(thermal_bridge_width 0.5)
			(island_removal_mode 1)
			(island_area_min 10)
		)
		(polygon
			(pts
				(xy 114.4635 149.5355) (xy 114.463404 149.529178) (xy 114.468989 149.489675) (xy 114.483922 149.471452)
				(xy 114.5135 149.458504) (xy 114.401 149.047) (xy 114.2885 149.458504) (xy 114.315493 149.46962)
				(xy 114.330595 149.485147) (xy 114.338596 149.529178) (xy 114.3385 149.5355)
			)
		)
	)
	(zone
		(net 78)
		(net_name "+1V8")
		(layer "B.Cu")
		(name "$teardrop_padvia$")
		(hatch none 0.1)
		(priority 30145)
		(attr
			(teardrop
				(type padvia)
			)
		)
		(connect_pads yes
			(clearance 0)
		)
		(min_thickness 0.0254)
		(filled_areas_thickness no)
		(fill yes
			(thermal_gap 0.5)
			(thermal_bridge_width 0.5)
			(island_removal_mode 1)
			(island_area_min 10)
		)
		(polygon
			(pts
				(xy 147.18 133.432) (xy 147.200463 133.482972) (xy 147.219257 133.520783) (xy 147.227794 133.558127)
				(xy 147.213674 133.590577) (xy 147.1645 133.613708) (xy 147.43 133.871) (xy 147.6955 133.613708)
				(xy 147.659356 133.600216) (xy 147.639384 133.582258) (xy 147.633731 133.542859) (xy 147.659537 133.482972)
				(xy 147.68 133.432)
			)
		)
	)
	(zone
		(net 197)
		(net_name "/OCuLink/PCIe_{x4}.RX3-")
		(layer "B.Cu")
		(name "$teardrop_padvia$")
		(hatch none 0.1)
		(priority 30499)
		(attr
			(teardrop
				(type padvia)
			)
		)
		(connect_pads yes
			(clearance 0)
		)
		(min_thickness 0.0254)
		(filled_areas_thickness no)
		(fill yes
			(thermal_gap 0.5)
			(thermal_bridge_width 0.5)
			(island_removal_mode 1)
			(island_area_min 10)
		)
		(polygon
			(pts
				(xy 106.5565 150.432504) (xy 106.551765 150.47929) (xy 106.538621 150.514742) (xy 106.493613 150.562939)
				(xy 106.455393 150.587115) (xy 106.412226 150.614484) (xy 106.370268 150.651147) (xy 106.5335 150.801)
				(xy 106.754177 150.78014) (xy 106.749548 150.679469) (xy 106.75298 150.596102) (xy 106.753105 150.594035)
				(xy 106.7585 150.432504)
			)
		)
	)
	(zone
		(net 1)
		(net_name "GND")
		(layer "B.Cu")
		(name "$teardrop_padvia$")
		(hatch none 0.1)
		(priority 30244)
		(attr
			(teardrop
				(type padvia)
			)
		)
		(connect_pads yes
			(clearance 0)
		)
		(min_thickness 0.0254)
		(filled_areas_thickness no)
		(fill yes
			(thermal_gap 0.5)
			(thermal_bridge_width 0.5)
			(island_removal_mode 1)
			(island_area_min 10)
		)
		(polygon
			(pts
				(xy 102.789323 161.26) (xy 102.9469 161.266932) (xy 103.060434 161.295456) (xy 103.102222 161.3125)
				(xy 103.191 161.11) (xy 103.102222 160.9075) (xy 103.006177 160.941883) (xy 102.904296 160.957101)
				(xy 102.789323 160.96)
			)
		)
	)
	(zone
		(net 973)
		(net_name "/PCIe redriver/RX_SW")
		(layer "B.Cu")
		(name "$teardrop_padvia$")
		(hatch none 0.1)
		(priority 30904)
		(attr
			(teardrop
				(type padvia)
			)
		)
		(connect_pads yes
			(clearance 0)
		)
		(min_thickness 0.0254)
		(filled_areas_thickness no)
		(fill yes
			(thermal_gap 0.5)
			(thermal_bridge_width 0.5)
			(island_removal_mode 1)
			(island_area_min 10)
		)
		(polygon
			(pts
				(xy 189.534479 136.924442) (xy 189.539016 136.928844) (xy 189.563 136.960726) (xy 189.565326 136.984171)
				(xy 189.553566 137.014242) (xy 189.924094 137.22567) (xy 189.712666 136.855142) (xy 189.685718 136.866369)
				(xy 189.66406 136.866069) (xy 189.627268 136.840592) (xy 189.622866 136.836055)
			)
		)
	)
	(zone
		(net 1)
		(net_name "GND")
		(layer "B.Cu")
		(name "$teardrop_padvia$")
		(hatch none 0.1)
		(priority 30052)
		(attr
			(teardrop
				(type padvia)
			)
		)
		(connect_pads yes
			(clearance 0)
		)
		(min_thickness 0.0254)
		(filled_areas_thickness no)
		(fill yes
			(thermal_gap 0.5)
			(thermal_bridge_width 0.5)
			(island_removal_mode 1)
			(island_area_min 10)
		)
		(polygon
			(pts
				(xy 252.252116 73.380042) (xy 252.21033 73.430147) (xy 252.162227 73.4885) (xy 252.101369 73.53989)
				(xy 252.021558 73.568872) (xy 251.972607 73.570133) (xy 251.916593 73.56) (xy 251.925003 74.060707)
				(xy 252.32571 74.169116) (xy 252.329174 74.103793) (xy 252.341378 74.045697) (xy 252.389844 73.942942)
				(xy 252.471106 73.849913) (xy 252.540018 73.790822) (xy 252.605668 73.733594)
			)
		)
	)
	(zone
		(net 978)
		(net_name "/PCIe redriver/RX_EQ0")
		(layer "B.Cu")
		(name "$teardrop_padvia$")
		(hatch none 0.1)
		(priority 30695)
		(attr
			(teardrop
				(type padvia)
			)
		)
		(connect_pads yes
			(clearance 0)
		)
		(min_thickness 0.0254)
		(filled_areas_thickness no)
		(fill yes
			(thermal_gap 0.5)
			(thermal_bridge_width 0.5)
			(island_removal_mode 1)
			(island_area_min 10)
		)
		(polygon
			(pts
				(xy 190.345962 140.209913) (xy 190.341144 140.279353) (xy 190.327422 140.330677) (xy 190.280707 140.406218)
				(xy 190.271164 140.418358) (xy 190.221381 140.485587) (xy 190.408462 140.61159) (xy 190.595543 140.485587)
				(xy 190.545761 140.418359) (xy 190.491356 140.335193) (xy 190.476272 140.282338) (xy 190.470962 140.209913)
			)
		)
	)
	(zone
		(net 211)
		(net_name "/Com Express 7 Interfaces/PCIe_{B1x4}.TX3-")
		(layer "B.Cu")
		(name "$teardrop_padvia$")
		(hatch none 0.1)
		(priority 30834)
		(attr
			(teardrop
				(type padvia)
			)
		)
		(connect_pads yes
			(clearance 0)
		)
		(min_thickness 0.0254)
		(filled_areas_thickness no)
		(fill yes
			(thermal_gap 0.5)
			(thermal_bridge_width 0.5)
			(island_removal_mode 1)
			(island_area_min 10)
		)
		(polygon
			(pts
				(xy 114.8555 145.1855) (xy 114.861457 145.19966) (xy 114.86931 145.223595) (xy 114.861086 145.232257)
				(xy 114.837574 145.235684) (xy 114.901 145.674) (xy 115.026 145.570348) (xy 115.01672 145.443171)
				(xy 115.04007 145.297903) (xy 115.0575 145.1855)
			)
		)
	)
	(zone
		(net 358)
		(net_name "/Com Express 7 MGMT/SMBus.SDA")
		(layer "B.Cu")
		(name "$teardrop_padvia$")
		(hatch none 0.1)
		(priority 30762)
		(attr
			(teardrop
				(type padvia)
			)
		)
		(connect_pads yes
			(clearance 0)
		)
		(min_thickness 0.0254)
		(filled_areas_thickness no)
		(fill yes
			(thermal_gap 0.5)
			(thermal_bridge_width 0.5)
			(island_removal_mode 1)
			(island_area_min 10)
		)
		(polygon
			(pts
				(xy 109.847485 162.333373) (xy 109.893181 162.385882) (xy 109.919768 162.431876) (xy 109.940152 162.518325)
				(xy 109.941988 162.533658) (xy 109.954323 162.616395) (xy 110.175707 162.573207) (xy 110.218895 162.351823)
				(xy 110.136158 162.339488) (xy 110.03888 162.319151) (xy 109.99084 162.292443) (xy 109.935873 162.244985)
			)
		)
	)
	(zone
		(net 711)
		(net_name "Net-(U37-SADR_{TRI})")
		(layer "B.Cu")
		(name "$teardrop_padvia$")
		(hatch none 0.1)
		(priority 30113)
		(attr
			(teardrop
				(type padvia)
			)
		)
		(connect_pads yes
			(clearance 0)
		)
		(min_thickness 0.0254)
		(filled_areas_thickness no)
		(fill yes
			(thermal_gap 0.5)
			(thermal_bridge_width 0.5)
			(island_removal_mode 1)
			(island_area_min 10)
		)
		(polygon
			(pts
				(xy 217.6425 125.517794) (xy 217.647315 125.435733) (xy 217.661019 125.370388) (xy 217.707576 125.27712)
				(xy 217.775787 125.198657) (xy 217.831942 125.137158) (xy 217.891801 125.058339) (xy 217.58 124.849)
				(xy 217.268199 125.058339) (xy 217.365219 125.178517) (xy 217.384214 125.198658) (xy 217.437366 125.257541)
				(xy 217.479591 125.321624) (xy 217.507449 125.404008) (xy 217.5175 125.517794)
			)
		)
	)
	(zone
		(net 662)
		(net_name "Net-(U43C-MODE_{SEL})")
		(layer "B.Cu")
		(name "$teardrop_padvia$")
		(hatch none 0.1)
		(priority 30403)
		(attr
			(teardrop
				(type padvia)
			)
		)
		(connect_pads yes
			(clearance 0)
		)
		(min_thickness 0.0254)
		(filled_areas_thickness no)
		(fill yes
			(thermal_gap 0.5)
			(thermal_bridge_width 0.5)
			(island_removal_mode 1)
			(island_area_min 10)
		)
		(polygon
			(pts
				(xy 145.143 141.9975) (xy 145.083588 141.977727) (xy 145.027503 141.914453) (xy 145.005801 141.865828)
				(xy 144.991127 141.806468) (xy 144.989347 141.7945) (xy 144.729 142.06) (xy 144.989347 142.3255)
				(xy 145.002197 142.265361) (xy 145.022131 142.215477) (xy 145.048056 142.175358) (xy 145.077876 142.146345)
				(xy 145.109294 142.128854) (xy 145.141105 142.122521) (xy 145.143 142.1225)
			)
		)
	)
	(zone
		(net 81)
		(net_name "/Misc/FAN_12V")
		(layer "B.Cu")
		(name "$teardrop_padvia$")
		(hatch none 0.1)
		(priority 30006)
		(attr
			(teardrop
				(type padvia)
			)
		)
		(connect_pads yes
			(clearance 0)
		)
		(min_thickness 0.0254)
		(filled_areas_thickness no)
		(fill yes
			(thermal_gap 0.5)
			(thermal_bridge_width 0.5)
			(island_removal_mode 1)
			(island_area_min 10)
		)
		(polygon
			(pts
				(xy 263.950708 73.204379) (xy 263.955971 73.121131) (xy 263.972814 73.031151) (xy 263.999954 72.944539)
				(xy 264.039508 72.856529) (xy 264.086624 72.778013) (xy 264.145643 72.70154) (xy 264.210733 72.634728)
				(xy 264.287191 72.572019) (xy 264.419929 72.490568) (xy 263.700708 71.859) (xy 262.981487 72.490568)
				(xy 263.143575 72.594426) (xy 263.271034 72.71958) (xy 263.365386 72.863236) (xy 263.42595 73.02086)
				(xy 263.450313 73.181986) (xy 263.450708 73.204379)
			)
		)
	)
	(zone
		(net 676)
		(net_name "Net-(U45C-PRTAD0)")
		(layer "B.Cu")
		(name "$teardrop_padvia$")
		(hatch none 0.1)
		(priority 30358)
		(attr
			(teardrop
				(type padvia)
			)
		)
		(connect_pads yes
			(clearance 0)
		)
		(min_thickness 0.0254)
		(filled_areas_thickness no)
		(fill yes
			(thermal_gap 0.5)
			(thermal_bridge_width 0.5)
			(island_removal_mode 1)
			(island_area_min 10)
		)
		(polygon
			(pts
				(xy 139.3225 141.798) (xy 139.342469 141.735134) (xy 139.368921 141.703156) (xy 139.406332 141.674642)
				(xy 139.453527 141.652118) (xy 139.511167 141.636907) (xy 139.511798 141.636798) (xy 139.26 141.359)
				(xy 139.008202 141.636798) (xy 139.063635 141.651095) (xy 139.10952 141.672175) (xy 139.147201 141.69954)
				(xy 139.174434 141.730448) (xy 139.191472 141.763735) (xy 139.197489 141.796566) (xy 139.1975 141.798)
			)
		)
	)
	(zone
		(net 304)
		(net_name "Net-(J12D-~{BATLOW})")
		(layer "B.Cu")
		(name "$teardrop_padvia$")
		(hatch none 0.1)
		(priority 30690)
		(attr
			(teardrop
				(type padvia)
			)
		)
		(connect_pads yes
			(clearance 0)
		)
		(min_thickness 0.0254)
		(filled_areas_thickness no)
		(fill yes
			(thermal_gap 0.5)
			(thermal_bridge_width 0.5)
			(island_removal_mode 1)
			(island_area_min 10)
		)
		(polygon
			(pts
				(xy 188.9375 169.549323) (xy 188.932682 169.618763) (xy 188.91896 169.670087) (xy 188.872245 169.745628)
				(xy 188.862702 169.757768) (xy 188.812919 169.824997) (xy 189 169.951) (xy 189.187081 169.824997)
				(xy 189.137299 169.757769) (xy 189.082894 169.674603) (xy 189.06781 169.621748) (xy 189.0625 169.549323)
			)
		)
	)
	(zone
		(net 1)
		(net_name "GND")
		(layer "B.Cu")
		(name "$teardrop_padvia$")
		(hatch none 0.1)
		(priority 30438)
		(attr
			(teardrop
				(type padvia)
			)
		)
		(connect_pads yes
			(clearance 0)
		)
		(min_thickness 0.0254)
		(filled_areas_thickness no)
		(fill yes
			(thermal_gap 0.5)
			(thermal_bridge_width 0.5)
			(island_removal_mode 1)
			(island_area_min 10)
		)
		(polygon
			(pts
				(xy 146.057 136.1225) (xy 146.116412 136.142273) (xy 146.172497 136.205547) (xy 146.194199 136.254172)
				(xy 146.208873 136.313531) (xy 146.210653 136.3255) (xy 146.471 136.06) (xy 146.210653 135.7945)
				(xy 146.197804 135.854638) (xy 146.17787 135.904522) (xy 146.151945 135.944641) (xy 146.122125 135.973654)
				(xy 146.090707 135.991146) (xy 146.058896 135.997479) (xy 146.057 135.9975)
			)
		)
	)
	(zone
		(net 867)
		(net_name "/Backplane/PCIe_{x2}.TX0-")
		(layer "B.Cu")
		(name "$teardrop_padvia$")
		(hatch none 0.1)
		(priority 30968)
		(attr
			(teardrop
				(type padvia)
			)
		)
		(connect_pads yes
			(clearance 0)
		)
		(min_thickness 0.0254)
		(filled_areas_thickness no)
		(fill yes
			(thermal_gap 0.5)
			(thermal_bridge_width 0.5)
			(island_removal_mode 1)
			(island_area_min 10)
		)
		(polygon
			(pts
				(xy 315.44128 160.255528) (xy 315.371073 160.272411) (xy 315.292898 160.293576) (xy 315.24787 160.29514)
				(xy 315.19826 160.285) (xy 315.136001 160.410023) (xy 315.411239 160.476323) (xy 315.415729 160.447591)
				(xy 315.425899 160.444785) (xy 315.435757 160.451469) (xy 315.445956 160.457472)
			)
		)
	)
	(zone
		(net 193)
		(net_name "/OCuLink/PCIe_{REF0}.CK-")
		(layer "B.Cu")
		(name "$teardrop_padvia$")
		(hatch none 0.1)
		(priority 30536)
		(attr
			(teardrop
				(type padvia)
			)
		)
		(connect_pads yes
			(clearance 0)
		)
		(min_thickness 0.0254)
		(filled_areas_thickness no)
		(fill yes
			(thermal_gap 0.5)
			(thermal_bridge_width 0.5)
			(island_removal_mode 1)
			(island_area_min 10)
		)
		(polygon
			(pts
				(xy 207.002504 129.8315) (xy 207.164035 129.826105) (xy 207.248445 129.822554) (xy 207.35014 129.827177)
				(xy 207.371 129.6065) (xy 207.221147 129.443268) (xy 207.167007 129.511935) (xy 207.157115 129.528393)
				(xy 207.132615 129.567065) (xy 207.103109 129.599279) (xy 207.061953 129.621327) (xy 207.002504 129.6295)
			)
		)
	)
	(zone
		(net 244)
		(net_name "/Com Express 7 Interfaces/PCIe_{B2Bx4}.RX2+")
		(layer "B.Cu")
		(name "$teardrop_padvia$")
		(hatch none 0.1)
		(priority 30505)
		(attr
			(teardrop
				(type padvia)
			)
		)
		(connect_pads yes
			(clearance 0)
		)
		(min_thickness 0.0254)
		(filled_areas_thickness no)
		(fill yes
			(thermal_gap 0.5)
			(thermal_bridge_width 0.5)
			(island_removal_mode 1)
			(island_area_min 10)
		)
		(polygon
			(pts
				(xy 173.967496 96.8145) (xy 173.92071 96.809765) (xy 173.885258 96.796621) (xy 173.83706 96.751613)
				(xy 173.812884 96.713392) (xy 173.785514 96.670225) (xy 173.748852 96.628268) (xy 173.599 96.7915)
				(xy 173.61986 97.012177) (xy 173.720531 97.007548) (xy 173.803897 97.01098) (xy 173.805964 97.011105)
				(xy 173.967496 97.0165)
			)
		)
	)
	(zone
		(net 1)
		(net_name "GND")
		(layer "B.Cu")
		(name "$teardrop_padvia$")
		(hatch none 0.1)
		(priority 30086)
		(attr
			(teardrop
				(type padvia)
			)
		)
		(connect_pads yes
			(clearance 0)
		)
		(min_thickness 0.0254)
		(filled_areas_thickness no)
		(fill yes
			(thermal_gap 0.5)
			(thermal_bridge_width 0.5)
			(island_removal_mode 1)
			(island_area_min 10)
		)
		(polygon
			(pts
				(xy 154.7 131.86) (xy 154.6976 131.837487) (xy 154.695691 131.808689) (xy 154.710397 131.783908)
				(xy 154.758237 131.766544) (xy 154.855729 131.76) (xy 154.6 131.359) (xy 154.127056 131.683495)
				(xy 154.176222 131.699947) (xy 154.20621 131.720131) (xy 154.21988 131.740293) (xy 154.224195 131.761781)
				(xy 154.210612 131.819564) (xy 154.2 131.86)
			)
		)
	)
	(zone
		(net 626)
		(net_name "/PCIe redriver/TX_FG0")
		(layer "B.Cu")
		(name "$teardrop_padvia$")
		(hatch none 0.1)
		(priority 30914)
		(attr
			(teardrop
				(type padvia)
			)
		)
		(connect_pads yes
			(clearance 0)
		)
		(min_thickness 0.0254)
		(filled_areas_thickness no)
		(fill yes
			(thermal_gap 0.5)
			(thermal_bridge_width 0.5)
			(island_removal_mode 1)
			(island_area_min 10)
		)
		(polygon
			(pts
				(xy 113.9635 149.5355) (xy 113.963404 149.529178) (xy 113.968989 149.489675) (xy 113.983922 149.471452)
				(xy 114.0135 149.458504) (xy 113.901 149.047) (xy 113.7885 149.458504) (xy 113.815493 149.46962)
				(xy 113.830595 149.485147) (xy 113.838596 149.529178) (xy 113.8385 149.5355)
			)
		)
	)
	(zone
		(net 318)
		(net_name "Net-(J12D-LPC_SERIRQ{slash}~{ESPI_CS1})")
		(layer "B.Cu")
		(name "$teardrop_padvia$")
		(hatch none 0.1)
		(priority 30097)
		(attr
			(teardrop
				(type padvia)
			)
		)
		(connect_pads yes
			(clearance 0)
		)
		(min_thickness 0.0254)
		(filled_areas_thickness no)
		(fill yes
			(thermal_gap 0.5)
			(thermal_bridge_width 0.5)
			(island_removal_mode 1)
			(island_area_min 10)
		)
		(polygon
			(pts
				(xy 196.171993 163.841396) (xy 196.233423 163.786775) (xy 196.28932 163.750259) (xy 196.388191 163.717229)
				(xy 196.491905 163.70998) (xy 196.575099 163.706201) (xy 196.673159 163.692794) (xy 196.600707 163.324293)
				(xy 196.232206 163.251841) (xy 196.21583 163.405423) (xy 196.21502 163.433096) (xy 196.210967 163.512317)
				(xy 196.195512 163.587488) (xy 196.156956 163.665441) (xy 196.083604 163.753007)
			)
		)
	)
	(zone
		(net 683)
		(net_name "Net-(U45C-MODE_{SEL})")
		(layer "B.Cu")
		(name "$teardrop_padvia$")
		(hatch none 0.1)
		(priority 30768)
		(attr
			(teardrop
				(type padvia)
			)
		)
		(connect_pads yes
			(clearance 0)
		)
		(min_thickness 0.0254)
		(filled_areas_thickness no)
		(fill yes
			(thermal_gap 0.5)
			(thermal_bridge_width 0.5)
			(island_removal_mode 1)
			(island_area_min 10)
		)
		(polygon
			(pts
				(xy 131.050873 141.187515) (xy 131.103382 141.141819) (xy 131.149376 141.115231) (xy 131.235824 141.094847)
				(xy 131.25116 141.093011) (xy 131.333895 141.080677) (xy 131.290707 140.859293) (xy 131.069323 140.816105)
				(xy 131.056988 140.898841) (xy 131.036651 140.996119) (xy 131.009943 141.044159) (xy 130.962485 141.099127)
			)
		)
	)
	(zone
		(net 926)
		(net_name "Net-(J5-SUSCLK)")
		(layer "B.Cu")
		(name "$teardrop_padvia$")
		(hatch none 0.1)
		(priority 30817)
		(attr
			(teardrop
				(type padvia)
			)
		)
		(connect_pads yes
			(clearance 0)
		)
		(min_thickness 0.0254)
		(filled_areas_thickness no)
		(fill yes
			(thermal_gap 0.5)
			(thermal_bridge_width 0.5)
			(island_removal_mode 1)
			(island_area_min 10)
		)
		(polygon
			(pts
				(xy 177.8125 108.957123) (xy 177.817272 108.922385) (xy 177.83068 108.899833) (xy 177.87286 108.882104)
				(xy 177.94204 108.882773) (xy 178.043895 108.880677) (xy 178 108.659) (xy 177.779323 108.616105)
				(xy 177.74162 108.733191) (xy 177.733216 108.751868) (xy 177.701383 108.83506) (xy 177.6875 108.957123)
			)
		)
	)
	(zone
		(net 222)
		(net_name "/Com Express 7 Interfaces/PCIe_{B1x4}.RX0+")
		(layer "B.Cu")
		(name "$teardrop_padvia$")
		(hatch none 0.1)
		(priority 30178)
		(attr
			(teardrop
				(type padvia)
			)
		)
		(connect_pads yes
			(clearance 0)
		)
		(min_thickness 0.0254)
		(filled_areas_thickness no)
		(fill yes
			(thermal_gap 0.5)
			(thermal_bridge_width 0.5)
			(island_removal_mode 1)
			(island_area_min 10)
		)
		(polygon
			(pts
				(xy 198.736209 138.038289) (xy 198.716851 138.030775) (xy 198.54976 137.955364) (xy 198.465503 137.897126)
				(xy 198.395793 137.820202) (xy 198.192292 138.069249) (xy 198.332428 138.347719) (xy 198.421371 138.249654)
				(xy 198.495635 138.191728) (xy 198.53344 138.176752) (xy 198.569308 138.174841) (xy 198.593375 138.181123)
			)
		)
	)
	(zone
		(net 2)
		(net_name "+3V3")
		(layer "B.Cu")
		(name "$teardrop_padvia$")
		(hatch none 0.1)
		(priority 30800)
		(attr
			(teardrop
				(type padvia)
			)
		)
		(connect_pads yes
			(clearance 0)
		)
		(min_thickness 0.0254)
		(filled_areas_thickness no)
		(fill yes
			(thermal_gap 0.5)
			(thermal_bridge_width 0.5)
			(island_removal_mode 1)
			(island_area_min 10)
		)
		(polygon
			(pts
				(xy 193.999732 138.56127) (xy 194.045119 138.613463) (xy 194.07154 138.659243) (xy 194.09169 138.745302)
				(xy 194.093525 138.761066) (xy 194.105863 138.844999) (xy 194.327247 138.801811) (xy 194.370435 138.580427)
				(xy 194.288921 138.568105) (xy 194.191335 138.547401) (xy 194.143229 138.520529) (xy 194.088121 138.472882)
			)
		)
	)
	(zone
		(net 657)
		(net_name "Net-(U43A-~{PDTRXA})")
		(layer "B.Cu")
		(name "$teardrop_padvia$")
		(hatch none 0.1)
		(priority 30439)
		(attr
			(teardrop
				(type padvia)
			)
		)
		(connect_pads yes
			(clearance 0)
		)
		(min_thickness 0.0254)
		(filled_areas_thickness no)
		(fill yes
			(thermal_gap 0.5)
			(thermal_bridge_width 0.5)
			(island_removal_mode 1)
			(island_area_min 10)
		)
		(polygon
			(pts
				(xy 157.007 139.4225) (xy 157.066412 139.442273) (xy 157.122497 139.505547) (xy 157.144199 139.554172)
				(xy 157.158873 139.613531) (xy 157.160653 139.6255) (xy 157.421 139.36) (xy 157.160653 139.0945)
				(xy 157.147804 139.154638) (xy 157.12787 139.204522) (xy 157.101945 139.244641) (xy 157.072125 139.273654)
				(xy 157.040707 139.291146) (xy 157.008896 139.297479) (xy 157.007 139.2975)
			)
		)
	)
	(zone
		(net 53)
		(net_name "/2xSFP+/SH")
		(layer "B.Cu")
		(name "$teardrop_padvia$")
		(hatch none 0.1)
		(priority 30205)
		(attr
			(teardrop
				(type padvia)
			)
		)
		(connect_pads yes
			(clearance 0)
		)
		(min_thickness 0.0254)
		(filled_areas_thickness no)
		(fill yes
			(thermal_gap 0.5)
			(thermal_bridge_width 0.5)
			(island_removal_mode 1)
			(island_area_min 10)
		)
		(polygon
			(pts
				(xy 118.15 169.348) (xy 118.149662 169.33113) (xy 118.150241 169.286174) (xy 118.162059 169.238831)
				(xy 118.196638 169.196427) (xy 118.2655 169.166291) (xy 118 168.909) (xy 117.7345 169.166291) (xy 117.779269 169.181848)
				(xy 117.810885 169.202565) (xy 117.843619 169.253701) (xy 117.850338 169.33113) (xy 117.85 169.348)
			)
		)
	)
	(zone
		(net 1)
		(net_name "GND")
		(layer "B.Cu")
		(name "$teardrop_padvia$")
		(hatch none 0.1)
		(priority 30228)
		(attr
			(teardrop
				(type padvia)
			)
		)
		(connect_pads yes
			(clearance 0)
		)
		(min_thickness 0.0254)
		(filled_areas_thickness no)
		(fill yes
			(thermal_gap 0.5)
			(thermal_bridge_width 0.5)
			(island_removal_mode 1)
			(island_area_min 10)
		)
		(polygon
			(pts
				(xy 98.260083 159.300249) (xy 98.361963 159.299881) (xy 98.520574 159.302749) (xy 98.609352 159.100249)
				(xy 98.520574 158.897749) (xy 98.361952 158.900616) (xy 98.260083 158.900249)
			)
		)
	)
	(zone
		(net 2)
		(net_name "+3V3")
		(layer "B.Cu")
		(name "$teardrop_padvia$")
		(hatch none 0.1)
		(priority 30917)
		(attr
			(teardrop
				(type padvia)
			)
		)
		(connect_pads yes
			(clearance 0)
		)
		(min_thickness 0.0254)
		(filled_areas_thickness no)
		(fill yes
			(thermal_gap 0.5)
			(thermal_bridge_width 0.5)
			(island_removal_mode 1)
			(island_area_min 10)
		)
		(polygon
			(pts
				(xy 117.3385 145.1855) (xy 117.338596 145.191822) (xy 117.333011 145.231325) (xy 117.318078 145.249547)
				(xy 117.2885 145.262495) (xy 117.401 145.674) (xy 117.5135 145.262495) (xy 117.486507 145.251379)
				(xy 117.471405 145.235852) (xy 117.463404 145.191822) (xy 117.4635 145.1855)
			)
		)
	)
	(zone
		(net 529)
		(net_name "/M.2 key M #1/~{CLKREQ}")
		(layer "B.Cu")
		(name "$teardrop_padvia$")
		(hatch none 0.1)
		(priority 30318)
		(attr
			(teardrop
				(type padvia)
			)
		)
		(connect_pads yes
			(clearance 0)
		)
		(min_thickness 0.0254)
		(filled_areas_thickness no)
		(fill yes
			(thermal_gap 0.5)
			(thermal_bridge_width 0.5)
			(island_removal_mode 1)
			(island_area_min 10)
		)
		(polygon
			(pts
				(xy 178.03 105.6725) (xy 178.068823 105.683438) (xy 178.083933 105.705195) (xy 178.09 105.745) (xy 178.841 105.61)
				(xy 178.09 105.475) (xy 178.085483 105.510281) (xy 178.073862 105.531797) (xy 178.041039 105.546995)
				(xy 178.03 105.5475)
			)
		)
	)
	(zone
		(net 716)
		(net_name "Net-(U40-SDA)")
		(layer "B.Cu")
		(name "$teardrop_padvia$")
		(hatch none 0.1)
		(priority 30900)
		(attr
			(teardrop
				(type padvia)
			)
		)
		(connect_pads yes
			(clearance 0)
		)
		(min_thickness 0.0254)
		(filled_areas_thickness no)
		(fill yes
			(thermal_gap 0.5)
			(thermal_bridge_width 0.5)
			(island_removal_mode 1)
			(island_area_min 10)
		)
		(polygon
			(pts
				(xy 196.499481 131.887014) (xy 196.495079 131.891551) (xy 196.463196 131.915536) (xy 196.439751 131.917862)
				(xy 196.40968 131.906102) (xy 196.198253 132.27663) (xy 196.56878 132.065202) (xy 196.557553 132.038254)
				(xy 196.557854 132.016596) (xy 196.583331 131.979802) (xy 196.587868 131.975401)
			)
		)
	)
	(zone
		(net 217)
		(net_name "/Com Express 7 Interfaces/PCIe_{B1x4}.RX1-")
		(layer "B.Cu")
		(name "$teardrop_padvia$")
		(hatch none 0.1)
		(priority 30166)
		(attr
			(teardrop
				(type padvia)
			)
		)
		(connect_pads yes
			(clearance 0)
		)
		(min_thickness 0.0254)
		(filled_areas_thickness no)
		(fill yes
			(thermal_gap 0.5)
			(thermal_bridge_width 0.5)
			(island_removal_mode 1)
			(island_area_min 10)
		)
		(polygon
			(pts
				(xy 199.287046 140.160316) (xy 199.280072 140.128671) (xy 199.283745 140.096102) (xy 199.323494 140.024515)
				(xy 199.453641 139.89937) (xy 199.175171 139.759234) (xy 198.926124 139.962735) (xy 199.008719 140.039257)
				(xy 199.080625 140.15282) (xy 199.136693 140.283784) (xy 199.144211 140.303151)
			)
		)
	)
	(zone
		(net 489)
		(net_name "Net-(J12K-10G_SDP1)")
		(layer "B.Cu")
		(name "$teardrop_padvia$")
		(hatch none 0.1)
		(priority 30093)
		(attr
			(teardrop
				(type padvia)
			)
		)
		(connect_pads yes
			(clearance 0)
		)
		(min_thickness 0.0254)
		(filled_areas_thickness no)
		(fill yes
			(thermal_gap 0.5)
			(thermal_bridge_width 0.5)
			(island_removal_mode 1)
			(island_area_min 10)
		)
		(polygon
			(pts
				(xy 194.2875 150.532206) (xy 194.282685 150.614266) (xy 194.268981 150.679611) (xy 194.222424 150.772879)
				(xy 194.154214 150.851341) (xy 194.098058 150.912841) (xy 194.038199 150.991661) (xy 194.35 151.201)
				(xy 194.661801 150.991661) (xy 194.564781 150.871482) (xy 194.545786 150.851341) (xy 194.492634 150.792458)
				(xy 194.450408 150.728375) (xy 194.42255 150.645992) (xy 194.4125 150.532206)
			)
		)
	)
	(zone
		(net 439)
		(net_name "Net-(J12L-RAPID_SHUTDOWN)")
		(layer "B.Cu")
		(name "$teardrop_padvia$")
		(hatch none 0.1)
		(priority 30687)
		(attr
			(teardrop
				(type padvia)
			)
		)
		(connect_pads yes
			(clearance 0)
		)
		(min_thickness 0.0254)
		(filled_areas_thickness no)
		(fill yes
			(thermal_gap 0.5)
			(thermal_bridge_width 0.5)
			(island_removal_mode 1)
			(island_area_min 10)
		)
		(polygon
			(pts
				(xy 208.7875 157.649323) (xy 208.782682 157.718763) (xy 208.76896 157.770087) (xy 208.722245 157.845628)
				(xy 208.712702 157.857768) (xy 208.662919 157.924997) (xy 208.85 158.051) (xy 209.037081 157.924997)
				(xy 208.987299 157.857769) (xy 208.932894 157.774603) (xy 208.91781 157.721748) (xy 208.9125 157.649323)
			)
		)
	)
	(zone
		(net 200)
		(net_name "/OCuLink/~{PERST_D0}")
		(layer "B.Cu")
		(name "$teardrop_padvia$")
		(hatch none 0.1)
		(priority 30812)
		(attr
			(teardrop
				(type padvia)
			)
		)
		(connect_pads yes
			(clearance 0)
		)
		(min_thickness 0.0254)
		(filled_areas_thickness no)
		(fill yes
			(thermal_gap 0.5)
			(thermal_bridge_width 0.5)
			(island_removal_mode 1)
			(island_area_min 10)
		)
		(polygon
			(pts
				(xy 103.219323 162.1725) (xy 103.284831 162.17728) (xy 103.333726 162.19074) (xy 103.405236 162.236605)
				(xy 103.420322 162.249308) (xy 103.494997 162.307081) (xy 103.621 162.12) (xy 103.494997 161.932919)
				(xy 103.437927 161.973503) (xy 103.349214 162.028076) (xy 103.294496 162.042529) (xy 103.219323 162.0475)
			)
		)
	)
	(zone
		(net 656)
		(net_name "Net-(U43C-PRTAD1)")
		(layer "B.Cu")
		(name "$teardrop_padvia$")
		(hatch none 0.1)
		(priority 30363)
		(attr
			(teardrop
				(type padvia)
			)
		)
		(connect_pads yes
			(clearance 0)
		)
		(min_thickness 0.0254)
		(filled_areas_thickness no)
		(fill yes
			(thermal_gap 0.5)
			(thermal_bridge_width 0.5)
			(island_removal_mode 1)
			(island_area_min 10)
		)
		(polygon
			(pts
				(xy 144.7925 137.498) (xy 144.812469 137.435134) (xy 144.838921 137.403156) (xy 144.876332 137.374642)
				(xy 144.923527 137.352118) (xy 144.981167 137.336907) (xy 144.981798 137.336798) (xy 144.73 137.059)
				(xy 144.478202 137.336798) (xy 144.533635 137.351095) (xy 144.57952 137.372175) (xy 144.617201 137.39954)
				(xy 144.644434 137.430448) (xy 144.661472 137.463735) (xy 144.667489 137.496566) (xy 144.6675 137.498)
			)
		)
	)
	(zone
		(net 54)
		(net_name "/USB-C console/SH")
		(layer "B.Cu")
		(name "$teardrop_padvia$")
		(hatch none 0.1)
		(priority 30033)
		(attr
			(teardrop
				(type padvia)
			)
		)
		(connect_pads yes
			(clearance 0)
		)
		(min_thickness 0.0254)
		(filled_areas_thickness no)
		(fill yes
			(thermal_gap 0.5)
			(thermal_bridge_width 0.5)
			(island_removal_mode 1)
			(island_area_min 10)
		)
		(polygon
			(pts
				(xy 105.208607 88.197) (xy 105.245236 88.196613) (xy 105.35436 88.198165) (xy 105.474176 88.219003)
				(xy 105.534817 88.242785) (xy 105.594198 88.278743) (xy 105.651009 88.329331) (xy 105.703938 88.397)
				(xy 106.425 87.947) (xy 105.703938 87.497) (xy 105.661137 87.553506) (xy 105.615597 87.598367) (xy 105.51487 87.660294)
				(xy 105.398291 87.691378) (xy 105.245236 87.697387) (xy 105.208607 87.697)
			)
		)
	)
	(zone
		(net 212)
		(net_name "/Com Express 7 Interfaces/PCIe_{B1x4}.TX3+")
		(layer "B.Cu")
		(name "$teardrop_padvia$")
		(hatch none 0.1)
		(priority 30490)
		(attr
			(teardrop
				(type padvia)
			)
		)
		(connect_pads yes
			(clearance 0)
		)
		(min_thickness 0.0254)
		(filled_areas_thickness no)
		(fill yes
			(thermal_gap 0.5)
			(thermal_bridge_width 0.5)
			(island_removal_mode 1)
			(island_area_min 10)
		)
		(polygon
			(pts
				(xy 204.4795 164.932504) (xy 204.474765 164.97929) (xy 204.461621 165.014742) (xy 204.416613 165.062939)
				(xy 204.378393 165.087115) (xy 204.335226 165.114484) (xy 204.293268 165.151147) (xy 204.4565 165.301)
				(xy 204.677177 165.28014) (xy 204.672548 165.179469) (xy 204.67598 165.096102) (xy 204.676105 165.094035)
				(xy 204.6815 164.932504)
			)
		)
	)
	(zone
		(net 656)
		(net_name "Net-(U43C-PRTAD1)")
		(layer "B.Cu")
		(name "$teardrop_padvia$")
		(hatch none 0.1)
		(priority 30368)
		(attr
			(teardrop
				(type padvia)
			)
		)
		(connect_pads yes
			(clearance 0)
		)
		(min_thickness 0.0254)
		(filled_areas_thickness no)
		(fill yes
			(thermal_gap 0.5)
			(thermal_bridge_width 0.5)
			(island_removal_mode 1)
			(island_area_min 10)
		)
		(polygon
			(pts
				(xy 144.6675 137.622) (xy 144.647531 137.684866) (xy 144.621079 137.716844) (xy 144.583668 137.745358)
				(xy 144.536473 137.767882) (xy 144.478833 137.783093) (xy 144.478202 137.783202) (xy 144.73 138.061)
				(xy 144.981798 137.783202) (xy 144.926365 137.768905) (xy 144.88048 137.747825) (xy 144.842799 137.72046)
				(xy 144.815566 137.689552) (xy 144.798528 137.656265) (xy 144.792511 137.623434) (xy 144.7925 137.622)
			)
		)
	)
	(zone
		(net 869)
		(net_name "/Backplane/PCIe_{x2}.TX1-")
		(layer "B.Cu")
		(name "$teardrop_padvia$")
		(hatch none 0.1)
		(priority 30938)
		(attr
			(teardrop
				(type padvia)
			)
		)
		(connect_pads yes
			(clearance 0)
		)
		(min_thickness 0.0254)
		(filled_areas_thickness no)
		(fill yes
			(thermal_gap 0.5)
			(thermal_bridge_width 0.5)
			(island_removal_mode 1)
			(island_area_min 10)
		)
		(polygon
			(pts
				(xy 314.04 161.9535) (xy 314.053941 161.948168) (xy 314.078365 161.941442) (xy 314.087289 161.950549)
				(xy 314.090953 161.975292) (xy 314.366 161.908) (xy 314.302083 161.783) (xy 314.219652 161.792335)
				(xy 314.119272 161.769146) (xy 314.04 161.7515)
			)
		)
	)
	(zone
		(net 170)
		(net_name "/2xSFP+/SFI0.RX-")
		(layer "B.Cu")
		(name "$teardrop_padvia$")
		(hatch none 0.1)
		(priority 30624)
		(attr
			(teardrop
				(type padvia)
			)
		)
		(connect_pads yes
			(clearance 0)
		)
		(min_thickness 0.0254)
		(filled_areas_thickness no)
		(fill yes
			(thermal_gap 0.5)
			(thermal_bridge_width 0.5)
			(island_removal_mode 1)
			(island_area_min 10)
		)
		(polygon
			(pts
				(xy 150.22 147.977084) (xy 150.224756 147.936299) (xy 150.238046 147.906971) (xy 150.282406 147.872311)
				(xy 150.325219 147.855729) (xy 150.410003 147.817081) (xy 150.285 147.629) (xy 150.064323 147.632143)
				(xy 150.062568 147.797771) (xy 150.06 147.977084)
			)
		)
	)
	(zone
		(net 707)
		(net_name "Net-(U24-TACH3)")
		(layer "B.Cu")
		(name "$teardrop_padvia$")
		(hatch none 0.1)
		(priority 30106)
		(attr
			(teardrop
				(type padvia)
			)
		)
		(connect_pads yes
			(clearance 0)
		)
		(min_thickness 0.0254)
		(filled_areas_thickness no)
		(fill yes
			(thermal_gap 0.5)
			(thermal_bridge_width 0.5)
			(island_removal_mode 1)
			(island_area_min 10)
		)
		(polygon
			(pts
				(xy 259.617794 84.3475) (xy 259.535734 84.342685) (xy 259.470388 84.328981) (xy 259.377121 84.282424)
				(xy 259.298658 84.214214) (xy 259.237159 84.158058) (xy 259.158339 84.098199) (xy 258.949 84.41)
				(xy 259.158339 84.721801) (xy 259.278517 84.62478) (xy 259.298657 84.605787) (xy 259.357541 84.552634)
				(xy 259.421624 84.510409) (xy 259.504008 84.482551) (xy 259.617794 84.4725)
			)
		)
	)
	(zone
		(net 533)
		(net_name "/Com Express 7 MGMT/PSON")
		(layer "B.Cu")
		(name "$teardrop_padvia$")
		(hatch none 0.1)
		(priority 30127)
		(attr
			(teardrop
				(type padvia)
			)
		)
		(connect_pads yes
			(clearance 0)
		)
		(min_thickness 0.0254)
		(filled_areas_thickness no)
		(fill yes
			(thermal_gap 0.5)
			(thermal_bridge_width 0.5)
			(island_removal_mode 1)
			(island_area_min 10)
		)
		(polygon
			(pts
				(xy 306.587 103.48) (xy 306.606721 103.42274) (xy 306.669533 103.370216) (xy 306.718153 103.350449)
				(xy 306.777451 103.337923) (xy 306.7945 103.336072) (xy 306.5245 102.859) (xy 306.2545 103.336072)
				(xy 306.315744 103.346248) (xy 306.366671 103.363925) (xy 306.407514 103.387823) (xy 306.437197 103.416022)
				(xy 306.45513 103.446012) (xy 306.461941 103.476862) (xy 306.462 103.48)
			)
		)
	)
	(zone
		(net 630)
		(net_name "Net-(U40-RXDET)")
		(layer "B.Cu")
		(name "$teardrop_padvia$")
		(hatch none 0.1)
		(priority 30896)
		(attr
			(teardrop
				(type padvia)
			)
		)
		(connect_pads yes
			(clearance 0)
		)
		(min_thickness 0.0254)
		(filled_areas_thickness no)
		(fill yes
			(thermal_gap 0.5)
			(thermal_bridge_width 0.5)
			(island_removal_mode 1)
			(island_area_min 10)
		)
		(polygon
			(pts
				(xy 197.647821 134.96293) (xy 197.643384 134.958624) (xy 197.619737 134.927031) (xy 197.617656 134.90377)
				(xy 197.629737 134.873915) (xy 197.258913 134.660994) (xy 197.468858 135.031226) (xy 197.495916 135.020301)
				(xy 197.51769 135.020781) (xy 197.554934 135.046677) (xy 197.559434 135.051317)
			)
		)
	)
	(zone
		(net 576)
		(net_name "Net-(U19-MODE)")
		(layer "B.Cu")
		(name "$teardrop_padvia$")
		(hatch none 0.1)
		(priority 30198)
		(attr
			(teardrop
				(type padvia)
			)
		)
		(connect_pads yes
			(clearance 0)
		)
		(min_thickness 0.0254)
		(filled_areas_thickness no)
		(fill yes
			(thermal_gap 0.5)
			(thermal_bridge_width 0.5)
			(island_removal_mode 1)
			(island_area_min 10)
		)
		(polygon
			(pts
				(xy 309.502949 106.040438) (xy 309.581289 105.989788) (xy 309.704271 105.959586) (xy 309.87068 105.961975)
				(xy 309.892925 105.965) (xy 309.825706 105.669293) (xy 309.504999 105.599441) (xy 309.504099 105.746329)
				(xy 309.489868 105.813957) (xy 309.467988 105.872903) (xy 309.414561 105.95205)
			)
		)
	)
	(zone
		(net 868)
		(net_name "/Backplane/PCIe_{x2}.TX1+")
		(layer "B.Cu")
		(name "$teardrop_padvia$")
		(hatch none 0.1)
		(priority 30045)
		(attr
			(teardrop
				(type padvia)
			)
		)
		(connect_pads yes
			(clearance 0)
		)
		(min_thickness 0.0254)
		(filled_areas_thickness no)
		(fill yes
			(thermal_gap 0.5)
			(thermal_bridge_width 0.5)
			(island_removal_mode 1)
			(island_area_min 10)
		)
		(polygon
			(pts
				(xy 317.860744 162.0165) (xy 318.255858 161.999246) (xy 318.69849 161.977362) (xy 318.959827 161.975348)
				(xy 319.254117 161.985) (xy 319.451 161.71) (xy 317.95 161.654408) (xy 317.950007 161.713332) (xy 317.940774 161.756415)
				(xy 317.925619 161.784485) (xy 317.906098 161.802295) (xy 317.860744 161.8145)
			)
		)
	)
	(zone
		(net 373)
		(net_name "Net-(J12D-~{THRM})")
		(layer "B.Cu")
		(name "$teardrop_padvia$")
		(hatch none 0.1)
		(priority 30424)
		(attr
			(teardrop
				(type padvia)
			)
		)
		(connect_pads yes
			(clearance 0)
		)
		(min_thickness 0.0254)
		(filled_areas_thickness no)
		(fill yes
			(thermal_gap 0.5)
			(thermal_bridge_width 0.5)
			(island_removal_mode 1)
			(island_area_min 10)
		)
		(polygon
			(pts
				(xy 192.9375 165.007) (xy 192.917727 165.066412) (xy 192.854453 165.122496) (xy 192.805828 165.144198)
				(xy 192.746469 165.158872) (xy 192.7345 165.160652) (xy 193 165.421) (xy 193.2655 165.160652) (xy 193.205362 165.147803)
				(xy 193.155478 165.127869) (xy 193.115358 165.101944) (xy 193.086345 165.072124) (xy 193.068854 165.040706)
				(xy 193.062521 165.008895) (xy 193.0625 165.007)
			)
		)
	)
	(zone
		(net 243)
		(net_name "/Com Express 7 Interfaces/PCIe_{B2Bx4}.RX2-")
		(layer "B.Cu")
		(name "$teardrop_padvia$")
		(hatch none 0.1)
		(priority 30302)
		(attr
			(teardrop
				(type padvia)
			)
		)
		(connect_pads yes
			(clearance 0)
		)
		(min_thickness 0.0254)
		(filled_areas_thickness no)
		(fill yes
			(thermal_gap 0.5)
			(thermal_bridge_width 0.5)
			(island_removal_mode 1)
			(island_area_min 10)
		)
		(polygon
			(pts
				(xy 175.39 97.461) (xy 175.404678 97.457463) (xy 175.434685 97.454192) (xy 175.445673 97.466143)
				(xy 175.45 97.495) (xy 176.201 97.36) (xy 175.45 97.225) (xy 175.445525 97.254204) (xy 175.434203 97.265997)
				(xy 175.404678 97.262537) (xy 175.39 97.259)
			)
		)
	)
	(zone
		(net 1)
		(net_name "GND")
		(layer "B.Cu")
		(name "$teardrop_padvia$")
		(hatch none 0.1)
		(priority 30347)
		(attr
			(teardrop
				(type padvia)
			)
		)
		(connect_pads yes
			(clearance 0)
		)
		(min_thickness 0.0254)
		(filled_areas_thickness no)
		(fill yes
			(thermal_gap 0.5)
			(thermal_bridge_width 0.5)
			(island_removal_mode 1)
			(island_area_min 10)
		)
		(polygon
			(pts
				(xy 137.488 169.5775) (xy 137.425134 169.557531) (xy 137.393156 169.531079) (xy 137.364642 169.493668)
				(xy 137.342118 169.446473) (xy 137.326907 169.388833) (xy 137.326798 169.388202) (xy 137.049 169.64)
				(xy 137.326798 169.891798) (xy 137.341095 169.836365) (xy 137.362175 169.79048) (xy 137.38954 169.752799)
				(xy 137.420448 169.725566) (xy 137.453735 169.708528) (xy 137.486566 169.702511) (xy 137.488 169.7025)
			)
		)
	)
	(zone
		(net 218)
		(net_name "/Com Express 7 Interfaces/PCIe_{B1x4}.RX1+")
		(layer "B.Cu")
		(name "$teardrop_padvia$")
		(hatch none 0.1)
		(priority 30493)
		(attr
			(teardrop
				(type padvia)
			)
		)
		(connect_pads yes
			(clearance 0)
		)
		(min_thickness 0.0254)
		(filled_areas_thickness no)
		(fill yes
			(thermal_gap 0.5)
			(thermal_bridge_width 0.5)
			(island_removal_mode 1)
			(island_area_min 10)
		)
		(polygon
			(pts
				(xy 207.4795 161.032504) (xy 207.474765 161.07929) (xy 207.461621 161.114742) (xy 207.416613 161.162939)
				(xy 207.378393 161.187115) (xy 207.335226 161.214484) (xy 207.293268 161.251147) (xy 207.4565 161.401)
				(xy 207.677177 161.38014) (xy 207.672548 161.279469) (xy 207.67598 161.196102) (xy 207.676105 161.194035)
				(xy 207.6815 161.032504)
			)
		)
	)
	(zone
		(net 160)
		(net_name "/2xUSB3.0+RJ45/USBSS_2.RX-")
		(layer "B.Cu")
		(name "$teardrop_padvia$")
		(hatch none 0.1)
		(priority 30024)
		(attr
			(teardrop
				(type padvia)
			)
		)
		(connect_pads yes
			(clearance 0)
		)
		(min_thickness 0.0254)
		(filled_areas_thickness no)
		(fill yes
			(thermal_gap 0.5)
			(thermal_bridge_width 0.5)
			(island_removal_mode 1)
			(island_area_min 10)
		)
		(polygon
			(pts
				(xy 112.301715 108.463142) (xy 112.15348 108.470239) (xy 112.031251 108.485371) (xy 111.836417 108.534773)
				(xy 111.709512 108.582681) (xy 111.541257 108.64504) (xy 111.318314 108.70297) (xy 111.449001 109.365015)
				(xy 112.11203 109.496686) (xy 112.12394 109.347751) (xy 112.105564 109.155353) (xy 112.094274 109.083129)
				(xy 112.071816 108.915584) (xy 112.070469 108.842286) (xy 112.080446 108.778222) (xy 112.105301 108.725084)
				(xy 112.148585 108.684561) (xy 112.213852 108.658342) (xy 112.304653 108.648118)
			)
		)
	)
	(zone
		(net 168)
		(net_name "Net-(J2A-RX_{LOS})")
		(layer "B.Cu")
		(name "$teardrop_padvia$")
		(hatch none 0.1)
		(priority 30423)
		(attr
			(teardrop
				(type padvia)
			)
		)
		(connect_pads yes
			(clearance 0)
		)
		(min_thickness 0.0254)
		(filled_areas_thickness no)
		(fill yes
			(thermal_gap 0.5)
			(thermal_bridge_width 0.5)
			(island_removal_mode 1)
			(island_area_min 10)
		)
		(polygon
			(pts
				(xy 144.9875 168.267) (xy 144.967727 168.326412) (xy 144.904453 168.382496) (xy 144.855828 168.404198)
				(xy 144.796469 168.418872) (xy 144.7845 168.420652) (xy 145.05 168.681) (xy 145.3155 168.420652)
				(xy 145.255362 168.407803) (xy 145.205478 168.387869) (xy 145.165358 168.361944) (xy 145.136345 168.332124)
				(xy 145.118854 168.300706) (xy 145.112521 168.268895) (xy 145.1125 168.267)
			)
		)
	)
	(zone
		(net 187)
		(net_name "/OCuLink/PCIe_{x4}.RX0-")
		(layer "B.Cu")
		(name "$teardrop_padvia$")
		(hatch none 0.1)
		(priority 30517)
		(attr
			(teardrop
				(type padvia)
			)
		)
		(connect_pads yes
			(clearance 0)
		)
		(min_thickness 0.0254)
		(filled_areas_thickness no)
		(fill yes
			(thermal_gap 0.5)
			(thermal_bridge_width 0.5)
			(island_removal_mode 1)
			(island_area_min 10)
		)
		(polygon
			(pts
				(xy 99.397496 165.5595) (xy 99.35071 165.554765) (xy 99.315258 165.541621) (xy 99.26706 165.496613)
				(xy 99.242884 165.458392) (xy 99.215514 165.415225) (xy 99.178852 165.373268) (xy 99.029 165.5365)
				(xy 99.04986 165.757177) (xy 99.150531 165.752548) (xy 99.233897 165.75598) (xy 99.235964 165.756105)
				(xy 99.397496 165.7615)
			)
		)
	)
	(zone
		(net 53)
		(net_name "/2xSFP+/SH")
		(layer "B.Cu")
		(name "$teardrop_padvia$")
		(hatch none 0.1)
		(priority 30014)
		(attr
			(teardrop
				(type padvia)
			)
		)
		(connect_pads yes
			(clearance 0)
		)
		(min_thickness 0.0254)
		(filled_areas_thickness no)
		(fill yes
			(thermal_gap 0.5)
			(thermal_bridge_width 0.5)
			(island_removal_mode 1)
			(island_area_min 10)
		)
		(polygon
			(pts
				(xy 117.785589 169.285) (xy 117.661824 169.280126) (xy 117.556865 169.266004) (xy 117.472229 169.244911)
				(xy 117.398644 169.216905) (xy 117.268431 169.138799) (xy 117.133797 169.024942) (xy 117.015402 168.922104)
				(xy 116.866678 168.811398) (xy 116.449 169.435) (xy 116.866678 170.058602) (xy 117.055228 169.914406)
				(xy 117.133796 169.845058) (xy 117.256074 169.740584) (xy 117.387489 169.658282) (xy 117.465048 169.627384)
				(xy 117.555005 169.604354) (xy 117.660728 169.589968) (xy 117.785589 169.585)
			)
		)
	)
	(zone
		(net 1)
		(net_name "GND")
		(layer "B.Cu")
		(name "$teardrop_padvia$")
		(hatch none 0.1)
		(priority 30617)
		(attr
			(teardrop
				(type padvia)
			)
		)
		(connect_pads yes
			(clearance 0)
		)
		(min_thickness 0.0254)
		(filled_areas_thickness no)
		(fill yes
			(thermal_gap 0.5)
			(thermal_bridge_width 0.5)
			(island_removal_mode 1)
			(island_area_min 10)
		)
		(polygon
			(pts
				(xy 140.570873 137.677515) (xy 140.614902 137.640191) (xy 140.655133 137.618607) (xy 140.731039 137.606332)
				(xy 140.764576 137.6072) (xy 140.819648 137.607918) (xy 140.883895 137.600677) (xy 140.840707 137.379293)
				(xy 140.643111 137.278674) (xy 140.596426 137.397868) (xy 140.562016 137.486729) (xy 140.531003 137.53445)
				(xy 140.482485 137.589127)
			)
		)
	)
	(zone
		(net 197)
		(net_name "/OCuLink/PCIe_{x4}.RX3-")
		(layer "B.Cu")
		(name "$teardrop_padvia$")
		(hatch none 0.1)
		(priority 30850)
		(attr
			(teardrop
				(type padvia)
			)
		)
		(connect_pads yes
			(clearance 0)
		)
		(min_thickness 0.0254)
		(filled_areas_thickness no)
		(fill yes
			(thermal_gap 0.5)
			(thermal_bridge_width 0.5)
			(island_removal_mode 1)
			(island_area_min 10)
		)
		(polygon
			(pts
				(xy 190.528671 135.93025) (xy 190.620478 135.997407) (xy 190.723451 136.069618) (xy 190.774982 136.118379)
				(xy 190.823074 136.180106) (xy 190.984754 136.16501) (xy 190.719667 135.810225) (xy 190.698407 135.82518)
				(xy 190.686129 135.82198) (xy 190.677306 135.80164) (xy 190.671506 135.787415)
			)
		)
	)
	(zone
		(net 1)
		(net_name "GND")
		(layer "B.Cu")
		(name "$teardrop_padvia$")
		(hatch none 0.1)
		(priority 30249)
		(attr
			(teardrop
				(type padvia)
			)
		)
		(connect_pads yes
			(clearance 0)
		)
		(min_thickness 0.0254)
		(filled_areas_thickness no)
		(fill yes
			(thermal_gap 0.5)
			(thermal_bridge_width 0.5)
			(island_removal_mode 1)
			(island_area_min 10)
		)
		(polygon
			(pts
				(xy 176.779323 98.01) (xy 176.9369 98.016932) (xy 177.050434 98.045456) (xy 177.092222 98.0625)
				(xy 177.181 97.86) (xy 177.092222 97.6575) (xy 176.996177 97.691883) (xy 176.894296 97.707101) (xy 176.779323 97.71)
			)
		)
	)
	(zone
		(net 143)
		(net_name "/2xSFP+/KR to SFI #2/~{RESET}")
		(layer "B.Cu")
		(name "$teardrop_padvia$")
		(hatch none 0.1)
		(priority 30724)
		(attr
			(teardrop
				(type padvia)
			)
		)
		(connect_pads yes
			(clearance 0)
		)
		(min_thickness 0.0254)
		(filled_areas_thickness no)
		(fill yes
			(thermal_gap 0.5)
			(thermal_bridge_width 0.5)
			(island_removal_mode 1)
			(island_area_min 10)
		)
		(polygon
			(pts
				(xy 140.3125 136.210677) (xy 140.317318 136.141236) (xy 140.33104 136.089912) (xy 140.377755 136.01437)
				(xy 140.387299 136.002229) (xy 140.437081 135.935003) (xy 140.25 135.809) (xy 140.062919 135.935003)
				(xy 140.112701 136.002231) (xy 140.167106 136.085397) (xy 140.18219 136.138251) (xy 140.1875 136.210677)
			)
		)
	)
	(zone
		(net 160)
		(net_name "/2xUSB3.0+RJ45/USBSS_2.RX-")
		(layer "B.Cu")
		(name "$teardrop_padvia$")
		(hatch none 0.1)
		(priority 30578)
		(attr
			(teardrop
				(type padvia)
			)
		)
		(connect_pads yes
			(clearance 0)
		)
		(min_thickness 0.0254)
		(filled_areas_thickness no)
		(fill yes
			(thermal_gap 0.5)
			(thermal_bridge_width 0.5)
			(island_removal_mode 1)
			(island_area_min 10)
		)
		(polygon
			(pts
				(xy 127.5425 107.390416) (xy 127.53776 107.435027) (xy 127.524582 107.468424) (xy 127.479799 107.512019)
				(xy 127.43718 107.534851) (xy 127.389337 107.560508) (xy 127.343311 107.597104) (xy 127.5025 107.751)
				(xy 127.723177 107.737562) (xy 127.723316 107.554857) (xy 127.7275 107.390416)
			)
		)
	)
	(zone
		(net 574)
		(net_name "Net-(U19-EN)")
		(layer "B.Cu")
		(name "$teardrop_padvia$")
		(hatch none 0.1)
		(priority 30705)
		(attr
			(teardrop
				(type padvia)
			)
		)
		(connect_pads yes
			(clearance 0)
		)
		(min_thickness 0.0254)
		(filled_areas_thickness no)
		(fill yes
			(thermal_gap 0.5)
			(thermal_bridge_width 0.5)
			(island_removal_mode 1)
			(island_area_min 10)
		)
		(polygon
			(pts
				(xy 309.762499 103.898322) (xy 309.757681 103.967762) (xy 309.743959 104.019086) (xy 309.697244 104.094627)
				(xy 309.687701 104.106767) (xy 309.637918 104.173996) (xy 309.824999 104.299999) (xy 310.01208 104.173996)
				(xy 309.962298 104.106768) (xy 309.907893 104.023602) (xy 309.892809 103.970747) (xy 309.887499 103.898322)
			)
		)
	)
	(zone
		(net 204)
		(net_name "/Backplane/USB.D-")
		(layer "B.Cu")
		(name "$teardrop_padvia$")
		(hatch none 0.1)
		(priority 31024)
		(attr
			(teardrop
				(type padvia)
			)
		)
		(connect_pads yes
			(clearance 0)
		)
		(min_thickness 0.0254)
		(filled_areas_thickness no)
		(fill yes
			(thermal_gap 0.5)
			(thermal_bridge_width 0.5)
			(island_removal_mode 1)
			(island_area_min 10)
		)
		(polygon
			(pts
				(xy 314.69 166.6155) (xy 314.671153 166.6204) (xy 314.637892 166.626518) (xy 314.623353 166.618159)
				(xy 314.613005 166.5955) (xy 314.364 166.708) (xy 314.613005 166.8205) (xy 314.622976 166.798283)
				(xy 314.636951 166.789669) (xy 314.671153 166.7956) (xy 314.69 166.8005)
			)
		)
	)
	(zone
		(net 200)
		(net_name "/OCuLink/~{PERST_D0}")
		(layer "B.Cu")
		(name "$teardrop_padvia$")
		(hatch none 0.1)
		(priority 31031)
		(attr
			(teardrop
				(type padvia)
			)
		)
		(connect_pads yes
			(clearance 0)
		)
		(min_thickness 0.0254)
		(filled_areas_thickness no)
		(fill yes
			(thermal_gap 0.5)
			(thermal_bridge_width 0.5)
			(island_removal_mode 1)
			(island_area_min 10)
		)
		(polygon
			(pts
				(xy 104.055002 162.1825) (xy 104.062795 162.182354) (xy 104.105186 162.187474) (xy 104.125381 162.201827)
				(xy 104.140867 162.230426) (xy 104.381002 162.112) (xy 104.122979 162.005798) (xy 104.113978 162.034068)
				(xy 104.099916 162.049638) (xy 104.060137 162.057564) (xy 104.055002 162.0575)
			)
		)
	)
	(zone
		(net 662)
		(net_name "Net-(U43C-MODE_{SEL})")
		(layer "B.Cu")
		(name "$teardrop_padvia$")
		(hatch none 0.1)
		(priority 30769)
		(attr
			(teardrop
				(type padvia)
			)
		)
		(connect_pads yes
			(clearance 0)
		)
		(min_thickness 0.0254)
		(filled_areas_thickness no)
		(fill yes
			(thermal_gap 0.5)
			(thermal_bridge_width 0.5)
			(island_removal_mode 1)
			(island_area_min 10)
		)
		(polygon
			(pts
				(xy 149.210873 141.187515) (xy 149.263382 141.141819) (xy 149.309376 141.115231) (xy 149.395824 141.094847)
				(xy 149.41116 141.093011) (xy 149.493895 141.080677) (xy 149.450707 140.859293) (xy 149.229323 140.816105)
				(xy 149.216988 140.898841) (xy 149.196651 140.996119) (xy 149.169943 141.044159) (xy 149.122485 141.099127)
			)
		)
	)
	(zone
		(net 975)
		(net_name "/PCIe redriver/RX_FG0")
		(layer "B.Cu")
		(name "$teardrop_padvia$")
		(hatch none 0.1)
		(priority 30700)
		(attr
			(teardrop
				(type padvia)
			)
		)
		(connect_pads yes
			(clearance 0)
		)
		(min_thickness 0.0254)
		(filled_areas_thickness no)
		(fill yes
			(thermal_gap 0.5)
			(thermal_bridge_width 0.5)
			(island_removal_mode 1)
			(island_area_min 10)
		)
		(polygon
			(pts
				(xy 192.6275 140.279323) (xy 192.622682 140.348763) (xy 192.60896 140.400087) (xy 192.562245 140.475628)
				(xy 192.552702 140.487768) (xy 192.502919 140.554997) (xy 192.69 140.681) (xy 192.877081 140.554997)
				(xy 192.827299 140.487769) (xy 192.772894 140.404603) (xy 192.75781 140.351748) (xy 192.7525 140.279323)
			)
		)
	)
	(zone
		(net 154)
		(net_name "Net-(J1A-LED_D1)")
		(layer "B.Cu")
		(name "$teardrop_padvia$")
		(hatch none 0.1)
		(priority 30350)
		(attr
			(teardrop
				(type padvia)
			)
		)
		(connect_pads yes
			(clearance 0)
		)
		(min_thickness 0.0254)
		(filled_areas_thickness no)
		(fill yes
			(thermal_gap 0.5)
			(thermal_bridge_width 0.5)
			(island_removal_mode 1)
			(island_area_min 10)
		)
		(polygon
			(pts
				(xy 122.9825 96.298) (xy 123.002469 96.235134) (xy 123.028921 96.203156) (xy 123.066332 96.174642)
				(xy 123.113527 96.152118) (xy 123.171167 96.136907) (xy 123.171798 96.136798) (xy 122.92 95.859)
				(xy 122.668202 96.136798) (xy 122.723635 96.151095) (xy 122.76952 96.172175) (xy 122.807201 96.19954)
				(xy 122.834434 96.230448) (xy 122.851472 96.263735) (xy 122.857489 96.296566) (xy 122.8575 96.298)
			)
		)
	)
	(zone
		(net 1)
		(net_name "GND")
		(layer "B.Cu")
		(name "$teardrop_padvia$")
		(hatch none 0.1)
		(priority 30311)
		(attr
			(teardrop
				(type padvia)
			)
		)
		(connect_pads yes
			(clearance 0)
		)
		(min_thickness 0.0254)
		(filled_areas_thickness no)
		(fill yes
			(thermal_gap 0.5)
			(thermal_bridge_width 0.5)
			(island_removal_mode 1)
			(island_area_min 10)
		)
		(polygon
			(pts
				(xy 219.6 166.593) (xy 219.605772 166.552263) (xy 219.626176 166.510348) (xy 219.653351 166.482047)
				(xy 219.692897 166.458618) (xy 219.7655 166.439347) (xy 219.5 166.179) (xy 219.2345 166.439347)
				(xy 219.287642 166.451214) (xy 219.328681 166.469662) (xy 219.380382 166.520336) (xy 219.399718 166.583905)
				(xy 219.4 166.593)
			)
		)
	)
	(zone
		(net 142)
		(net_name "/2xSFP+/PHY0_{RESET}")
		(layer "B.Cu")
		(name "$teardrop_padvia$")
		(hatch none 0.1)
		(priority 30329)
		(attr
			(teardrop
				(type padvia)
			)
		)
		(connect_pads yes
			(clearance 0)
		)
		(min_thickness 0.0254)
		(filled_areas_thickness no)
		(fill yes
			(thermal_gap 0.5)
			(thermal_bridge_width 0.5)
			(island_removal_mode 1)
			(island_area_min 10)
		)
		(polygon
			(pts
				(xy 141.8625 132.9305) (xy 141.882221 132.877623) (xy 141.944164 132.833031) (xy 141.992638 132.818031)
				(xy 142.051825 132.810873) (xy 142.07 132.8105) (xy 141.8 132.5095) (xy 141.53 132.8105) (xy 141.59221 132.815222)
				(xy 141.643739 132.828274) (xy 141.684329 132.847999) (xy 141.713672 132.872719) (xy 141.731011 132.899624)
				(xy 141.737462 132.928114) (xy 141.7375 132.9305)
			)
		)
	)
	(zone
		(net 294)
		(net_name "/2xUSB3.0+RJ45/GbE.MDI0-")
		(layer "B.Cu")
		(name "$teardrop_padvia$")
		(hatch none 0.1)
		(priority 30660)
		(attr
			(teardrop
				(type padvia)
			)
		)
		(connect_pads yes
			(clearance 0)
		)
		(min_thickness 0.0254)
		(filled_areas_thickness no)
		(fill yes
			(thermal_gap 0.5)
			(thermal_bridge_width 0.5)
			(island_removal_mode 1)
			(island_area_min 10)
		)
		(polygon
			(pts
				(xy 181.675 167.742084) (xy 181.672797 167.536718) (xy 181.670677 167.398242) (xy 181.45 167.399)
				(xy 181.324997 167.587081) (xy 181.401138 167.620995) (xy 181.417738 167.62605) (xy 181.459281 167.639844)
				(xy 181.493398 167.659262) (xy 181.516501 167.691083) (xy 181.525 167.742084)
			)
		)
	)
	(zone
		(net 962)
		(net_name "/PCIe redriver/PCIe_{O}_C.TX1+")
		(layer "B.Cu")
		(name "$teardrop_padvia$")
		(hatch none 0.1)
		(priority 30186)
		(attr
			(teardrop
				(type padvia)
			)
		)
		(connect_pads yes
			(clearance 0)
		)
		(min_thickness 0.0254)
		(filled_areas_thickness no)
		(fill yes
			(thermal_gap 0.5)
			(thermal_bridge_width 0.5)
			(island_removal_mode 1)
			(island_area_min 10)
		)
		(polygon
			(pts
				(xy 108.739154 164.959785) (xy 108.678943 164.980796) (xy 108.521596 165.029692) (xy 108.434596 165.041704)
				(xy 108.346484 165.035571) (xy 108.372 165.355571) (xy 108.668 165.4584) (xy 108.661973 165.331093)
				(xy 108.67255 165.240317) (xy 108.688109 165.202308) (xy 108.71137 165.175941) (xy 108.739154 165.161785)
			)
		)
	)
	(zone
		(net 61)
		(net_name "/OCuLink/5V_CONN0")
		(layer "B.Cu")
		(name "$teardrop_padvia$")
		(hatch none 0.1)
		(priority 30231)
		(attr
			(teardrop
				(type padvia)
			)
		)
		(connect_pads yes
			(clearance 0)
		)
		(min_thickness 0.0254)
		(filled_areas_thickness no)
		(fill yes
			(thermal_gap 0.5)
			(thermal_bridge_width 0.5)
			(island_removal_mode 1)
			(island_area_min 10)
		)
		(polygon
			(pts
				(xy 103.159323 167.76) (xy 103.187979 167.759981) (xy 103.351177 167.764437) (xy 103.482288 167.796669)
				(xy 103.561 167.59) (xy 103.460779 167.392239) (xy 103.33234 167.444003) (xy 103.258234 167.456118)
				(xy 103.159323 167.46)
			)
		)
	)
	(zone
		(net 54)
		(net_name "/USB-C console/SH")
		(layer "B.Cu")
		(name "$teardrop_padvia$")
		(hatch none 0.1)
		(priority 30031)
		(attr
			(teardrop
				(type padvia)
			)
		)
		(connect_pads yes
			(clearance 0)
		)
		(min_thickness 0.0254)
		(filled_areas_thickness no)
		(fill yes
			(thermal_gap 0.5)
			(thermal_bridge_width 0.5)
			(island_removal_mode 1)
			(island_area_min 10)
		)
		(polygon
			(pts
				(xy 99.540393 87.697) (xy 99.503764 87.697387) (xy 99.39464 87.695835) (xy 99.274824 87.674997)
				(xy 99.214184 87.651215) (xy 99.154802 87.615257) (xy 99.097992 87.564669) (xy 99.045062 87.497)
				(xy 98.324 87.947) (xy 99.045062 88.397) (xy 99.087864 88.340494) (xy 99.133404 88.295633) (xy 99.234131 88.233706)
				(xy 99.35071 88.202622) (xy 99.503764 88.196613) (xy 99.540393 88.197)
			)
		)
	)
	(zone
		(net 78)
		(net_name "+1V8")
		(layer "B.Cu")
		(name "$teardrop_padvia$")
		(hatch none 0.1)
		(priority 30143)
		(attr
			(teardrop
				(type padvia)
			)
		)
		(connect_pads yes
			(clearance 0)
		)
		(min_thickness 0.0254)
		(filled_areas_thickness no)
		(fill yes
			(thermal_gap 0.5)
			(thermal_bridge_width 0.5)
			(island_removal_mode 1)
			(island_area_min 10)
		)
		(polygon
			(pts
				(xy 129.04 133.432) (xy 129.05882 133.477595) (xy 129.076685 133.512892) (xy 129.084068 133.547411)
				(xy 129.068318 133.576454) (xy 129.016783 133.595324) (xy 129.27 133.871) (xy 129.546731 133.630517)
				(xy 129.513162 133.615065) (xy 129.494551 133.595725) (xy 129.489674 133.553448) (xy 129.517588 133.488434)
				(xy 129.54 133.432)
			)
		)
	)
	(zone
		(net 389)
		(net_name "Net-(J12D-~{BIOS_DIS1})")
		(layer "B.Cu")
		(name "$teardrop_padvia$")
		(hatch none 0.1)
		(priority 30474)
		(attr
			(teardrop
				(type padvia)
			)
		)
		(connect_pads yes
			(clearance 0)
		)
		(min_thickness 0.0254)
		(filled_areas_thickness no)
		(fill yes
			(thermal_gap 0.5)
			(thermal_bridge_width 0.5)
			(island_removal_mode 1)
			(island_area_min 10)
		)
		(polygon
			(pts
				(xy 219.6 164.900677) (xy 219.604713 164.822764) (xy 219.6177 164.76398) (xy 219.659802 164.672947)
				(xy 219.7025 164.587778) (xy 219.5 164.499) (xy 219.2975 164.587778) (xy 219.340198 164.672949)
				(xy 219.382867 164.765783) (xy 219.395444 164.823922) (xy 219.4 164.900677)
			)
		)
	)
	(zone
		(net 2)
		(net_name "+3V3")
		(layer "B.Cu")
		(name "$teardrop_padvia$")
		(hatch none 0.1)
		(priority 30797)
		(attr
			(teardrop
				(type padvia)
			)
		)
		(connect_pads yes
			(clearance 0)
		)
		(min_thickness 0.0254)
		(filled_areas_thickness no)
		(fill yes
			(thermal_gap 0.5)
			(thermal_bridge_width 0.5)
			(island_removal_mode 1)
			(island_area_min 10)
		)
		(polygon
			(pts
				(xy 115.9635 145.220677) (xy 115.968313 145.151677) (xy 115.982002 145.100623) (xy 116.028606 145.025522)
				(xy 116.038456 145.013077) (xy 116.089081 144.945003) (xy 115.902 144.819) (xy 115.714919 144.945003)
				(xy 115.763846 145.011356) (xy 115.818209 145.094999) (xy 115.833224 145.148018) (xy 115.8385 145.220677)
			)
		)
	)
	(zone
		(net 1)
		(net_name "GND")
		(layer "B.Cu")
		(name "$teardrop_padvia$")
		(hatch none 0.1)
		(priority 30285)
		(attr
			(teardrop
				(type padvia)
			)
		)
		(connect_pads yes
			(clearance 0)
		)
		(min_thickness 0.0254)
		(filled_areas_thickness no)
		(fill yes
			(thermal_gap 0.5)
			(thermal_bridge_width 0.5)
			(island_removal_mode 1)
			(island_area_min 10)
		)
		(polygon
			(pts
				(xy 141.216887 137.569755) (xy 141.139414 137.484861) (xy 141.092294 137.414076) (xy 141.04941 137.308904)
				(xy 140.839293 137.379293) (xy 140.749925 137.581548) (xy 140.823826 137.620436) (xy 140.886371 137.667507)
				(xy 140.994859 137.771988) (xy 141.004755 137.781887)
			)
		)
	)
	(zone
		(net 47)
		(net_name "/2xUSB3.0+RJ45/USBSS_1.TX-")
		(layer "B.Cu")
		(name "$teardrop_padvia$")
		(hatch none 0.1)
		(priority 30973)
		(attr
			(teardrop
				(type padvia)
			)
		)
		(connect_pads yes
			(clearance 0)
		)
		(min_thickness 0.0254)
		(filled_areas_thickness no)
		(fill yes
			(thermal_gap 0.5)
			(thermal_bridge_width 0.5)
			(island_removal_mode 1)
			(island_area_min 10)
		)
		(polygon
			(pts
				(xy 101.627027 104.714532) (xy 101.555101 104.730081) (xy 101.474912 104.749631) (xy 101.428379 104.751169)
				(xy 101.376763 104.742) (xy 101.324001 104.867025) (xy 101.6 104.927423) (xy 101.604297 104.895799)
				(xy 101.61438 104.891389) (xy 101.622453 104.895493) (xy 101.631653 104.899474)
			)
		)
	)
	(zone
		(net 53)
		(net_name "/2xSFP+/SH")
		(layer "B.Cu")
		(name "$teardrop_padvia$")
		(hatch none 0.1)
		(priority 30232)
		(attr
			(teardrop
				(type padvia)
			)
		)
		(connect_pads yes
			(clearance 0)
		)
		(min_thickness 0.0254)
		(filled_areas_thickness no)
		(fill yes
			(thermal_gap 0.5)
			(thermal_bridge_width 0.5)
			(island_removal_mode 1)
			(island_area_min 10)
		)
		(polygon
			(pts
				(xy 131.393 169.285) (xy 131.37791 169.285337) (xy 131.337674 169.28476) (xy 131.29613 169.272946)
				(xy 131.260835 169.238367) (xy 131.239347 169.1695) (xy 130.979 169.435) (xy 131.239347 169.7005)
				(xy 131.250291 169.654062) (xy 131.267391 169.621865) (xy 131.311856 169.590422) (xy 131.37791 169.584663)
				(xy 131.393 169.585)
			)
		)
	)
	(zone
		(net 125)
		(net_name "/2xUSB3.0+RJ45/P2_D-")
		(layer "B.Cu")
		(name "$teardrop_padvia$")
		(hatch none 0.1)
		(priority 30026)
		(attr
			(teardrop
				(type padvia)
			)
		)
		(connect_pads yes
			(clearance 0)
		)
		(min_thickness 0.0254)
		(filled_areas_thickness no)
		(fill yes
			(thermal_gap 0.5)
			(thermal_bridge_width 0.5)
			(island_removal_mode 1)
			(island_area_min 10)
		)
		(polygon
			(pts
				(xy 111.15203 104.2725) (xy 111.041578 104.267641) (xy 110.948297 104.253631) (xy 110.872958 104.232633)
				(xy 110.807941 104.204876) (xy 110.692954 104.127075) (xy 110.586849 104.026814) (xy 110.473211 103.918327)
				(xy 110.32501 103.803758) (xy 109.949 104.365) (xy 110.32501 104.926242) (xy 110.488643 104.797839)
				(xy 110.586849 104.703186) (xy 110.689643 104.605736) (xy 110.802672 104.527844) (xy 110.870259 104.498323)
				(xy 110.949085 104.476201) (xy 111.042044 104.462315) (xy 111.15203 104.4575)
			)
		)
	)
	(zone
		(net 704)
		(net_name "Net-(U24-GPIO2)")
		(layer "B.Cu")
		(name "$teardrop_padvia$")
		(hatch none 0.1)
		(priority 30108)
		(attr
			(teardrop
				(type padvia)
			)
		)
		(connect_pads yes
			(clearance 0)
		)
		(min_thickness 0.0254)
		(filled_areas_thickness no)
		(fill yes
			(thermal_gap 0.5)
			(thermal_bridge_width 0.5)
			(island_removal_mode 1)
			(island_area_min 10)
		)
		(polygon
			(pts
				(xy 259.617794 85.6475) (xy 259.535734 85.642685) (xy 259.470388 85.628981) (xy 259.377121 85.582424)
				(xy 259.298658 85.514214) (xy 259.237159 85.458058) (xy 259.158339 85.398199) (xy 258.949 85.71)
				(xy 259.158339 86.021801) (xy 259.278517 85.92478) (xy 259.298657 85.905787) (xy 259.357541 85.852634)
				(xy 259.421624 85.810409) (xy 259.504008 85.782551) (xy 259.617794 85.7725)
			)
		)
	)
	(zone
		(net 2)
		(net_name "+3V3")
		(layer "B.Cu")
		(name "$teardrop_padvia$")
		(hatch none 0.1)
		(priority 30376)
		(attr
			(teardrop
				(type padvia)
			)
		)
		(connect_pads yes
			(clearance 0)
		)
		(min_thickness 0.0254)
		(filled_areas_thickness no)
		(fill yes
			(thermal_gap 0.5)
			(thermal_bridge_width 0.5)
			(island_removal_mode 1)
			(island_area_min 10)
		)
		(polygon
			(pts
				(xy 122.2425 161.998) (xy 122.262469 161.935134) (xy 122.288921 161.903156) (xy 122.326332 161.874642)
				(xy 122.373527 161.852118) (xy 122.431167 161.836907) (xy 122.431798 161.836798) (xy 122.18 161.559)
				(xy 121.928202 161.836798) (xy 121.983635 161.851095) (xy 122.02952 161.872175) (xy 122.067201 161.89954)
				(xy 122.094434 161.930448) (xy 122.111472 161.963735) (xy 122.117489 161.996566) (xy 122.1175 161.998)
			)
		)
	)
	(zone
		(net 45)
		(net_name "/2xUSB3.0+RJ45/USBSS_2.TX+")
		(layer "B.Cu")
		(name "$teardrop_padvia$")
		(hatch none 0.1)
		(priority 30943)
		(attr
			(teardrop
				(type padvia)
			)
		)
		(connect_pads yes
			(clearance 0)
		)
		(min_thickness 0.0254)
		(filled_areas_thickness no)
		(fill yes
			(thermal_gap 0.5)
			(thermal_bridge_width 0.5)
			(island_removal_mode 1)
			(island_area_min 10)
		)
		(polygon
			(pts
				(xy 124.11 103.2695) (xy 124.097475 103.27278) (xy 124.072498 103.275714) (xy 124.063392 103.264753)
				(xy 124.059774 103.238366) (xy 123.784 103.302) (xy 123.841649 103.427) (xy 123.929774 103.418159)
				(xy 124.029692 103.438748) (xy 124.11 103.4545)
			)
		)
	)
	(zone
		(net 965)
		(net_name "/PCIe redriver/PCIe_{O}_C.TX1-")
		(layer "B.Cu")
		(name "$teardrop_padvia$")
		(hatch none 0.1)
		(priority 30171)
		(attr
			(teardrop
				(type padvia)
			)
		)
		(connect_pads yes
			(clearance 0)
		)
		(min_thickness 0.0254)
		(filled_areas_thickness no)
		(fill yes
			(thermal_gap 0.5)
			(thermal_bridge_width 0.5)
			(island_removal_mode 1)
			(island_area_min 10)
		)
		(polygon
			(pts
				(xy 108.739154 164.570786) (xy 108.711576 164.556786) (xy 108.690537 164.534116) (xy 108.666334 164.46155)
				(xy 108.664581 164.317042) (xy 108.668 164.27417) (xy 108.372 164.377) (xy 108.346484 164.697) (xy 108.456856 164.692484)
				(xy 108.589405 164.720972) (xy 108.678943 164.751775) (xy 108.739154 164.772786)
			)
		)
	)
	(zone
		(net 106)
		(net_name "/OCuLink/PCIe_{x4}.TX3+")
		(layer "B.Cu")
		(name "$teardrop_padvia$")
		(hatch none 0.1)
		(priority 30992)
		(attr
			(teardrop
				(type padvia)
			)
		)
		(connect_pads yes
			(clearance 0)
		)
		(min_thickness 0.0254)
		(filled_areas_thickness no)
		(fill yes
			(thermal_gap 0.5)
			(thermal_bridge_width 0.5)
			(island_removal_mode 1)
			(island_area_min 10)
		)
		(polygon
			(pts
				(xy 104.83 159.213) (xy 104.850648 159.205802) (xy 104.882984 159.196208) (xy 104.897007 159.203035)
				(xy 104.906995 159.2245) (xy 105.156 159.112) (xy 104.906995 158.9995) (xy 104.897271 159.020676)
				(xy 104.883643 159.027731) (xy 104.850648 159.018198) (xy 104.83 159.011)
			)
		)
	)
	(zone
		(net 162)
		(net_name "Net-(J2A-TX_{FAULT})")
		(layer "B.Cu")
		(name "$teardrop_padvia$")
		(hatch none 0.1)
		(priority 30730)
		(attr
			(teardrop
				(type padvia)
			)
		)
		(connect_pads yes
			(clearance 0)
		)
		(min_thickness 0.0254)
		(filled_areas_thickness no)
		(fill yes
			(thermal_gap 0.5)
			(thermal_bridge_width 0.5)
			(island_removal_mode 1)
			(island_area_min 10)
		)
		(polygon
			(pts
				(xy 143.1125 168.110677) (xy 143.117318 168.041236) (xy 143.13104 167.989912) (xy 143.177755 167.91437)
				(xy 143.187299 167.902229) (xy 143.237081 167.835003) (xy 143.05 167.709) (xy 142.862919 167.835003)
				(xy 142.912701 167.902231) (xy 142.967106 167.985397) (xy 142.98219 168.038251) (xy 142.9875 168.110677)
			)
		)
	)
	(zone
		(net 1)
		(net_name "GND")
		(layer "B.Cu")
		(name "$teardrop_padvia$")
		(hatch none 0.1)
		(priority 30877)
		(attr
			(teardrop
				(type padvia)
			)
		)
		(connect_pads yes
			(clearance 0)
		)
		(min_thickness 0.0254)
		(filled_areas_thickness no)
		(fill yes
			(thermal_gap 0.5)
			(thermal_bridge_width 0.5)
			(island_removal_mode 1)
			(island_area_min 10)
		)
		(polygon
			(pts
				(xy 104.028 159.6725) (xy 104.061863 159.678281) (xy 104.096484 159.698745) (xy 104.118306 159.72581)
				(xy 104.134 159.76515) (xy 104.137289 159.780711) (xy 104.384 159.61) (xy 104.137289 159.439289)
				(xy 104.1257 159.47951) (xy 104.108116 159.508984) (xy 104.060534 159.542173) (xy 104.028 159.5475)
			)
		)
	)
	(zone
		(net 574)
		(net_name "Net-(U19-EN)")
		(layer "B.Cu")
		(name "$teardrop_padvia$")
		(hatch none 0.1)
		(priority 30325)
		(attr
			(teardrop
				(type padvia)
			)
		)
		(connect_pads yes
			(clearance 0)
		)
		(min_thickness 0.0254)
		(filled_areas_thickness no)
		(fill yes
			(thermal_gap 0.5)
			(thermal_bridge_width 0.5)
			(island_removal_mode 1)
			(island_area_min 10)
		)
		(polygon
			(pts
				(xy 307.894 100.5975) (xy 307.841123 100.577779) (xy 307.796531 100.515836) (xy 307.781531 100.467362)
				(xy 307.774373 100.408175) (xy 307.774 100.39) (xy 307.473 100.66) (xy 307.774 100.93) (xy 307.778722 100.86779)
				(xy 307.791774 100.816261) (xy 307.811499 100.775671) (xy 307.836219 100.746328) (xy 307.863124 100.728989)
				(xy 307.891614 100.722538) (xy 307.894 100.7225)
			)
		)
	)
	(zone
		(net 959)
		(net_name "/PCIe redriver/PCIe_{I}_C.RX2+")
		(layer "B.Cu")
		(name "$teardrop_padvia$")
		(hatch none 0.1)
		(priority 30884)
		(attr
			(teardrop
				(type padvia)
			)
		)
		(connect_pads yes
			(clearance 0)
		)
		(min_thickness 0.0254)
		(filled_areas_thickness no)
		(fill yes
			(thermal_gap 0.5)
			(thermal_bridge_width 0.5)
			(island_removal_mode 1)
			(island_area_min 10)
		)
		(polygon
			(pts
				(xy 194.493771 138.116979) (xy 194.47408 138.107468) (xy 194.444432 138.091387) (xy 194.439344 138.076644)
				(xy 194.447459 138.054402) (xy 194.076932 137.842975) (xy 194.288359 138.213502) (xy 194.31021 138.205405)
				(xy 194.324835 138.210053) (xy 194.341425 138.240123) (xy 194.350936 138.259814)
			)
		)
	)
	(zone
		(net 1)
		(net_name "GND")
		(layer "B.Cu")
		(name "$teardrop_padvia$")
		(hatch none 0.1)
		(priority 30879)
		(attr
			(teardrop
				(type padvia)
			)
		)
		(connect_pads yes
			(clearance 0)
		)
		(min_thickness 0.0254)
		(filled_areas_thickness no)
		(fill yes
			(thermal_gap 0.5)
			(thermal_bridge_width 0.5)
			(island_removal_mode 1)
			(island_area_min 10)
		)
		(polygon
			(pts
				(xy 104.8 159.6725) (xy 104.833863 159.678281) (xy 104.868484 159.698745) (xy 104.890306 159.72581)
				(xy 104.906 159.76515) (xy 104.909289 159.780711) (xy 105.156 159.61) (xy 104.909289 159.439289)
				(xy 104.8977 159.47951) (xy 104.880116 159.508984) (xy 104.832534 159.542173) (xy 104.8 159.5475)
			)
		)
	)
	(zone
		(net 697)
		(net_name "Net-(U5-IO0_6)")
		(layer "B.Cu")
		(name "$teardrop_padvia$")
		(hatch none 0.1)
		(priority 30699)
		(attr
			(teardrop
				(type padvia)
			)
		)
		(connect_pads yes
			(clearance 0)
		)
		(min_thickness 0.0254)
		(filled_areas_thickness no)
		(fill yes
			(thermal_gap 0.5)
			(thermal_bridge_width 0.5)
			(island_removal_mode 1)
			(island_area_min 10)
		)
		(polygon
			(pts
				(xy 157.7875 162.909323) (xy 157.782682 162.978763) (xy 157.76896 163.030087) (xy 157.722245 163.105628)
				(xy 157.712702 163.117768) (xy 157.662919 163.184997) (xy 157.85 163.311) (xy 158.037081 163.184997)
				(xy 157.987299 163.117769) (xy 157.932894 163.034603) (xy 157.91781 162.981748) (xy 157.9125 162.909323)
			)
		)
	)
	(zone
		(net 969)
		(net_name "/M.2 key M #1/M2_3V3")
		(layer "B.Cu")
		(name "$teardrop_padvia$")
		(hatch none 0.1)
		(priority 30272)
		(attr
			(teardrop
				(type padvia)
			)
		)
		(connect_pads yes
			(clearance 0)
		)
		(min_thickness 0.0254)
		(filled_areas_thickness no)
		(fill yes
			(thermal_gap 0.5)
			(thermal_bridge_width 0.5)
			(island_removal_mode 1)
			(island_area_min 10)
		)
		(polygon
			(pts
				(xy 178.260677 95.46) (xy 178.103106 95.453069) (xy 177.989578 95.424549) (xy 177.947778 95.4075)
				(xy 177.859 95.61) (xy 177.947778 95.8125) (xy 178.043817 95.778118) (xy 178.145689 95.7629) (xy 178.260677 95.76)
			)
		)
	)
	(zone
		(net 102)
		(net_name "/OCuLink/PCIe_{x4}.TX1+")
		(layer "B.Cu")
		(name "$teardrop_padvia$")
		(hatch none 0.1)
		(priority 30175)
		(attr
			(teardrop
				(type padvia)
			)
		)
		(connect_pads yes
			(clearance 0)
		)
		(min_thickness 0.0254)
		(filled_areas_thickness no)
		(fill yes
			(thermal_gap 0.5)
			(thermal_bridge_width 0.5)
			(island_removal_mode 1)
			(island_area_min 10)
		)
		(polygon
			(pts
				(xy 107.048621 165.1575) (xy 107.076112 165.17285) (xy 107.096919 165.196669) (xy 107.120457 165.27159)
				(xy 107.12101 165.419866) (xy 107.118 165.456387) (xy 107.414 165.355571) (xy 107.442221 165.035571)
				(xy 107.330981 165.039998) (xy 107.199034 165.011109) (xy 107.094025 164.972851) (xy 107.048621 164.9555)
			)
		)
	)
	(zone
		(net 1)
		(net_name "GND")
		(layer "B.Cu")
		(name "$teardrop_padvia$")
		(hatch none 0.1)
		(priority 30157)
		(attr
			(teardrop
				(type padvia)
			)
		)
		(connect_pads yes
			(clearance 0)
		)
		(min_thickness 0.0254)
		(filled_areas_thickness no)
		(fill yes
			(thermal_gap 0.5)
			(thermal_bridge_width 0.5)
			(island_removal_mode 1)
			(island_area_min 10)
		)
		(polygon
			(pts
				(xy 255.457707 78.385) (xy 255.502353 78.364597) (xy 255.535899 78.345779) (xy 255.568363 78.337205)
				(xy 255.595073 78.351303) (xy 255.61136 78.4005) (xy 255.871707 78.135) (xy 255.61136 77.8695) (xy 255.60154 77.907593)
				(xy 255.586133 77.927358) (xy 255.551808 77.930352) (xy 255.502353 77.905403) (xy 255.457707 77.885)
			)
		)
	)
	(zone
		(net 896)
		(net_name "Net-(J2B-RX_{LOS})")
		(layer "B.Cu")
		(name "$teardrop_padvia$")
		(hatch none 0.1)
		(priority 30088)
		(attr
			(teardrop
				(type padvia)
			)
		)
		(connect_pads yes
			(clearance 0)
		)
		(min_thickness 0.0254)
		(filled_areas_thickness no)
		(fill yes
			(thermal_gap 0.5)
			(thermal_bridge_width 0.5)
			(island_removal_mode 1)
			(island_area_min 10)
		)
		(polygon
			(pts
				(xy 140.006776 167.828389) (xy 139.974712 167.789481) (xy 139.958882 167.754022) (xy 139.956741 167.725355)
				(xy 139.964068 167.698351) (xy 140.008112 167.641391) (xy 140.094063 167.573469) (xy 140.184653 167.502965)
				(xy 140.261801 167.418339) (xy 139.949293 167.209293) (xy 139.638199 167.418339) (xy 139.714247 167.560212)
				(xy 139.741357 167.632624) (xy 139.797076 167.76297) (xy 139.845165 167.834714) (xy 139.918389 167.916776)
			)
		)
	)
	(zone
		(net 539)
		(net_name "/Misc/~{PWR_OK}")
		(layer "B.Cu")
		(name "$teardrop_padvia$")
		(hatch none 0.1)
		(priority 30395)
		(attr
			(teardrop
				(type padvia)
			)
		)
		(connect_pads yes
			(clearance 0)
		)
		(min_thickness 0.0254)
		(filled_areas_thickness no)
		(fill yes
			(thermal_gap 0.5)
			(thermal_bridge_width 0.5)
			(island_removal_mode 1)
			(island_area_min 10)
		)
		(polygon
			(pts
				(xy 98.6385 74.372) (xy 98.632466 74.431794) (xy 98.610228 74.49973) (xy 98.583969 74.541092) (xy 98.546403 74.574929)
				(xy 98.536228 74.581054) (xy 98.82 74.811) (xy 99.010379 74.498529) (xy 98.932334 74.491565) (xy 98.867774 74.476103)
				(xy 98.820828 74.455147) (xy 98.787301 74.428798) (xy 98.769853 74.40253) (xy 98.763515 74.373554)
				(xy 98.7635 74.372)
			)
		)
	)
	(zone
		(net 78)
		(net_name "+1V8")
		(layer "B.Cu")
		(name "$teardrop_padvia$")
		(hatch none 0.1)
		(priority 30739)
		(attr
			(teardrop
				(type padvia)
			)
		)
		(connect_pads yes
			(clearance 0)
		)
		(min_thickness 0.0254)
		(filled_areas_thickness no)
		(fill yes
			(thermal_gap 0.5)
			(thermal_bridge_width 0.5)
			(island_removal_mode 1)
			(island_area_min 10)
		)
		(polygon
			(pts
				(xy 142.920677 134.8175) (xy 142.851236 134.812682) (xy 142.799913 134.79896) (xy 142.724371 134.752246)
				(xy 142.712231 134.742701) (xy 142.645003 134.692919) (xy 142.519 134.88) (xy 142.645003 135.067081)
				(xy 142.712229 135.017299) (xy 142.795396 134.962894) (xy 142.848251 134.94781) (xy 142.920677 134.9425)
			)
		)
	)
	(zone
		(net 2)
		(net_name "+3V3")
		(layer "B.Cu")
		(name "$teardrop_padvia$")
		(hatch none 0.1)
		(priority 30782)
		(attr
			(teardrop
				(type padvia)
			)
		)
		(connect_pads yes
			(clearance 0)
		)
		(min_thickness 0.0254)
		(filled_areas_thickness no)
		(fill yes
			(thermal_gap 0.5)
			(thermal_bridge_width 0.5)
			(island_removal_mode 1)
			(island_area_min 10)
		)
		(polygon
			(pts
				(xy 120.726515 150.140127) (xy 120.680819 150.087618) (xy 120.654231 150.041623) (xy 120.633847 149.955175)
				(xy 120.632011 149.93984) (xy 120.619677 149.857105) (xy 120.398293 149.900293) (xy 120.355105 150.121677)
				(xy 120.43784 150.134011) (xy 120.535119 150.154349) (xy 120.583159 150.181057) (xy 120.638127 150.228515)
			)
		)
	)
	(zone
		(net 55)
		(net_name "/USB-C console/USB_D+")
		(layer "B.Cu")
		(name "$teardrop_padvia$")
		(hatch none 0.1)
		(priority 30599)
		(attr
			(teardrop
				(type padvia)
			)
		)
		(connect_pads yes
			(clearance 0)
		)
		(min_thickness 0.0254)
		(filled_areas_thickness no)
		(fill yes
			(thermal_gap 0.5)
			(thermal_bridge_width 0.5)
			(island_removal_mode 1)
			(island_area_min 10)
		)
		(polygon
			(pts
				(xy 102.207852 84.847041) (xy 102.185912 84.818364) (xy 102.178461 84.79204) (xy 102.193687 84.747151)
				(xy 102.237408 84.697966) (xy 102.280195 84.651481) (xy 102.310773 84.597159) (xy 102.099295 84.528644)
				(xy 101.912921 84.654354) (xy 101.96015 84.752477) (xy 101.971608 84.791537) (xy 102.002433 84.878311)
				(xy 102.031461 84.925454) (xy 102.077038 84.977855)
			)
		)
	)
	(zone
		(net 1)
		(net_name "GND")
		(layer "B.Cu")
		(name "$teardrop_padvia$")
		(hatch none 0.1)
		(priority 30202)
		(attr
			(teardrop
				(type padvia)
			)
		)
		(connect_pads yes
			(clearance 0)
		)
		(min_thickness 0.0254)
		(filled_areas_thickness no)
		(fill yes
			(thermal_gap 0.5)
			(thermal_bridge_width 0.5)
			(island_removal_mode 1)
			(island_area_min 10)
		)
		(polygon
			(pts
				(xy 107.45 156.978) (xy 107.449662 156.96113) (xy 107.450241 156.916174) (xy 107.462059 156.868831)
				(xy 107.496638 156.826427) (xy 107.5655 156.796291) (xy 107.3 156.539) (xy 107.0345 156.796291)
				(xy 107.079269 156.811848) (xy 107.110885 156.832565) (xy 107.143619 156.883701) (xy 107.150338 156.96113)
				(xy 107.15 156.978)
			)
		)
	)
	(zone
		(net 353)
		(net_name "Net-(J12D-~{LPC_DRQ0}{slash}~{ESPI_ALERT0})")
		(layer "B.Cu")
		(name "$teardrop_padvia$")
		(hatch none 0.1)
		(priority 30116)
		(attr
			(teardrop
				(type padvia)
			)
		)
		(connect_pads yes
			(clearance 0)
		)
		(min_thickness 0.0254)
		(filled_areas_thickness no)
		(fill yes
			(thermal_gap 0.5)
			(thermal_bridge_width 0.5)
			(island_removal_mode 1)
			(island_area_min 10)
		)
		(polygon
			(pts
				(xy 176.917794 166.0875) (xy 176.84344 166.082699) (xy 176.783532 166.069092) (xy 176.697511 166.022459)
				(xy 176.614929 165.936298) (xy 176.548819 165.862663) (xy 176.458339 165.788199) (xy 176.249 166.1)
				(xy 176.458339 166.411801) (xy 176.564701 166.334731) (xy 176.635275 166.283261) (xy 176.706779 166.244841)
				(xy 176.795516 166.220808) (xy 176.917794 166.2125)
			)
		)
	)
	(zone
		(net 78)
		(net_name "+1V8")
		(layer "B.Cu")
		(name "$teardrop_padvia$")
		(hatch none 0.1)
		(priority 30720)
		(attr
			(teardrop
				(type padvia)
			)
		)
		(connect_pads yes
			(clearance 0)
		)
		(min_thickness 0.0254)
		(filled_areas_thickness no)
		(fill yes
			(thermal_gap 0.5)
			(thermal_bridge_width 0.5)
			(island_removal_mode 1)
			(island_area_min 10)
		)
		(polygon
			(pts
				(xy 158.4425 140.760677) (xy 158.447318 140.691236) (xy 158.46104 140.639912) (xy 158.507755 140.56437)
				(xy 158.517299 140.552229) (xy 158.567081 140.485003) (xy 158.38 140.359) (xy 158.192919 140.485003)
				(xy 158.242701 140.552231) (xy 158.297106 140.635397) (xy 158.31219 140.688251) (xy 158.3175 140.760677)
			)
		)
	)
	(zone
		(net 53)
		(net_name "/2xSFP+/SH")
		(layer "B.Cu")
		(name "$teardrop_padvia$")
		(hatch none 0.1)
		(priority 30239)
		(attr
			(teardrop
				(type padvia)
			)
		)
		(connect_pads yes
			(clearance 0)
		)
		(min_thickness 0.0254)
		(filled_areas_thickness no)
		(fill yes
			(thermal_gap 0.5)
			(thermal_bridge_width 0.5)
			(island_removal_mode 1)
			(island_area_min 10)
		)
		(polygon
			(pts
				(xy 151.9 167.347) (xy 151.900337 167.36209) (xy 151.89976 167.402326) (xy 151.887946 167.44387)
				(xy 151.853367 167.479164) (xy 151.7845 167.500652) (xy 152.05 167.761) (xy 152.3155 167.500652)
				(xy 152.269062 167.489708) (xy 152.236865 167.472609) (xy 152.205422 167.428144) (xy 152.199663 167.36209)
				(xy 152.2 167.347)
			)
		)
	)
	(zone
		(net 154)
		(net_name "Net-(J1A-LED_D1)")
		(layer "B.Cu")
		(name "$teardrop_padvia$")
		(hatch none 0.1)
		(priority 30036)
		(attr
			(teardrop
				(type padvia)
			)
		)
		(connect_pads yes
			(clearance 0)
		)
		(min_thickness 0.0254)
		(filled_areas_thickness no)
		(fill yes
			(thermal_gap 0.5)
			(thermal_bridge_width 0.5)
			(island_removal_mode 1)
			(island_area_min 10)
		)
		(polygon
			(pts
				(xy 121.990241 97.7975) (xy 121.86063 97.792735) (xy 121.751248 97.779376) (xy 121.575187 97.731918)
				(xy 121.405979 97.654022) (xy 121.230147 97.572262) (xy 121.121997 97.534942) (xy 120.991686 97.50297)
				(xy 120.859 98.165) (xy 121.421242 98.54001) (xy 121.509534 98.379394) (xy 121.557899 98.265791)
				(xy 121.618011 98.129939) (xy 121.652728 98.071534) (xy 121.694463 98.021068) (xy 121.746149 97.979737)
				(xy 121.810718 97.948735) (xy 121.891105 97.929258) (xy 121.990241 97.9225)
			)
		)
	)
	(zone
		(net 716)
		(net_name "Net-(U40-SDA)")
		(layer "B.Cu")
		(name "$teardrop_padvia$")
		(hatch none 0.1)
		(priority 30666)
		(attr
			(teardrop
				(type padvia)
			)
		)
		(connect_pads yes
			(clearance 0)
		)
		(min_thickness 0.0254)
		(filled_areas_thickness no)
		(fill yes
			(thermal_gap 0.5)
			(thermal_bridge_width 0.5)
			(island_removal_mode 1)
			(island_area_min 10)
		)
		(polygon
			(pts
				(xy 196.53967 132.0236) (xy 196.621493 131.935401) (xy 196.673216 131.867333) (xy 196.689383 131.844)
				(xy 196.757549 131.749402) (xy 196.581504 131.613364) (xy 196.36196 131.662408) (xy 196.393427 131.730491)
				(xy 196.431818 131.778498) (xy 196.462277 131.816036) (xy 196.481412 131.852965) (xy 196.480616 131.89184)
				(xy 196.451282 131.935212)
			)
		)
	)
	(zone
		(net 205)
		(net_name "/Backplane/PCIe_{REF}.CK-")
		(layer "B.Cu")
		(name "$teardrop_padvia$")
		(hatch none 0.1)
		(priority 30990)
		(attr
			(teardrop
				(type padvia)
			)
		)
		(connect_pads yes
			(clearance 0)
		)
		(min_thickness 0.0254)
		(filled_areas_thickness no)
		(fill yes
			(thermal_gap 0.5)
			(thermal_bridge_width 0.5)
			(island_removal_mode 1)
			(island_area_min 10)
		)
		(polygon
			(pts
				(xy 314.812 165.311) (xy 314.832648 165.303802) (xy 314.864984 165.294208) (xy 314.879007 165.301035)
				(xy 314.888995 165.3225) (xy 315.138 165.21) (xy 314.888995 165.0975) (xy 314.879271 165.118676)
				(xy 314.865643 165.125731) (xy 314.832648 165.116198) (xy 314.812 165.109)
			)
		)
	)
	(zone
		(net 292)
		(net_name "/2xUSB3.0+RJ45/GbE.MDI1-")
		(layer "B.Cu")
		(name "$teardrop_padvia$")
		(hatch none 0.1)
		(priority 30652)
		(attr
			(teardrop
				(type padvia)
			)
		)
		(connect_pads yes
			(clearance 0)
		)
		(min_thickness 0.0254)
		(filled_areas_thickness no)
		(fill yes
			(thermal_gap 0.5)
			(thermal_bridge_width 0.5)
			(island_removal_mode 1)
			(island_area_min 10)
		)
		(polygon
			(pts
				(xy 180.025 167.057916) (xy 180.020244 167.097838) (xy 180.00695 167.126255) (xy 179.962871 167.158671)
				(xy 179.917738 167.173949) (xy 179.871459 167.189244) (xy 179.824997 167.212919) (xy 179.95 167.401)
				(xy 180.170677 167.401757) (xy 180.172797 167.263281) (xy 180.175 167.057916)
			)
		)
	)
	(zone
		(net 186)
		(net_name "/OCuLink/PCIe_{x4}.RX0+")
		(layer "B.Cu")
		(name "$teardrop_padvia$")
		(hatch none 0.1)
		(priority 30565)
		(attr
			(teardrop
				(type padvia)
			)
		)
		(connect_pads yes
			(clearance 0)
		)
		(min_thickness 0.0254)
		(filled_areas_thickness no)
		(fill yes
			(thermal_gap 0.5)
			(thermal_bridge_width 0.5)
			(island_removal_mode 1)
			(island_area_min 10)
		)
		(polygon
			(pts
				(xy 99.397496 165.9485) (xy 99.235964 165.953895) (xy 99.151554 165.957445) (xy 99.04986 165.952823)
				(xy 99.029 166.1735) (xy 99.178852 166.336731) (xy 99.232992 166.268062) (xy 99.242883 166.251608)
				(xy 99.267383 166.212935) (xy 99.29689 166.180721) (xy 99.338046 166.158673) (xy 99.397496 166.1505)
			)
		)
	)
	(zone
		(net 1)
		(net_name "GND")
		(layer "B.Cu")
		(name "$teardrop_padvia$")
		(hatch none 0.1)
		(priority 30147)
		(attr
			(teardrop
				(type padvia)
			)
		)
		(connect_pads yes
			(clearance 0)
		)
		(min_thickness 0.0254)
		(filled_areas_thickness no)
		(fill yes
			(thermal_gap 0.5)
			(thermal_bridge_width 0.5)
			(island_removal_mode 1)
			(island_area_min 10)
		)
		(polygon
			(pts
				(xy 143.090472 149.18595) (xy 143.139738 149.144578) (xy 143.203173 149.108115) (xy 143.265896 149.085275)
				(xy 143.338243 149.071736) (xy 143.451244 149.073) (xy 143.377707 148.777293) (xy 143.057 148.714945)
				(xy 143.056773 148.836711) (xy 143.022341 148.94343) (xy 142.959211 149.033987) (xy 142.94905 149.044528)
			)
		)
	)
	(zone
		(net 163)
		(net_name "Net-(J2A-TX_{DISABLE})")
		(layer "B.Cu")
		(name "$teardrop_padvia$")
		(hatch none 0.1)
		(priority 30073)
		(attr
			(teardrop
				(type padvia)
			)
		)
		(connect_pads yes
			(clearance 0)
		)
		(min_thickness 0.0254)
		(filled_areas_thickness no)
		(fill yes
			(thermal_gap 0.5)
			(thermal_bridge_width 0.5)
			(island_removal_mode 1)
			(island_area_min 10)
		)
		(polygon
			(pts
				(xy 146.715652 161.007264) (xy 146.657595 160.942385) (xy 146.617584 160.882904) (xy 146.579114 160.777939)
				(xy 146.569873 160.641643) (xy 146.566966 160.542859) (xy 146.551738 160.426111) (xy 146.129293 160.509293)
				(xy 146.046111 160.931738) (xy 146.208348 160.949046) (xy 146.261643 160.949873) (xy 146.351997 160.952904)
				(xy 146.438036 160.969259) (xy 146.527284 161.012365) (xy 146.627264 161.095652)
			)
		)
	)
	(zone
		(net 57)
		(net_name "/USB-C console/FTDI_VCCIO")
		(layer "B.Cu")
		(name "$teardrop_padvia$")
		(hatch none 0.1)
		(priority 30243)
		(attr
			(teardrop
				(type padvia)
			)
		)
		(connect_pads yes
			(clearance 0)
		)
		(min_thickness 0.0254)
		(filled_areas_thickness no)
		(fill yes
			(thermal_gap 0.5)
			(thermal_bridge_width 0.5)
			(island_removal_mode 1)
			(island_area_min 10)
		)
		(polygon
			(pts
				(xy 115.734322 74.075) (xy 115.891899 74.081932) (xy 116.005433 74.110456) (xy 116.047221 74.1275)
				(xy 116.135999 73.925) (xy 116.047221 73.7225) (xy 115.951176 73.756883) (xy 115.849295 73.772101)
				(xy 115.734322 73.775)
			)
		)
	)
	(zone
		(net 159)
		(net_name "/2xUSB3.0+RJ45/USBSS_1.RX+")
		(layer "B.Cu")
		(name "$teardrop_padvia$")
		(hatch none 0.1)
		(priority 30951)
		(attr
			(teardrop
				(type padvia)
			)
		)
		(connect_pads yes
			(clearance 0)
		)
		(min_thickness 0.0254)
		(filled_areas_thickness no)
		(fill yes
			(thermal_gap 0.5)
			(thermal_bridge_width 0.5)
			(island_removal_mode 1)
			(island_area_min 10)
		)
		(polygon
			(pts
				(xy 100.228 106.0175) (xy 100.308309 106.001748) (xy 100.396167 105.982329) (xy 100.444805 105.980846)
				(xy 100.496351 105.99) (xy 100.554 105.865) (xy 100.278225 105.801366) (xy 100.273746 105.8298)
				(xy 100.262735 105.839653) (xy 100.240525 105.83578) (xy 100.228 105.8325)
			)
		)
	)
	(zone
		(net 141)
		(net_name "/2xSFP+/KR to SFI #1/~{RESET}")
		(layer "B.Cu")
		(name "$teardrop_padvia$")
		(hatch none 0.1)
		(priority 30330)
		(attr
			(teardrop
				(type padvia)
			)
		)
		(connect_pads yes
			(clearance 0)
		)
		(min_thickness 0.0254)
		(filled_areas_thickness no)
		(fill yes
			(thermal_gap 0.5)
			(thermal_bridge_width 0.5)
			(island_removal_mode 1)
			(island_area_min 10)
		)
		(polygon
			(pts
				(xy 139.6625 131.981) (xy 139.682221 131.928123) (xy 139.744164 131.883531) (xy 139.792638 131.868531)
				(xy 139.851825 131.861373) (xy 139.87 131.861) (xy 139.6 131.56) (xy 139.33 131.861) (xy 139.39221 131.865722)
				(xy 139.443739 131.878774) (xy 139.484329 131.898499) (xy 139.513672 131.923219) (xy 139.531011 131.950124)
				(xy 139.537462 131.978614) (xy 139.5375 131.981)
			)
		)
	)
	(zone
		(net 78)
		(net_name "+1V8")
		(layer "B.Cu")
		(name "$teardrop_padvia$")
		(hatch none 0.1)
		(priority 30461)
		(attr
			(teardrop
				(type padvia)
			)
		)
		(connect_pads yes
			(clearance 0)
		)
		(min_thickness 0.0254)
		(filled_areas_thickness no)
		(fill yes
			(thermal_gap 0.5)
			(thermal_bridge_width 0.5)
			(island_removal_mode 1)
			(island_area_min 10)
		)
		(polygon
			(pts
				(xy 125.553078 135.671466) (xy 125.550739 135.694498) (xy 125.538602 135.714961) (xy 125.48144 135.75125)
				(xy 125.358202 135.783202) (xy 125.610707 136.060707) (xy 125.861798 135.783202) (xy 125.767925 135.749017)
				(xy 125.689701 135.68331) (xy 125.661416 135.641962) (xy 125.644861 135.601041) (xy 125.641466 135.583078)
			)
		)
	)
	(zone
		(net 531)
		(net_name "/Com Express 7 Interfaces/SD_CD")
		(layer "B.Cu")
		(name "$teardrop_padvia$")
		(hatch none 0.1)
		(priority 30819)
		(attr
			(teardrop
				(type padvia)
			)
		)
		(connect_pads yes
			(clearance 0)
		)
		(min_thickness 0.0254)
		(filled_areas_thickness no)
		(fill yes
			(thermal_gap 0.5)
			(thermal_bridge_width 0.5)
			(island_removal_mode 1)
			(island_area_min 10)
		)
		(polygon
			(pts
				(xy 144.90836 148.930028) (xy 144.936262 148.908874) (xy 144.961695 148.902394) (xy 145.004244 148.919601)
				(xy 145.052514 148.968191) (xy 145.124997 149.037081) (xy 145.250707 148.849293) (xy 145.124997 148.662919)
				(xy 145.01356 148.720623) (xy 144.997692 148.726862) (xy 144.916403 148.764285) (xy 144.819972 148.84164)
			)
		)
	)
	(zone
		(net 93)
		(net_name "/Com Express 7 Interfaces/PCIe_{B2Ax4}.RX3+")
		(layer "B.Cu")
		(name "$teardrop_padvia$")
		(hatch none 0.1)
		(priority 30492)
		(attr
			(teardrop
				(type padvia)
			)
		)
		(connect_pads yes
			(clearance 0)
		)
		(min_thickness 0.0254)
		(filled_areas_thickness no)
		(fill yes
			(thermal_gap 0.5)
			(thermal_bridge_width 0.5)
			(island_removal_mode 1)
			(island_area_min 10)
		)
		(polygon
			(pts
				(xy 287.152 75.019852) (xy 287.147265 75.066638) (xy 287.134121 75.10209) (xy 287.089113 75.150287)
				(xy 287.050893 75.174463) (xy 287.007726 75.201832) (xy 286.965768 75.238495) (xy 287.129 75.388348)
				(xy 287.349677 75.367488) (xy 287.345048 75.266817) (xy 287.34848 75.18345) (xy 287.348605 75.181383)
				(xy 287.354 75.019852)
			)
		)
	)
	(zone
		(net 2)
		(net_name "+3V3")
		(layer "B.Cu")
		(name "$teardrop_padvia$")
		(hatch none 0.1)
		(priority 30673)
		(attr
			(teardrop
				(type padvia)
			)
		)
		(connect_pads yes
			(clearance 0)
		)
		(min_thickness 0.0254)
		(filled_areas_thickness no)
		(fill yes
			(thermal_gap 0.5)
			(thermal_bridge_width 0.5)
			(island_removal_mode 1)
			(island_area_min 10)
		)
		(polygon
			(pts
				(xy 180.473508 88.744881) (xy 180.504446 88.720678) (xy 180.533112 88.710872) (xy 180.584128 88.721367)
				(xy 180.630174 88.749402) (xy 180.679012 88.779614) (xy 180.736105 88.800677) (xy 180.780707 88.579293)
				(xy 180.631225 88.41669) (xy 180.45507 88.586219) (xy 180.38512 88.656493)
			)
		)
	)
	(zone
		(net 891)
		(net_name "Net-(D13-A)")
		(layer "B.Cu")
		(name "$teardrop_padvia$")
		(hatch none 0.1)
		(priority 30455)
		(attr
			(teardrop
				(type padvia)
			)
		)
		(connect_pads yes
			(clearance 0)
		)
		(min_thickness 0.0254)
		(filled_areas_thickness no)
		(fill yes
			(thermal_gap 0.5)
			(thermal_bridge_width 0.5)
			(island_removal_mode 1)
			(island_area_min 10)
		)
		(polygon
			(pts
				(xy 178.997001 88.8225) (xy 179.056413 88.842273) (xy 179.112498 88.905547) (xy 179.1342 88.954172)
				(xy 179.148874 89.013531) (xy 179.150654 89.0255) (xy 179.411001 88.76) (xy 179.150654 88.4945)
				(xy 179.137805 88.554638) (xy 179.117871 88.604522) (xy 179.091946 88.644641) (xy 179.062126 88.673654)
				(xy 179.030708 88.691146) (xy 178.998897 88.697479) (xy 178.997001 88.6975)
			)
		)
	)
	(zone
		(net 81)
		(net_name "/Misc/FAN_12V")
		(layer "B.Cu")
		(name "$teardrop_padvia$")
		(hatch none 0.1)
		(priority 30057)
		(attr
			(teardrop
				(type padvia)
			)
		)
		(connect_pads yes
			(clearance 0)
		)
		(min_thickness 0.0254)
		(filled_areas_thickness no)
		(fill yes
			(thermal_gap 0.5)
			(thermal_bridge_width 0.5)
			(island_removal_mode 1)
			(island_area_min 10)
		)
		(polygon
			(pts
				(xy 236.11575 73.733594) (xy 236.181401 73.790823) (xy 236.255977 73.855229) (xy 236.326072 73.93492)
				(xy 236.377408 74.037136) (xy 236.39158 74.098953) (xy 236.395708 74.169116) (xy 236.796415 74.060707)
				(xy 236.804825 73.56) (xy 236.75071 73.569977) (xy 236.703183 73.569304) (xy 236.6236 73.542036)
				(xy 236.553483 73.482248) (xy 236.511088 73.430147) (xy 236.469302 73.380042)
			)
		)
	)
	(zone
		(net 1)
		(net_name "GND")
		(layer "B.Cu")
		(name "$teardrop_padvia$")
		(hatch none 0.1)
		(priority 30618)
		(attr
			(teardrop
				(type padvia)
			)
		)
		(connect_pads yes
			(clearance 0)
		)
		(min_thickness 0.0254)
		(filled_areas_thickness no)
		(fill yes
			(thermal_gap 0.5)
			(thermal_bridge_width 0.5)
			(island_removal_mode 1)
			(island_area_min 10)
		)
		(polygon
			(pts
				(xy 308.816197 102.714585) (xy 308.868703 102.773647) (xy 308.901716 102.824268) (xy 308.934716 102.901959)
				(xy 308.98569 103.017552) (xy 309.180707 102.910707) (xy 309.223054 102.689323) (xy 309.124217 102.684842)
				(xy 309.096261 102.687452) (xy 309.049259 102.690951) (xy 309.003577 102.686754) (xy 308.956318 102.667593)
				(xy 308.904585 102.626197)
			)
		)
	)
	(zone
		(net 2)
		(net_name "+3V3")
		(layer "B.Cu")
		(name "$teardrop_padvia$")
		(hatch none 0.1)
		(priority 30895)
		(attr
			(teardrop
				(type padvia)
			)
		)
		(connect_pads yes
			(clearance 0)
		)
		(min_thickness 0.0254)
		(filled_areas_thickness no)
		(fill yes
			(thermal_gap 0.5)
			(thermal_bridge_width 0.5)
			(island_removal_mode 1)
			(island_area_min 10)
		)
		(polygon
			(pts
				(xy 197.294268 135.316483) (xy 197.28983 135.312176) (xy 197.266183 135.280583) (xy 197.264102 135.257321)
				(xy 197.276182 135.227466) (xy 196.905359 135.014548) (xy 197.115305 135.38478) (xy 197.142363 135.373855)
				(xy 197.164138 135.374335) (xy 197.201382 135.40023) (xy 197.205881 135.40487)
			)
		)
	)
	(zone
		(net 574)
		(net_name "Net-(U19-EN)")
		(layer "B.Cu")
		(name "$teardrop_padvia$")
		(hatch none 0.1)
		(priority 30326)
		(attr
			(teardrop
				(type padvia)
			)
		)
		(connect_pads yes
			(clearance 0)
		)
		(min_thickness 0.0254)
		(filled_areas_thickness no)
		(fill yes
			(thermal_gap 0.5)
			(thermal_bridge_width 0.5)
			(island_removal_mode 1)
			(island_area_min 10)
		)
		(polygon
			(pts
				(xy 307.054 100.7225) (xy 307.106877 100.742221) (xy 307.151469 100.804164) (xy 307.166469 100.852638)
				(xy 307.173627 100.911825) (xy 307.174 100.93) (xy 307.475 100.66) (xy 307.174 100.39) (xy 307.169278 100.45221)
				(xy 307.156226 100.503739) (xy 307.136501 100.544329) (xy 307.111781 100.573672) (xy 307.084876 100.591011)
				(xy 307.056386 100.597462) (xy 307.054 100.5975)
			)
		)
	)
	(zone
		(net 1)
		(net_name "GND")
		(layer "B.Cu")
		(name "$teardrop_padvia$")
		(hatch none 0.1)
		(priority 30483)
		(attr
			(teardrop
				(type padvia)
			)
		)
		(connect_pads yes
			(clearance 0)
		)
		(min_thickness 0.0254)
		(filled_areas_thickness no)
		(fill yes
			(thermal_gap 0.5)
			(thermal_bridge_width 0.5)
			(island_removal_mode 1)
			(island_area_min 10)
		)
		(polygon
			(pts
				(xy 125.082 148.379323) (xy 125.07721 148.480517) (xy 125.063682 148.553842) (xy 125.035865 148.637179)
				(xy 125.009926 148.710505) (xy 125.22 148.781) (xy 125.407081 148.654997) (xy 125.358995 148.590362)
				(xy 125.30356 148.506235) (xy 125.287679 148.452378) (xy 125.282 148.379323)
			)
		)
	)
	(zone
		(net 1)
		(net_name "GND")
		(layer "B.Cu")
		(name "$teardrop_padvia$")
		(hatch none 0.1)
		(priority 30479)
		(attr
			(teardrop
				(type padvia)
			)
		)
		(connect_pads yes
			(clearance 0)
		)
		(min_thickness 0.0254)
		(filled_areas_thickness no)
		(fill yes
			(thermal_gap 0.5)
			(thermal_bridge_width 0.5)
			(island_removal_mode 1)
			(island_area_min 10)
		)
		(polygon
			(pts
				(xy 219.4 166.399323) (xy 219.395287 166.477234) (xy 219.3823 166.536018) (xy 219.340199 166.627048)
				(xy 219.2975 166.712221) (xy 219.5 166.801) (xy 219.7025 166.712221) (xy 219.659801 166.62705) (xy 219.617133 166.534217)
				(xy 219.604556 166.476078) (xy 219.6 166.399323)
			)
		)
	)
	(zone
		(net 1)
		(net_name "GND")
		(layer "B.Cu")
		(name "$teardrop_padvia$")
		(hatch none 0.1)
		(priority 30472)
		(attr
			(teardrop
				(type padvia)
			)
		)
		(connect_pads yes
			(clearance 0)
		)
		(min_thickness 0.0254)
		(filled_areas_thickness no)
		(fill yes
			(thermal_gap 0.5)
			(thermal_bridge_width 0.5)
			(island_removal_mode 1)
			(island_area_min 10)
		)
		(polygon
			(pts
				(xy 123.946823 104.4) (xy 124.024735 104.404713) (xy 124.08352 104.4177) (xy 124.174551 104.459802)
				(xy 124.259722 104.5025) (xy 124.3485 104.3) (xy 124.259722 104.0975) (xy 124.17455 104.140199)
				(xy 124.081717 104.182867) (xy 124.023578 104.195444) (xy 123.946823 104.2)
			)
		)
	)
	(zone
		(net 45)
		(net_name "/2xUSB3.0+RJ45/USBSS_2.TX+")
		(layer "B.Cu")
		(name "$teardrop_padvia$")
		(hatch none 0.1)
		(priority 30586)
		(attr
			(teardrop
				(type padvia)
			)
		)
		(connect_pads yes
			(clearance 0)
		)
		(min_thickness 0.0254)
		(filled_areas_thickness no)
		(fill yes
			(thermal_gap 0.5)
			(thermal_bridge_width 0.5)
			(island_removal_mode 1)
			(island_area_min 10)
		)
		(polygon
			(pts
				(xy 126.410152 103.4545) (xy 126.574593 103.450316) (xy 126.757298 103.450177) (xy 126.770736 103.2295)
				(xy 126.61684 103.070311) (xy 126.567961 103.137836) (xy 126.554587 103.16418) (xy 126.533212 103.204443)
				(xy 126.506503 103.238002) (xy 126.467728 103.260979) (xy 126.410152 103.2695)
			)
		)
	)
	(zone
		(net 158)
		(net_name "/2xUSB3.0+RJ45/USBSS_1.RX-")
		(layer "B.Cu")
		(name "$teardrop_padvia$")
		(hatch none 0.1)
		(priority 30948)
		(attr
			(teardrop
				(type padvia)
			)
		)
		(connect_pads yes
			(clearance 0)
		)
		(min_thickness 0.0254)
		(filled_areas_thickness no)
		(fill yes
			(thermal_gap 0.5)
			(thermal_bridge_width 0.5)
			(island_removal_mode 1)
			(island_area_min 10)
		)
		(polygon
			(pts
				(xy 100.228 106.3975) (xy 100.240525 106.39422) (xy 100.265501 106.391286) (xy 100.274607 106.402247)
				(xy 100.278225 106.428633) (xy 100.554 106.365) (xy 100.496351 106.24) (xy 100.408227 106.248841)
				(xy 100.308309 106.228252) (xy 100.228 106.2125)
			)
		)
	)
	(zone
		(net 1)
		(net_name "GND")
		(layer "B.Cu")
		(name "$teardrop_padvia$")
		(hatch none 0.1)
		(priority 30261)
		(attr
			(teardrop
				(type padvia)
			)
		)
		(connect_pads yes
			(clearance 0)
		)
		(min_thickness 0.0254)
		(filled_areas_thickness no)
		(fill yes
			(thermal_gap 0.5)
			(thermal_bridge_width 0.5)
			(island_removal_mode 1)
			(island_area_min 10)
		)
		(polygon
			(pts
				(xy 99.860677 163.45) (xy 99.703106 163.443069) (xy 99.589578 163.414549) (xy 99.547778 163.3975)
				(xy 99.459 163.6) (xy 99.547778 163.8025) (xy 99.643817 163.768118) (xy 99.745689 163.7529) (xy 99.860677 163.75)
			)
		)
	)
	(zone
		(net 220)
		(net_name "/Com Express 7 Interfaces/PCIe_{B1x4}.TX1+")
		(layer "B.Cu")
		(name "$teardrop_padvia$")
		(hatch none 0.1)
		(priority 30842)
		(attr
			(teardrop
				(type padvia)
			)
		)
		(connect_pads yes
			(clearance 0)
		)
		(min_thickness 0.0254)
		(filled_areas_thickness no)
		(fill yes
			(thermal_gap 0.5)
			(thermal_bridge_width 0.5)
			(island_removal_mode 1)
			(island_area_min 10)
		)
		(polygon
			(pts
				(xy 118.2425 145.1855) (xy 118.260482 145.300025) (xy 118.282805 145.42475) (xy 118.285149 145.496169)
				(xy 118.276 145.574405) (xy 118.401 145.674) (xy 118.462662 145.2355) (xy 118.436953 145.231082)
				(xy 118.430495 145.220153) (xy 118.438582 145.1996) (xy 118.4445 145.1855)
			)
		)
	)
	(zone
		(net 124)
		(net_name "/2xUSB3.0+RJ45/P1_D+")
		(layer "B.Cu")
		(name "$teardrop_padvia$")
		(hatch none 0.1)
		(priority 30020)
		(attr
			(teardrop
				(type padvia)
			)
		)
		(connect_pads yes
			(clearance 0)
		)
		(min_thickness 0.0254)
		(filled_areas_thickness no)
		(fill yes
			(thermal_gap 0.5)
			(thermal_bridge_width 0.5)
			(island_removal_mode 1)
			(island_area_min 10)
		)
		(polygon
			(pts
				(xy 105.883483 105.6475) (xy 105.953791 105.652381) (xy 106.009706 105.666552) (xy 106.048544 105.686416)
				(xy 106.078103 105.712583) (xy 106.113358 105.781615) (xy 106.123532 105.886672) (xy 106.101844 106.085439)
				(xy 106.077691 106.290348) (xy 106.076191 106.394503) (xy 106.08797 106.496686) (xy 106.751 106.365)
				(xy 106.881686 105.70297) (xy 106.63996 105.638496) (xy 106.487479 105.58072) (xy 106.370109 105.535606)
				(xy 106.242312 105.497928) (xy 106.0861 105.472091) (xy 105.883483 105.4625)
			)
		)
	)
	(zone
		(net 49)
		(net_name "/2xUSB3.0+RJ45/USBSS_2.TX-")
		(layer "B.Cu")
		(name "$teardrop_padvia$")
		(hatch none 0.1)
		(priority 30958)
		(attr
			(teardrop
				(type padvia)
			)
		)
		(connect_pads yes
			(clearance 0)
		)
		(min_thickness 0.0254)
		(filled_areas_thickness no)
		(fill yes
			(thermal_gap 0.5)
			(thermal_bridge_width 0.5)
			(island_removal_mode 1)
			(island_area_min 10)
		)
		(polygon
			(pts
				(xy 124.11 103.6495) (xy 124.029692 103.665252) (xy 123.941833 103.684671) (xy 123.893195 103.686154)
				(xy 123.841649 103.677) (xy 123.784 103.802) (xy 124.059774 103.865633) (xy 124.064254 103.8372)
				(xy 124.075265 103.827347) (xy 124.097475 103.83122) (xy 124.11 103.8345)
			)
		)
	)
	(zone
		(net 74)
		(net_name "+1V0")
		(layer "B.Cu")
		(name "$teardrop_padvia$")
		(hatch none 0.1)
		(priority 30156)
		(attr
			(teardrop
				(type padvia)
			)
		)
		(connect_pads yes
			(clearance 0)
		)
		(min_thickness 0.0254)
		(filled_areas_thickness no)
		(fill yes
			(thermal_gap 0.5)
			(thermal_bridge_width 0.5)
			(island_removal_mode 1)
			(island_area_min 10)
		)
		(polygon
			(pts
				(xy 135.683 132.6) (xy 135.636801 132.621228) (xy 135.602757 132.640494) (xy 135.569753 132.64962)
				(xy 135.542363 132.636301) (xy 135.52516 132.588234) (xy 135.269 132.86) (xy 135.533565 133.119187)
				(xy 135.542831 133.080007) (xy 135.557902 133.059649) (xy 135.591616 133.05625) (xy 135.639868 133.08039)
				(xy 135.683 133.1)
			)
		)
	)
	(zone
		(net 1)
		(net_name "GND")
		(layer "B.Cu")
		(name "$teardrop_padvia$")
		(hatch none 0.1)
		(priority 30260)
		(attr
			(teardrop
				(type padvia)
			)
		)
		(connect_pads yes
			(clearance 0)
		)
		(min_thickness 0.0254)
		(filled_areas_thickness no)
		(fill yes
			(thermal_gap 0.5)
			(thermal_bridge_width 0.5)
			(island_removal_mode 1)
			(island_area_min 10)
		)
		(polygon
			(pts
				(xy 152.662745 160.759387) (xy 152.779071 160.652864) (xy 152.879522 160.592752) (xy 152.92112 160.575257)
				(xy 152.840707 160.369293) (xy 152.634742 160.288879) (xy 152.591141 160.381105) (xy 152.529861 160.463905)
				(xy 152.450613 160.547255)
			)
		)
	)
	(zone
		(net 1)
		(net_name "GND")
		(layer "B.Cu")
		(name "$teardrop_padvia$")
		(hatch none 0.1)
		(priority 30861)
		(attr
			(teardrop
				(type padvia)
			)
		)
		(connect_pads yes
			(clearance 0)
		)
		(min_thickness 0.0254)
		(filled_areas_thickness no)
		(fill yes
			(thermal_gap 0.5)
			(thermal_bridge_width 0.5)
			(island_removal_mode 1)
			(island_area_min 10)
		)
		(polygon
			(pts
				(xy 100.908 105.265) (xy 100.897885 105.265153) (xy 100.867169 105.26454) (xy 100.83468 105.256218)
				(xy 100.805526 105.232325) (xy 100.784809 105.185) (xy 100.552 105.365) (xy 100.784809 105.545)
				(xy 100.798168 105.509099) (xy 100.816399 105.485801) (xy 100.861725 105.466101) (xy 100.897885 105.464847)
				(xy 100.908 105.465)
			)
		)
	)
	(zone
		(net 2)
		(net_name "+3V3")
		(layer "B.Cu")
		(name "$teardrop_padvia$")
		(hatch none 0.1)
		(priority 30725)
		(attr
			(teardrop
				(type padvia)
			)
		)
		(connect_pads yes
			(clearance 0)
		)
		(min_thickness 0.0254)
		(filled_areas_thickness no)
		(fill yes
			(thermal_gap 0.5)
			(thermal_bridge_width 0.5)
			(island_removal_mode 1)
			(island_area_min 10)
		)
		(polygon
			(pts
				(xy 122.2425 161.960677) (xy 122.247318 161.891236) (xy 122.26104 161.839912) (xy 122.307755 161.76437)
				(xy 122.317299 161.752229) (xy 122.367081 161.685003) (xy 122.18 161.559) (xy 121.992919 161.685003)
				(xy 122.042701 161.752231) (xy 122.097106 161.835397) (xy 122.11219 161.888251) (xy 122.1175 161.960677)
			)
		)
	)
	(zone
		(net 963)
		(net_name "/PCIe redriver/PCIe_{O}_C.TX0+")
		(layer "B.Cu")
		(name "$teardrop_padvia$")
		(hatch none 0.1)
		(priority 30187)
		(attr
			(teardrop
				(type padvia)
			)
		)
		(connect_pads yes
			(clearance 0)
		)
		(min_thickness 0.0254)
		(filled_areas_thickness no)
		(fill yes
			(thermal_gap 0.5)
			(thermal_bridge_width 0.5)
			(island_removal_mode 1)
			(island_area_min 10)
		)
		(polygon
			(pts
				(xy 110.657154 166.451785) (xy 110.596943 166.472796) (xy 110.439596 166.521692) (xy 110.352596 166.533704)
				(xy 110.264484 166.527571) (xy 110.29 166.847571) (xy 110.586 166.9504) (xy 110.579973 166.823093)
				(xy 110.59055 166.732317) (xy 110.606109 166.694308) (xy 110.62937 166.667941) (xy 110.657154 166.653785)
			)
		)
	)
	(zone
		(net 1)
		(net_name "GND")
		(layer "B.Cu")
		(name "$teardrop_padvia$")
		(hatch none 0.1)
		(priority 30442)
		(attr
			(teardrop
				(type padvia)
			)
		)
		(connect_pads yes
			(clearance 0)
		)
		(min_thickness 0.0254)
		(filled_areas_thickness no)
		(fill yes
			(thermal_gap 0.5)
			(thermal_bridge_width 0.5)
			(island_removal_mode 1)
			(island_area_min 10)
		)
		(polygon
			(pts
				(xy 127.897 136.1225) (xy 127.956412 136.142273) (xy 128.012497 136.205547) (xy 128.034199 136.254172)
				(xy 128.048873 136.313531) (xy 128.050653 136.3255) (xy 128.311 136.06) (xy 128.050653 135.7945)
				(xy 128.037804 135.854638) (xy 128.01787 135.904522) (xy 127.991945 135.944641) (xy 127.962125 135.973654)
				(xy 127.930707 135.991146) (xy 127.898896 135.997479) (xy 127.897 135.9975)
			)
		)
	)
	(zone
		(net 1)
		(net_name "GND")
		(layer "B.Cu")
		(name "$teardrop_padvia$")
		(hatch none 0.1)
		(priority 30482)
		(attr
			(teardrop
				(type padvia)
			)
		)
		(connect_pads yes
			(clearance 0)
		)
		(min_thickness 0.0254)
		(filled_areas_thickness no)
		(fill yes
			(thermal_gap 0.5)
			(thermal_bridge_width 0.5)
			(island_removal_mode 1)
			(island_area_min 10)
		)
		(polygon
			(pts
				(xy 140.188534 137.883078) (xy 140.160971 137.954964) (xy 140.129177 137.995852) (xy 140.087056 138.032816)
				(xy 140.038928 138.061069) (xy 139.983545 138.08012) (xy 139.968202 138.083202) (xy 140.219293 138.360707)
				(xy 140.471798 138.083202) (xy 140.378342 138.061782) (xy 140.312991 138.033168) (xy 140.287895 138.010642)
				(xy 140.276956 137.98442) (xy 140.276922 137.971466)
			)
		)
	)
	(zone
		(net 347)
		(net_name "/2xUSB3.0+RJ45/~{GBE0_ACT}")
		(layer "B.Cu")
		(name "$teardrop_padvia$")
		(hatch none 0.1)
		(priority 30355)
		(attr
			(teardrop
				(type padvia)
			)
		)
		(connect_pads yes
			(clearance 0)
		)
		(min_thickness 0.0254)
		(filled_areas_thickness no)
		(fill yes
			(thermal_gap 0.5)
			(thermal_bridge_width 0.5)
			(island_removal_mode 1)
			(island_area_min 10)
		)
		(polygon
			(pts
				(xy 123.8175 98.422) (xy 123.797531 98.484866) (xy 123.771079 98.516844) (xy 123.733668 98.545358)
				(xy 123.686473 98.567882) (xy 123.628833 98.583093) (xy 123.628202 98.583202) (xy 123.88 98.861)
				(xy 124.131798 98.583202) (xy 124.076365 98.568905) (xy 124.03048 98.547825) (xy 123.992799 98.52046)
				(xy 123.965566 98.489552) (xy 123.948528 98.456265) (xy 123.942511 98.423434) (xy 123.9425 98.422)
			)
		)
	)
	(zone
		(net 706)
		(net_name "Net-(U24-GPIO0)")
		(layer "B.Cu")
		(name "$teardrop_padvia$")
		(hatch none 0.1)
		(priority 30103)
		(attr
			(teardrop
				(type padvia)
			)
		)
		(connect_pads yes
			(clearance 0)
		)
		(min_thickness 0.0254)
		(filled_areas_thickness no)
		(fill yes
			(thermal_gap 0.5)
			(thermal_bridge_width 0.5)
			(island_removal_mode 1)
			(island_area_min 10)
		)
		(polygon
			(pts
				(xy 259.617793 86.9475) (xy 259.535733 86.942685) (xy 259.470387 86.928981) (xy 259.37712 86.882424)
				(xy 259.298657 86.814214) (xy 259.237158 86.758058) (xy 259.158338 86.698199) (xy 258.948999 87.01)
				(xy 259.158338 87.321801) (xy 259.278516 87.22478) (xy 259.298656 87.205787) (xy 259.35754 87.152634)
				(xy 259.421623 87.110409) (xy 259.504007 87.082551) (xy 259.617793 87.0725)
			)
		)
	)
	(zone
		(net 106)
		(net_name "/OCuLink/PCIe_{x4}.TX3+")
		(layer "B.Cu")
		(name "$teardrop_padvia$")
		(hatch none 0.1)
		(priority 31010)
		(attr
			(teardrop
				(type padvia)
			)
		)
		(connect_pads yes
			(clearance 0)
		)
		(min_thickness 0.0254)
		(filled_areas_thickness no)
		(fill yes
			(thermal_gap 0.5)
			(thermal_bridge_width 0.5)
			(island_removal_mode 1)
			(island_area_min 10)
		)
		(polygon
			(pts
				(xy 104.708 159.011) (xy 104.687352 159.018199) (xy 104.655017 159.027792) (xy 104.640994 159.020965)
				(xy 104.631005 158.9995) (xy 104.382 159.112) (xy 104.631005 159.2245) (xy 104.64073 159.203324)
				(xy 104.654358 159.196269) (xy 104.687352 159.205801) (xy 104.708 159.213)
			)
		)
	)
	(zone
		(net 381)
		(net_name "Net-(J12D-~{SYS_RESET})")
		(layer "B.Cu")
		(name "$teardrop_padvia$")
		(hatch none 0.1)
		(priority 30784)
		(attr
			(teardrop
				(type padvia)
			)
		)
		(connect_pads yes
			(clearance 0)
		)
		(min_thickness 0.0254)
		(filled_areas_thickness no)
		(fill yes
			(thermal_gap 0.5)
			(thermal_bridge_width 0.5)
			(island_removal_mode 1)
			(island_area_min 10)
		)
		(polygon
			(pts
				(xy 193.227515 159.289127) (xy 193.181819 159.236618) (xy 193.155231 159.190623) (xy 193.134847 159.104175)
				(xy 193.133011 159.08884) (xy 193.120677 159.006105) (xy 192.899293 159.049293) (xy 192.856105 159.270677)
				(xy 192.93884 159.283011) (xy 193.036119 159.303349) (xy 193.084159 159.330057) (xy 193.139127 159.377515)
			)
		)
	)
	(zone
		(net 866)
		(net_name "/Backplane/PCIe_{x2}.TX0+")
		(layer "B.Cu")
		(name "$teardrop_padvia$")
		(hatch none 0.1)
		(priority 30969)
		(attr
			(teardrop
				(type padvia)
			)
		)
		(connect_pads yes
			(clearance 0)
		)
		(min_thickness 0.0254)
		(filled_areas_thickness no)
		(fill yes
			(thermal_gap 0.5)
			(thermal_bridge_width 0.5)
			(island_removal_mode 1)
			(island_area_min 10)
		)
		(polygon
			(pts
				(xy 315.438026 159.866444) (xy 315.429838 159.872724) (xy 315.417812 159.879831) (xy 315.412 159.847749)
				(xy 315.136001 159.910013) (xy 315.191428 160.035) (xy 315.275763 160.026647) (xy 315.367433 160.050467)
				(xy 315.44079 160.068424)
			)
		)
	)
	(zone
		(net 1)
		(net_name "GND")
		(layer "B.Cu")
		(hatch edge 0.5)
		(priority 14)
		(connect_pads
			(clearance 0.15)
		)
		(min_thickness 0.25)
		(filled_areas_thickness no)
		(fill yes
			(thermal_gap 0.2)
			(thermal_bridge_width 0.3)
		)
		(polygon
			(pts
				(xy 310.924999 106) (xy 311.824999 106) (xy 312.424999 105.4) (xy 312.424999 104.1) (xy 310.924999 104.1)
			)
		)
	)
	(zone
		(net 158)
		(net_name "/2xUSB3.0+RJ45/USBSS_1.RX-")
		(layer "B.Cu")
		(name "$teardrop_padvia$")
		(hatch none 0.1)
		(priority 30960)
		(attr
			(teardrop
				(type padvia)
			)
		)
		(connect_pads yes
			(clearance 0)
		)
		(min_thickness 0.0254)
		(filled_areas_thickness no)
		(fill yes
			(thermal_gap 0.5)
			(thermal_bridge_width 0.5)
			(island_removal_mode 1)
			(island_area_min 10)
		)
		(polygon
			(pts
				(xy 101 106.4005) (xy 101.012655 106.39715) (xy 101.037765 106.394051) (xy 101.046968 106.404877)
				(xy 101.05071 106.431073) (xy 101.326 106.365) (xy 101.264271 106.24) (xy 101.177415 106.250063)
				(xy 101.077915 106.230419) (xy 101 106.2155)
			)
		)
	)
	(zone
		(net 78)
		(net_name "+1V8")
		(layer "B.Cu")
		(name "$teardrop_padvia$")
		(hatch none 0.1)
		(priority 30390)
		(attr
			(teardrop
				(type padvia)
			)
		)
		(connect_pads yes
			(clearance 0)
		)
		(min_thickness 0.0254)
		(filled_areas_thickness no)
		(fill yes
			(thermal_gap 0.5)
			(thermal_bridge_width 0.5)
			(island_removal_mode 1)
			(island_area_min 10)
		)
		(polygon
			(pts
				(xy 125.5475 136.622) (xy 125.527531 136.684866) (xy 125.501079 136.716844) (xy 125.463668 136.745358)
				(xy 125.416473 136.767882) (xy 125.358833 136.783093) (xy 125.358202 136.783202) (xy 125.61 137.061)
				(xy 125.861798 136.783202) (xy 125.806365 136.768905) (xy 125.76048 136.747825) (xy 125.722799 136.72046)
				(xy 125.695566 136.689552) (xy 125.678528 136.656265) (xy 125.672511 136.623434) (xy 125.6725 136.622)
			)
		)
	)
	(zone
		(net 2)
		(net_name "+3V3")
		(layer "B.Cu")
		(name "$teardrop_padvia$")
		(hatch none 0.1)
		(priority 30793)
		(attr
			(teardrop
				(type padvia)
			)
		)
		(connect_pads yes
			(clearance 0)
		)
		(min_thickness 0.0254)
		(filled_areas_thickness no)
		(fill yes
			(thermal_gap 0.5)
			(thermal_bridge_width 0.5)
			(island_removal_mode 1)
			(island_area_min 10)
		)
		(polygon
			(pts
				(xy 117.3385 149.500323) (xy 117.333687 149.569322) (xy 117.319999 149.620376) (xy 117.273394 149.695477)
				(xy 117.263545 149.70792) (xy 117.212919 149.775997) (xy 117.4 149.902) (xy 117.587081 149.775997)
				(xy 117.538154 149.709644) (xy 117.483791 149.626) (xy 117.468776 149.572982) (xy 117.4635 149.500323)
			)
		)
	)
	(zone
		(net 409)
		(net_name "Net-(J12K-10G_SDP2)")
		(layer "B.Cu")
		(name "$teardrop_padvia$")
		(hatch none 0.1)
		(priority 30721)
		(attr
			(teardrop
				(type padvia)
			)
		)
		(connect_pads yes
			(clearance 0)
		)
		(min_thickness 0.0254)
		(filled_areas_thickness no)
		(fill yes
			(thermal_gap 0.5)
			(thermal_bridge_width 0.5)
			(island_removal_mode 1)
			(island_area_min 10)
		)
		(polygon
			(pts
				(xy 180.8625 159.550677) (xy 180.867318 159.481236) (xy 180.88104 159.429912) (xy 180.927755 159.35437)
				(xy 180.937299 159.342229) (xy 180.987081 159.275003) (xy 180.8 159.149) (xy 180.612919 159.275003)
				(xy 180.662701 159.342231) (xy 180.717106 159.425397) (xy 180.73219 159.478251) (xy 180.7375 159.550677)
			)
		)
	)
	(zone
		(net 353)
		(net_name "Net-(J12D-~{LPC_DRQ0}{slash}~{ESPI_ALERT0})")
		(layer "B.Cu")
		(name "$teardrop_padvia$")
		(hatch none 0.1)
		(priority 30770)
		(attr
			(teardrop
				(type padvia)
			)
		)
		(connect_pads yes
			(clearance 0)
		)
		(min_thickness 0.0254)
		(filled_areas_thickness no)
		(fill yes
			(thermal_gap 0.5)
			(thermal_bridge_width 0.5)
			(island_removal_mode 1)
			(island_area_min 10)
		)
		(polygon
			(pts
				(xy 178.660873 166.027515) (xy 178.713382 165.981819) (xy 178.759376 165.955231) (xy 178.845824 165.934847)
				(xy 178.86116 165.933011) (xy 178.943895 165.920677) (xy 178.900707 165.699293) (xy 178.679323 165.656105)
				(xy 178.666988 165.738841) (xy 178.646651 165.836119) (xy 178.619943 165.884159) (xy 178.572485 165.939127)
			)
		)
	)
	(zone
		(net 1)
		(net_name "GND")
		(layer "B.Cu")
		(name "$teardrop_padvia$")
		(hatch none 0.1)
		(priority 30468)
		(attr
			(teardrop
				(type padvia)
			)
		)
		(connect_pads yes
			(clearance 0)
		)
		(min_thickness 0.0254)
		(filled_areas_thickness no)
		(fill yes
			(thermal_gap 0.5)
			(thermal_bridge_width 0.5)
			(island_removal_mode 1)
			(island_area_min 10)
		)
		(polygon
			(pts
				(xy 315.949323 165.81) (xy 316.027235 165.814713) (xy 316.08602 165.8277) (xy 316.177051 165.869802)
				(xy 316.262222 165.9125) (xy 316.351 165.71) (xy 316.262222 165.5075) (xy 316.17705 165.550199)
				(xy 316.084217 165.592867) (xy 316.026078 165.605444) (xy 315.949323 165.61)
			)
		)
	)
	(zone
		(net 192)
		(net_name "/OCuLink/PCIe_{REF0}.CK+")
		(layer "B.Cu")
		(name "$teardrop_padvia$")
		(hatch none 0.1)
		(priority 30573)
		(attr
			(teardrop
				(type padvia)
			)
		)
		(connect_pads yes
			(clearance 0)
		)
		(min_thickness 0.0254)
		(filled_areas_thickness no)
		(fill yes
			(thermal_gap 0.5)
			(thermal_bridge_width 0.5)
			(island_removal_mode 1)
			(island_area_min 10)
		)
		(polygon
			(pts
				(xy 151.292496 113.8685) (xy 151.130964 113.873895) (xy 151.046554 113.877445) (xy 150.94486 113.872823)
				(xy 150.924 114.0935) (xy 151.073852 114.256731) (xy 151.127992 114.188062) (xy 151.137883 114.171608)
				(xy 151.162383 114.132935) (xy 151.19189 114.100721) (xy 151.233046 114.078673) (xy 151.292496 114.0705)
			)
		)
	)
	(zone
		(net 658)
		(net_name "Net-(U43C-PRTAD2)")
		(layer "B.Cu")
		(name "$teardrop_padvia$")
		(hatch none 0.1)
		(priority 30707)
		(attr
			(teardrop
				(type padvia)
			)
		)
		(connect_pads yes
			(clearance 0)
		)
		(min_thickness 0.0254)
		(filled_areas_thickness no)
		(fill yes
			(thermal_gap 0.5)
			(thermal_bridge_width 0.5)
			(island_removal_mode 1)
			(island_area_min 10)
		)
		(polygon
			(pts
				(xy 146.049323 139.9225) (xy 146.118764 139.927318) (xy 146.170088 139.94104) (xy 146.245629 139.987755)
				(xy 146.257769 139.997299) (xy 146.324997 140.047081) (xy 146.451 139.86) (xy 146.324997 139.672919)
				(xy 146.257768 139.722702) (xy 146.174602 139.777106) (xy 146.121748 139.79219) (xy 146.049323 139.7975)
			)
		)
	)
	(zone
		(net 162)
		(net_name "Net-(J2A-TX_{FAULT})")
		(layer "B.Cu")
		(name "$teardrop_padvia$")
		(hatch none 0.1)
		(priority 30751)
		(attr
			(teardrop
				(type padvia)
			)
		)
		(connect_pads yes
			(clearance 0)
		)
		(min_thickness 0.0254)
		(filled_areas_thickness no)
		(fill yes
			(thermal_gap 0.5)
			(thermal_bridge_width 0.5)
			(island_removal_mode 1)
			(island_area_min 10)
		)
		(polygon
			(pts
				(xy 143.289127 167.382485) (xy 143.236618 167.428181) (xy 143.190623 167.454768) (xy 143.104174 167.475152)
				(xy 143.088841 167.476988) (xy 143.006105 167.489323) (xy 143.049293 167.710707) (xy 143.270677 167.753895)
				(xy 143.283011 167.67116) (xy 143.303349 167.573881) (xy 143.330057 167.525841) (xy 143.377515 167.470873)
			)
		)
	)
	(zone
		(net 676)
		(net_name "Net-(U45C-PRTAD0)")
		(layer "B.Cu")
		(name "$teardrop_padvia$")
		(hatch none 0.1)
		(priority 30357)
		(attr
			(teardrop
				(type padvia)
			)
		)
		(connect_pads yes
			(clearance 0)
		)
		(min_thickness 0.0254)
		(filled_areas_thickness no)
		(fill yes
			(thermal_gap 0.5)
			(thermal_bridge_width 0.5)
			(island_removal_mode 1)
			(island_area_min 10)
		)
		(polygon
			(pts
				(xy 139.1975 141.922) (xy 139.177531 141.984866) (xy 139.151079 142.016844) (xy 139.113668 142.045358)
				(xy 139.066473 142.067882) (xy 139.008833 142.083093) (xy 139.008202 142.083202) (xy 139.26 142.361)
				(xy 139.511798 142.083202) (xy 139.456365 142.068905) (xy 139.41048 142.047825) (xy 139.372799 142.02046)
				(xy 139.345566 141.989552) (xy 139.328528 141.956265) (xy 139.322511 141.923434) (xy 139.3225 141.922)
			)
		)
	)
	(zone
		(net 97)
		(net_name "/OCuLink/PCIe_{x4}.TX2-")
		(layer "B.Cu")
		(name "$teardrop_padvia$")
		(hatch none 0.1)
		(priority 31018)
		(attr
			(teardrop
				(type padvia)
			)
		)
		(connect_pads yes
			(clearance 0)
		)
		(min_thickness 0.0254)
		(filled_areas_thickness no)
		(fill yes
			(thermal_gap 0.5)
			(thermal_bridge_width 0.5)
			(island_removal_mode 1)
			(island_area_min 10)
		)
		(polygon
			(pts
				(xy 104.708 160.009) (xy 104.687352 160.016199) (xy 104.655017 160.025792) (xy 104.640994 160.018965)
				(xy 104.631005 159.9975) (xy 104.382 160.11) (xy 104.631005 160.2225) (xy 104.64073 160.201324)
				(xy 104.654358 160.194269) (xy 104.687352 160.203801) (xy 104.708 160.211)
			)
		)
	)
	(zone
		(net 65)
		(net_name "+12V")
		(layer "B.Cu")
		(name "$teardrop_padvia$")
		(hatch none 0.1)
		(priority 30761)
		(attr
			(teardrop
				(type padvia)
			)
		)
		(connect_pads yes
			(clearance 0)
		)
		(min_thickness 0.0254)
		(filled_areas_thickness no)
		(fill yes
			(thermal_gap 0.5)
			(thermal_bridge_width 0.5)
			(island_removal_mode 1)
			(island_area_min 10)
		)
		(polygon
			(pts
				(xy 299.722485 140.545873) (xy 299.768181 140.598382) (xy 299.794768 140.644376) (xy 299.815152 140.730825)
				(xy 299.816988 140.746158) (xy 299.829323 140.828895) (xy 300.050707 140.785707) (xy 300.093895 140.564323)
				(xy 300.011158 140.551988) (xy 299.91388 140.531651) (xy 299.86584 140.504943) (xy 299.810873 140.457485)
			)
		)
	)
	(zone
		(net 628)
		(net_name "/PCIe redriver/TX_SW")
		(layer "B.Cu")
		(name "$teardrop_padvia$")
		(hatch none 0.1)
		(priority 30732)
		(attr
			(teardrop
				(type padvia)
			)
		)
		(connect_pads yes
			(clearance 0)
		)
		(min_thickness 0.0254)
		(filled_areas_thickness no)
		(fill yes
			(thermal_gap 0.5)
			(thermal_bridge_width 0.5)
			(island_removal_mode 1)
			(island_area_min 10)
		)
		(polygon
			(pts
				(xy 113.9635 144.330677) (xy 113.968318 144.261236) (xy 113.98204 144.209912) (xy 114.028755 144.13437)
				(xy 114.038299 144.122229) (xy 114.088081 144.055003) (xy 113.901 143.929) (xy 113.713919 144.055003)
				(xy 113.763701 144.122231) (xy 113.818106 144.205397) (xy 113.83319 144.258251) (xy 113.8385 144.330677)
			)
		)
	)
	(zone
		(net 1)
		(net_name "GND")
		(layer "B.Cu")
		(name "$teardrop_padvia$")
		(hatch none 0.1)
		(priority 30003)
		(attr
			(teardrop
				(type padvia)
			)
		)
		(connect_pads yes
			(clearance 0)
		)
		(min_thickness 0.0254)
		(filled_areas_thickness no)
		(fill yes
			(thermal_gap 0.5)
			(thermal_bridge_width 0.5)
			(island_removal_mode 1)
			(island_area_min 10)
		)
		(polygon
			(pts
				(xy 266.480709 73.221) (xy 266.48585 73.168476) (xy 266.50184 73.115561) (xy 266.52754 73.066933)
				(xy 266.564294 73.020842) (xy 266.609791 72.980901) (xy 266.666372 72.945645) (xy 266.732504 72.917002)
				(xy 266.810199 72.894967) (xy 266.899502 72.880672) (xy 267.001324 72.875045) (xy 267.01177 72.875)
				(xy 266.240708 71.859) (xy 265.454728 72.875) (xy 265.557612 72.879817) (xy 265.647799 72.893539)
				(xy 265.72529 72.914877) (xy 265.791375 72.942833) (xy 265.846904 72.976556) (xy 265.891994 73.014806)
				(xy 265.954353 73.103227) (xy 265.980043 73.202027) (xy 265.980709 73.221)
			)
		)
	)
	(zone
		(net 166)
		(net_name "Net-(J2A-MOD_{ABS})")
		(layer "B.Cu")
		(name "$teardrop_padvia$")
		(hatch none 0.1)
		(priority 30426)
		(attr
			(teardrop
				(type padvia)
			)
		)
		(connect_pads yes
			(clearance 0)
		)
		(min_thickness 0.0254)
		(filled_areas_thickness no)
		(fill yes
			(thermal_gap 0.5)
			(thermal_bridge_width 0.5)
			(island_removal_mode 1)
			(island_area_min 10)
		)
		(polygon
			(pts
				(xy 143.9875 168.267) (xy 143.967727 168.326412) (xy 143.904453 168.382496) (xy 143.855828 168.404198)
				(xy 143.796469 168.418872) (xy 143.7845 168.420652) (xy 144.05 168.681) (xy 144.3155 168.420652)
				(xy 144.255362 168.407803) (xy 144.205478 168.387869) (xy 144.165358 168.361944) (xy 144.136345 168.332124)
				(xy 144.118854 168.300706) (xy 144.112521 168.268895) (xy 144.1125 168.267)
			)
		)
	)
	(zone
		(net 660)
		(net_name "Net-(U43B-~{PDTRXB})")
		(layer "B.Cu")
		(name "$teardrop_padvia$")
		(hatch none 0.1)
		(priority 30654)
		(attr
			(teardrop
				(type padvia)
			)
		)
		(connect_pads yes
			(clearance 0)
		)
		(min_thickness 0.0254)
		(filled_areas_thickness no)
		(fill yes
			(thermal_gap 0.5)
			(thermal_bridge_width 0.5)
			(island_removal_mode 1)
			(island_area_min 10)
		)
		(polygon
			(pts
				(xy 148.779924 134.751688) (xy 148.749854 134.775005) (xy 148.722404 134.783475) (xy 148.67631 134.769541)
				(xy 148.623593 134.724224) (xy 148.571088 134.677548) (xy 148.507799 134.645082) (xy 148.449293 134.860707)
				(xy 148.578157 135.043926) (xy 148.687443 134.976673) (xy 148.768371 134.926997) (xy 148.868312 134.840076)
			)
		)
	)
	(zone
		(net 57)
		(net_name "/USB-C console/FTDI_VCCIO")
		(layer "B.Cu")
		(name "$teardrop_padvia$")
		(hatch none 0.1)
		(priority 30278)
		(attr
			(teardrop
				(type padvia)
			)
		)
		(connect_pads yes
			(clearance 0)
		)
		(min_thickness 0.0254)
		(filled_areas_thickness no)
		(fill yes
			(thermal_gap 0.5)
			(thermal_bridge_width 0.5)
			(island_removal_mode 1)
			(island_area_min 10)
		)
		(polygon
			(pts
				(xy 113.11 76.399323) (xy 113.103069 76.556893) (xy 113.074549 76.670421) (xy 113.0575 76.712221)
				(xy 113.26 76.801) (xy 113.4625 76.712221) (xy 113.428117 76.616179) (xy 113.4129 76.514304) (xy 113.41 76.399323)
			)
		)
	)
	(zone
		(net 1)
		(net_name "GND")
		(layer "B.Cu")
		(name "$teardrop_padvia$")
		(hatch none 0.1)
		(priority 30257)
		(attr
			(teardrop
				(type padvia)
			)
		)
		(connect_pads yes
			(clearance 0)
		)
		(min_thickness 0.0254)
		(filled_areas_thickness no)
		(fill yes
			(thermal_gap 0.5)
			(thermal_bridge_width 0.5)
			(island_removal_mode 1)
			(island_area_min 10)
		)
		(polygon
			(pts
				(xy 176.779323 93.51) (xy 176.9369 93.516932) (xy 177.050434 93.545456) (xy 177.092222 93.5625)
				(xy 177.181 93.36) (xy 177.092222 93.1575) (xy 176.996177 93.191883) (xy 176.894296 93.207101) (xy 176.779323 93.21)
			)
		)
	)
	(zone
		(net 154)
		(net_name "Net-(J1A-LED_D1)")
		(layer "B.Cu")
		(name "$teardrop_padvia$")
		(hatch none 0.1)
		(priority 30456)
		(attr
			(teardrop
				(type padvia)
			)
		)
		(connect_pads yes
			(clearance 0)
		)
		(min_thickness 0.0254)
		(filled_areas_thickness no)
		(fill yes
			(thermal_gap 0.5)
			(thermal_bridge_width 0.5)
			(island_removal_mode 1)
			(island_area_min 10)
		)
		(polygon
			(pts
				(xy 122.507 97.9225) (xy 122.566412 97.942273) (xy 122.622497 98.005547) (xy 122.644199 98.054172)
				(xy 122.658873 98.113531) (xy 122.660653 98.1255) (xy 122.921 97.86) (xy 122.660653 97.5945) (xy 122.647804 97.654638)
				(xy 122.62787 97.704522) (xy 122.601945 97.744641) (xy 122.572125 97.773654) (xy 122.540707 97.791146)
				(xy 122.508896 97.797479) (xy 122.507 97.7975)
			)
		)
	)
	(zone
		(net 2)
		(net_name "+3V3")
		(layer "B.Cu")
		(name "$teardrop_padvia$")
		(hatch none 0.1)
		(priority 30723)
		(attr
			(teardrop
				(type padvia)
			)
		)
		(connect_pads yes
			(clearance 0)
		)
		(min_thickness 0.0254)
		(filled_areas_thickness no)
		(fill yes
			(thermal_gap 0.5)
			(thermal_bridge_width 0.5)
			(island_removal_mode 1)
			(island_area_min 10)
		)
		(polygon
			(pts
				(xy 178.9125 159.950677) (xy 178.917318 159.881236) (xy 178.93104 159.829912) (xy 178.977755 159.75437)
				(xy 178.987299 159.742229) (xy 179.037081 159.675003) (xy 178.85 159.549) (xy 178.662919 159.675003)
				(xy 178.712701 159.742231) (xy 178.767106 159.825397) (xy 178.78219 159.878251) (xy 178.7875 159.950677)
			)
		)
	)
	(zone
		(net 155)
		(net_name "Net-(J1A-LED_D2)")
		(layer "B.Cu")
		(name "$teardrop_padvia$")
		(hatch none 0.1)
		(priority 30339)
		(attr
			(teardrop
				(type padvia)
			)
		)
		(connect_pads yes
			(clearance 0)
		)
		(min_thickness 0.0254)
		(filled_areas_thickness no)
		(fill yes
			(thermal_gap 0.5)
			(thermal_bridge_width 0.5)
			(island_removal_mode 1)
			(island_area_min 10)
		)
		(polygon
			(pts
				(xy 122.9825 99.298) (xy 123.002469 99.235134) (xy 123.028921 99.203156) (xy 123.066332 99.174642)
				(xy 123.113527 99.152118) (xy 123.171167 99.136907) (xy 123.171798 99.136798) (xy 122.92 98.859)
				(xy 122.668202 99.136798) (xy 122.723635 99.151095) (xy 122.76952 99.172175) (xy 122.807201 99.19954)
				(xy 122.834434 99.230448) (xy 122.851472 99.263735) (xy 122.857489 99.296566) (xy 122.8575 99.298)
			)
		)
	)
	(zone
		(net 78)
		(net_name "+1V8")
		(layer "B.Cu")
		(name "$teardrop_padvia$")
		(hatch none 0.1)
		(priority 30404)
		(attr
			(teardrop
				(type padvia)
			)
		)
		(connect_pads yes
			(clearance 0)
		)
		(min_thickness 0.0254)
		(filled_areas_thickness no)
		(fill yes
			(thermal_gap 0.5)
			(thermal_bridge_width 0.5)
			(island_removal_mode 1)
			(island_area_min 10)
		)
		(polygon
			(pts
				(xy 129.683 133.8075) (xy 129.623588 133.787727) (xy 129.567503 133.724453) (xy 129.545801 133.675828)
				(xy 129.531127 133.616468) (xy 129.529347 133.6045) (xy 129.269 133.87) (xy 129.529347 134.1355)
				(xy 129.542197 134.075361) (xy 129.562131 134.025477) (xy 129.588056 133.985358) (xy 129.617876 133.956345)
				(xy 129.649294 133.938854) (xy 129.681105 133.932521) (xy 129.683 133.9325)
			)
		)
	)
	(zone
		(net 673)
		(net_name "/2xSFP+/KR to SFI #2/PRBSEN")
		(layer "B.Cu")
		(name "$teardrop_padvia$")
		(hatch none 0.1)
		(priority 30452)
		(attr
			(teardrop
				(type padvia)
			)
		)
		(connect_pads yes
			(clearance 0)
		)
		(min_thickness 0.0254)
		(filled_areas_thickness no)
		(fill yes
			(thermal_gap 0.5)
			(thermal_bridge_width 0.5)
			(island_removal_mode 1)
			(island_area_min 10)
		)
		(polygon
			(pts
				(xy 138.847 140.4225) (xy 138.906412 140.442273) (xy 138.962497 140.505547) (xy 138.984199 140.554172)
				(xy 138.998873 140.613531) (xy 139.000653 140.6255) (xy 139.261 140.36) (xy 139.000653 140.0945)
				(xy 138.987804 140.154638) (xy 138.96787 140.204522) (xy 138.941945 140.244641) (xy 138.912125 140.273654)
				(xy 138.880707 140.291146) (xy 138.848896 140.297479) (xy 138.847 140.2975)
			)
		)
	)
	(zone
		(net 143)
		(net_name "/2xSFP+/KR to SFI #2/~{RESET}")
		(layer "B.Cu")
		(name "$teardrop_padvia$")
		(hatch none 0.1)
		(priority 30155)
		(attr
			(teardrop
				(type padvia)
			)
		)
		(connect_pads yes
			(clearance 0)
		)
		(min_thickness 0.0254)
		(filled_areas_thickness no)
		(fill yes
			(thermal_gap 0.5)
			(thermal_bridge_width 0.5)
			(island_removal_mode 1)
			(island_area_min 10)
		)
		(polygon
			(pts
				(xy 140.15501 136.666602) (xy 140.136809 136.670155) (xy 140.121507 136.660711) (xy 140.101013 136.605417)
				(xy 140.093149 136.516558) (xy 139.599293 136.761707) (xy 140.096118 136.990514) (xy 140.115287 136.899216)
				(xy 140.168186 136.815148) (xy 140.243398 136.75499)
			)
		)
	)
	(zone
		(net 869)
		(net_name "/Backplane/PCIe_{x2}.TX1-")
		(layer "B.Cu")
		(name "$teardrop_padvia$")
		(hatch none 0.1)
		(priority 31007)
		(attr
			(teardrop
				(type padvia)
			)
		)
		(connect_pads yes
			(clearance 0)
		)
		(min_thickness 0.0254)
		(filled_areas_thickness no)
		(fill yes
			(thermal_gap 0.5)
			(thermal_bridge_width 0.5)
			(island_removal_mode 1)
			(island_area_min 10)
		)
		(polygon
			(pts
				(xy 314.69 161.807) (xy 314.669352 161.814199) (xy 314.637017 161.823792) (xy 314.622994 161.816965)
				(xy 314.613005 161.7955) (xy 314.364 161.908) (xy 314.613005 162.0205) (xy 314.62273 161.999324)
				(xy 314.636358 161.992269) (xy 314.669352 162.001801) (xy 314.69 162.009)
			)
		)
	)
	(zone
		(net 57)
		(net_name "/USB-C console/FTDI_VCCIO")
		(layer "B.Cu")
		(name "$teardrop_padvia$")
		(hatch none 0.1)
		(priority 30211)
		(attr
			(teardrop
				(type padvia)
			)
		)
		(connect_pads yes
			(clearance 0)
		)
		(min_thickness 0.0254)
		(filled_areas_thickness no)
		(fill yes
			(thermal_gap 0.5)
			(thermal_bridge_width 0.5)
			(island_removal_mode 1)
			(island_area_min 10)
		)
		(polygon
			(pts
				(xy 111.338 70.19) (xy 111.32113 70.190338) (xy 111.276174 70.189759) (xy 111.228831 70.177941)
				(xy 111.186427 70.143362) (xy 111.156292 70.0745) (xy 110.899 70.34) (xy 111.156292 70.6055) (xy 111.171849 70.560731)
				(xy 111.192565 70.529115) (xy 111.243701 70.496381) (xy 111.32113 70.489662) (xy 111.338 70.49)
			)
		)
	)
	(zone
		(net 89)
		(net_name "/Com Express 7 Interfaces/PCIe_{B2Ax4}.RX3-")
		(layer "B.Cu")
		(name "$teardrop_padvia$")
		(hatch none 0.1)
		(priority 30547)
		(attr
			(teardrop
				(type padvia)
			)
		)
		(connect_pads yes
			(clearance 0)
		)
		(min_thickness 0.0254)
		(filled_areas_thickness no)
		(fill yes
			(thermal_gap 0.5)
			(thermal_bridge_width 0.5)
			(island_removal_mode 1)
			(island_area_min 10)
		)
		(polygon
			(pts
				(xy 287.541 75.019852) (xy 287.546395 75.181383) (xy 287.549945 75.265794) (xy 287.545323 75.367488)
				(xy 287.766 75.388348) (xy 287.929231 75.238495) (xy 287.860562 75.184355) (xy 287.844108 75.174464)
				(xy 287.805435 75.149964) (xy 287.773221 75.120457) (xy 287.751173 75.079301) (xy 287.743 75.019852)
			)
		)
	)
	(zone
		(net 945)
		(net_name "/GPIO expander/GPIOEX5")
		(layer "B.Cu")
		(name "$teardrop_padvia$")
		(hatch none 0.1)
		(priority 30706)
		(attr
			(teardrop
				(type padvia)
			)
		)
		(connect_pads yes
			(clearance 0)
		)
		(min_thickness 0.0254)
		(filled_areas_thickness no)
		(fill yes
			(thermal_gap 0.5)
			(thermal_bridge_width 0.5)
			(island_removal_mode 1)
			(island_area_min 10)
		)
		(polygon
			(pts
				(xy 122.449323 160.6225) (xy 122.518764 160.627318) (xy 122.570088 160.64104) (xy 122.645629 160.687755)
				(xy 122.657769 160.697299) (xy 122.724997 160.747081) (xy 122.851 160.56) (xy 122.724997 160.372919)
				(xy 122.657768 160.422702) (xy 122.574602 160.477106) (xy 122.521748 160.49219) (xy 122.449323 160.4975)
			)
		)
	)
	(zone
		(net 242)
		(net_name "/Com Express 7 Interfaces/PCIe_{B2Bx4}.TX3+")
		(layer "B.Cu")
		(name "$teardrop_padvia$")
		(hatch none 0.1)
		(priority 30304)
		(attr
			(teardrop
				(type padvia)
			)
		)
		(connect_pads yes
			(clearance 0)
		)
		(min_thickness 0.0254)
		(filled_areas_thickness no)
		(fill yes
			(thermal_gap 0.5)
			(thermal_bridge_width 0.5)
			(island_removal_mode 1)
			(island_area_min 10)
		)
		(polygon
			(pts
				(xy 175.39 95.461) (xy 175.404678 95.457463) (xy 175.434685 95.454192) (xy 175.445673 95.466143)
				(xy 175.45 95.495) (xy 176.201 95.36) (xy 175.45 95.225) (xy 175.445525 95.254204) (xy 175.434203 95.265997)
				(xy 175.404678 95.262537) (xy 175.39 95.259)
			)
		)
	)
	(zone
		(net 1)
		(net_name "GND")
		(layer "B.Cu")
		(name "$teardrop_padvia$")
		(hatch none 0.1)
		(priority 30476)
		(attr
			(teardrop
				(type padvia)
			)
		)
		(connect_pads yes
			(clearance 0)
		)
		(min_thickness 0.0254)
		(filled_areas_thickness no)
		(fill yes
			(thermal_gap 0.5)
			(thermal_bridge_width 0.5)
			(island_removal_mode 1)
			(island_area_min 10)
		)
		(polygon
			(pts
				(xy 103.590677 162.51) (xy 103.512765 162.505287) (xy 103.453981 162.4923) (xy 103.362949 162.450198)
				(xy 103.277778 162.4075) (xy 103.189 162.61) (xy 103.277778 162.8125) (xy 103.362947 162.769802)
				(xy 103.455782 162.727133) (xy 103.513921 162.714556) (xy 103.590677 162.71)
			)
		)
	)
	(zone
		(net 102)
		(net_name "/OCuLink/PCIe_{x4}.TX1+")
		(layer "B.Cu")
		(name "$teardrop_padvia$")
		(hatch none 0.1)
		(priority 30978)
		(attr
			(teardrop
				(type padvia)
			)
		)
		(connect_pads yes
			(clearance 0)
		)
		(min_thickness 0.0254)
		(filled_areas_thickness no)
		(fill yes
			(thermal_gap 0.5)
			(thermal_bridge_width 0.5)
			(island_removal_mode 1)
			(island_area_min 10)
		)
		(polygon
			(pts
				(xy 104.058 165.213) (xy 104.078648 165.205802) (xy 104.110984 165.196208) (xy 104.125007 165.203035)
				(xy 104.134995 165.2245) (xy 104.384 165.112) (xy 104.134995 164.9995) (xy 104.125271 165.020676)
				(xy 104.111643 165.027731) (xy 104.078648 165.018198) (xy 104.058 165.011)
			)
		)
	)
	(zone
		(net 703)
		(net_name "Net-(U24-GPIO3)")
		(layer "B.Cu")
		(name "$teardrop_padvia$")
		(hatch none 0.1)
		(priority 30109)
		(attr
			(teardrop
				(type padvia)
			)
		)
		(connect_pads yes
			(clearance 0)
		)
		(min_thickness 0.0254)
		(filled_areas_thickness no)
		(fill yes
			(thermal_gap 0.5)
			(thermal_bridge_width 0.5)
			(island_removal_mode 1)
			(island_area_min 10)
		)
		(polygon
			(pts
				(xy 260.617794 84.9975) (xy 260.535734 84.992685) (xy 260.470388 84.978981) (xy 260.377121 84.932424)
				(xy 260.298658 84.864214) (xy 260.237159 84.808058) (xy 260.158339 84.748199) (xy 259.949 85.06)
				(xy 260.158339 85.371801) (xy 260.278517 85.27478) (xy 260.298657 85.255787) (xy 260.357541 85.202634)
				(xy 260.421624 85.160409) (xy 260.504008 85.132551) (xy 260.617794 85.1225)
			)
		)
	)
	(zone
		(net 877)
		(net_name "/2xSFP+/SFI1.RX-")
		(layer "B.Cu")
		(name "$teardrop_padvia$")
		(hatch none 0.1)
		(priority 30670)
		(attr
			(teardrop
				(type padvia)
			)
		)
		(connect_pads yes
			(clearance 0)
		)
		(min_thickness 0.0254)
		(filled_areas_thickness no)
		(fill yes
			(thermal_gap 0.5)
			(thermal_bridge_width 0.5)
			(island_removal_mode 1)
			(island_area_min 10)
		)
		(polygon
			(pts
				(xy 132.064982 147.960414) (xy 132.068942 147.922616) (xy 132.081626 147.895996) (xy 132.124818 147.866182)
				(xy 132.165839 147.853244) (xy 132.210591 147.839257) (xy 132.255003 147.817081) (xy 132.12998 147.629001)
				(xy 131.909323 147.628554) (xy 131.906484 147.755986) (xy 131.905018 147.963754)
			)
		)
	)
	(zone
		(net 1)
		(net_name "GND")
		(layer "B.Cu")
		(name "$teardrop_padvia$")
		(hatch none 0.1)
		(priority 30467)
		(attr
			(teardrop
				(type padvia)
			)
		)
		(connect_pads yes
			(clearance 0)
		)
		(min_thickness 0.0254)
		(filled_areas_thickness no)
		(fill yes
			(thermal_gap 0.5)
			(thermal_bridge_width 0.5)
			(island_removal_mode 1)
			(island_area_min 10)
		)
		(polygon
			(pts
				(xy 113.275677 103.71) (xy 113.190682 103.70528) (xy 113.127336 103.692238) (xy 113.038551 103.655944)
				(xy 112.955123 103.619329) (xy 112.874 103.825) (xy 112.9712 104.024011) (xy 113.055929 103.975703)
				(xy 113.144629 103.92897) (xy 113.200971 103.915061) (xy 113.275677 103.91)
			)
		)
	)
	(zone
		(net 94)
		(net_name "/PCIe redriver/PCIe_{O}_C.TX3+")
		(layer "B.Cu")
		(name "$teardrop_padvia$")
		(hatch none 0.1)
		(priority 30185)
		(attr
			(teardrop
				(type padvia)
			)
		)
		(connect_pads yes
			(clearance 0)
		)
		(min_thickness 0.0254)
		(filled_areas_thickness no)
		(fill yes
			(thermal_gap 0.5)
			(thermal_bridge_width 0.5)
			(island_removal_mode 1)
			(island_area_min 10)
		)
		(polygon
			(pts
				(xy 108.739154 158.959785) (xy 108.678943 158.980796) (xy 108.521596 159.029692) (xy 108.434596 159.041704)
				(xy 108.346484 159.035571) (xy 108.372 159.355571) (xy 108.668 159.4584) (xy 108.661973 159.331093)
				(xy 108.67255 159.240317) (xy 108.688109 159.202308) (xy 108.71137 159.175941) (xy 108.739154 159.161785)
			)
		)
	)
	(zone
		(net 2)
		(net_name "+3V3")
		(layer "B.Cu")
		(name "$teardrop_padvia$")
		(hatch none 0.1)
		(priority 30802)
		(attr
			(teardrop
				(type padvia)
			)
		)
		(connect_pads yes
			(clearance 0)
		)
		(min_thickness 0.0254)
		(filled_areas_thickness no)
		(fill yes
			(thermal_gap 0.5)
			(thermal_bridge_width 0.5)
			(island_removal_mode 1)
			(island_area_min 10)
		)
		(polygon
			(pts
				(xy 195.060393 137.50061) (xy 195.10578 137.552803) (xy 195.132201 137.598583) (xy 195.152351 137.684642)
				(xy 195.154186 137.700406) (xy 195.166524 137.784339) (xy 195.387908 137.741151) (xy 195.431096 137.519767)
				(xy 195.349582 137.507445) (xy 195.251996 137.486741) (xy 195.203889 137.459869) (xy 195.148781 137.412222)
			)
		)
	)
	(zone
		(net 214)
		(net_name "/Com Express 7 Interfaces/PCIe_{B1x4}.RX2+")
		(layer "B.Cu")
		(name "$teardrop_padvia$")
		(hatch none 0.1)
		(priority 30491)
		(attr
			(teardrop
				(type padvia)
			)
		)
		(connect_pads yes
			(clearance 0)
		)
		(min_thickness 0.0254)
		(filled_areas_thickness no)
		(fill yes
			(thermal_gap 0.5)
			(thermal_bridge_width 0.5)
			(island_removal_mode 1)
			(island_area_min 10)
		)
		(polygon
			(pts
				(xy 205.9795 161.032504) (xy 205.974765 161.07929) (xy 205.961621 161.114742) (xy 205.916613 161.162939)
				(xy 205.878393 161.187115) (xy 205.835226 161.214484) (xy 205.793268 161.251147) (xy 205.9565 161.401)
				(xy 206.177177 161.38014) (xy 206.172548 161.279469) (xy 206.17598 161.196102) (xy 206.176105 161.194035)
				(xy 206.1815 161.032504)
			)
		)
	)
	(zone
		(net 2)
		(net_name "+3V3")
		(layer "B.Cu")
		(name "$teardrop_padvia$")
		(hatch none 0.1)
		(priority 30392)
		(attr
			(teardrop
				(type padvia)
			)
		)
		(connect_pads yes
			(clearance 0)
		)
		(min_thickness 0.0254)
		(filled_areas_thickness no)
		(fill yes
			(thermal_gap 0.5)
			(thermal_bridge_width 0.5)
			(island_removal_mode 1)
			(island_area_min 10)
		)
		(polygon
			(pts
				(xy 193.320681 141.665947) (xy 193.379254 141.635615) (xy 193.42057 141.631708) (xy 193.467187 141.637998)
				(xy 193.516486 141.655444) (xy 193.567999 141.685446) (xy 193.568521 141.685814) (xy 193.586906 141.311333)
				(xy 193.212425 141.329718) (xy 193.241513 141.379025) (xy 193.259053 141.426377) (xy 193.266348 141.472372)
				(xy 193.263749 141.513484) (xy 193.252259 141.549068) (xy 193.233299 141.576537) (xy 193.232293 141.577559)
			)
		)
	)
	(zone
		(net 204)
		(net_name "/Backplane/USB.D-")
		(layer "B.Cu")
		(name "$teardrop_padvia$")
		(hatch none 0.1)
		(priority 31025)
		(attr
			(teardrop
				(type padvia)
			)
		)
		(connect_pads yes
			(clearance 0)
		)
		(min_thickness 0.0254)
		(filled_areas_thickness no)
		(fill yes
			(thermal_gap 0.5)
			(thermal_bridge_width 0.5)
			(island_removal_mode 1)
			(island_area_min 10)
		)
		(polygon
			(pts
				(xy 314.812 166.8005) (xy 314.830847 166.7956) (xy 314.864108 166.789482) (xy 314.878647 166.797841)
				(xy 314.888995 166.8205) (xy 315.138 166.708) (xy 314.888995 166.5955) (xy 314.879025 166.617717)
				(xy 314.86505 166.626331) (xy 314.830847 166.6204) (xy 314.812 166.6155)
			)
		)
	)
	(zone
		(net 1)
		(net_name "GND")
		(layer "B.Cu")
		(name "$teardrop_padvia$")
		(hatch none 0.1)
		(priority 30245)
		(attr
			(teardrop
				(type padvia)
			)
		)
		(connect_pads yes
			(clearance 0)
		)
		(min_thickness 0.0254)
		(filled_areas_thickness no)
		(fill yes
			(thermal_gap 0.5)
			(thermal_bridge_width 0.5)
			(island_removal_mode 1)
			(island_area_min 10)
		)
		(polygon
			(pts
				(xy 176.779323 93.01) (xy 176.9369 93.016932) (xy 177.050434 93.045456) (xy 177.092222 93.0625)
				(xy 177.181 92.86) (xy 177.092222 92.6575) (xy 176.996177 92.691883) (xy 176.894296 92.707101) (xy 176.779323 92.71)
			)
		)
	)
	(zone
		(net 158)
		(net_name "/2xUSB3.0+RJ45/USBSS_1.RX-")
		(layer "B.Cu")
		(name "$teardrop_padvia$")
		(hatch none 0.1)
		(priority 30955)
		(attr
			(teardrop
				(type padvia)
			)
		)
		(connect_pads yes
			(clearance 0)
		)
		(min_thickness 0.0254)
		(filled_areas_thickness no)
		(fill yes
			(thermal_gap 0.5)
			(thermal_bridge_width 0.5)
			(island_removal_mode 1)
			(island_area_min 10)
		)
		(polygon
			(pts
				(xy 101.65 106.2125) (xy 101.569692 106.228252) (xy 101.481833 106.247671) (xy 101.433195 106.249154)
				(xy 101.381649 106.24) (xy 101.324 106.365) (xy 101.599774 106.428633) (xy 101.604254 106.4002)
				(xy 101.615265 106.390347) (xy 101.637475 106.39422) (xy 101.65 106.3975)
			)
		)
	)
	(zone
		(net 377)
		(net_name "/Com Express 7 Interfaces/USB1.D-")
		(layer "B.Cu")
		(name "$teardrop_padvia$")
		(hatch none 0.1)
		(priority 30603)
		(attr
			(teardrop
				(type padvia)
			)
		)
		(connect_pads yes
			(clearance 0)
		)
		(min_thickness 0.0254)
		(filled_areas_thickness no)
		(fill yes
			(thermal_gap 0.5)
			(thermal_bridge_width 0.5)
			(island_removal_mode 1)
			(island_area_min 10)
		)
		(polygon
			(pts
				(xy 204.3675 141.894916) (xy 204.362743 141.937708) (xy 204.349445 141.969045) (xy 204.304537 142.008413)
				(xy 204.26578 142.027253) (xy 204.197997 142.062919) (xy 204.323 142.251) (xy 204.543677 142.241365)
				(xy 204.546644 142.070056) (xy 204.5525 141.894916)
			)
		)
	)
	(zone
		(net 141)
		(net_name "/2xSFP+/KR to SFI #1/~{RESET}")
		(layer "B.Cu")
		(name "$teardrop_padvia$")
		(hatch none 0.1)
		(priority 30328)
		(attr
			(teardrop
				(type padvia)
			)
		)
		(connect_pads yes
			(clearance 0)
		)
		(min_thickness 0.0254)
		(filled_areas_thickness no)
		(fill yes
			(thermal_gap 0.5)
			(thermal_bridge_width 0.5)
			(island_removal_mode 1)
			(island_area_min 10)
		)
		(polygon
			(pts
				(xy 139.5375 133.041) (xy 139.517779 133.093877) (xy 139.455836 133.138469) (xy 139.407362 133.153469)
				(xy 139.348175 133.160627) (xy 139.33 133.161) (xy 139.6 133.462) (xy 139.87 133.161) (xy 139.80779 133.156278)
				(xy 139.756261 133.143226) (xy 139.715671 133.123501) (xy 139.686328 133.098781) (xy 139.668989 133.071876)
				(xy 139.662538 133.043386) (xy 139.6625 133.041)
			)
		)
	)
	(zone
		(net 141)
		(net_name "/2xSFP+/KR to SFI #1/~{RESET}")
		(layer "B.Cu")
		(name "$teardrop_padvia$")
		(hatch none 0.1)
		(priority 30764)
		(attr
			(teardrop
				(type padvia)
			)
		)
		(connect_pads yes
			(clearance 0)
		)
		(min_thickness 0.0254)
		(filled_areas_thickness no)
		(fill yes
			(thermal_gap 0.5)
			(thermal_bridge_width 0.5)
			(island_removal_mode 1)
			(island_area_min 10)
		)
		(polygon
			(pts
				(xy 149.122485 135.620873) (xy 149.168181 135.673382) (xy 149.194768 135.719376) (xy 149.215152 135.805825)
				(xy 149.216988 135.821158) (xy 149.229323 135.903895) (xy 149.450707 135.860707) (xy 149.493895 135.639323)
				(xy 149.411158 135.626988) (xy 149.31388 135.606651) (xy 149.26584 135.579943) (xy 149.210873 135.532485)
			)
		)
	)
	(zone
		(net 214)
		(net_name "/Com Express 7 Interfaces/PCIe_{B1x4}.RX2+")
		(layer "B.Cu")
		(name "$teardrop_padvia$")
		(hatch none 0.1)
		(priority 30190)
		(attr
			(teardrop
				(type padvia)
			)
		)
		(connect_pads yes
			(clearance 0)
		)
		(min_thickness 0.0254)
		(filled_areas_thickness no)
		(fill yes
			(thermal_gap 0.5)
			(thermal_bridge_width 0.5)
			(island_removal_mode 1)
			(island_area_min 10)
		)
		(polygon
			(pts
				(xy 196.595747 140.147538) (xy 196.513194 140.117992) (xy 196.419116 140.075038) (xy 196.327195 140.014526)
				(xy 196.251111 139.932302) (xy 196.049759 140.183498) (xy 196.191533 140.46033) (xy 196.281619 140.360878)
				(xy 196.356946 140.302371) (xy 196.394985 140.287501) (xy 196.43144 140.285465) (xy 196.452912 140.290373)
			)
		)
	)
	(zone
		(net 312)
		(net_name "/2xUSB3.0+RJ45/USB_1.D-")
		(layer "B.Cu")
		(name "$teardrop_padvia$")
		(hatch none 0.1)
		(priority 30589)
		(attr
			(teardrop
				(type padvia)
			)
		)
		(connect_pads yes
			(clearance 0)
		)
		(min_thickness 0.0254)
		(filled_areas_thickness no)
		(fill yes
			(thermal_gap 0.5)
			(thermal_bridge_width 0.5)
			(island_removal_mode 1)
			(island_area_min 10)
		)
		(polygon
			(pts
				(xy 134.873207 115.864679) (xy 134.759885 115.983917) (xy 134.630795 116.113204) (xy 134.777335 116.278749)
				(xy 134.998719 116.282491) (xy 134.985534 116.200181) (xy 134.976363 116.172097) (xy 134.963007 116.128512)
				(xy 134.958163 116.085897) (xy 134.969334 116.042231) (xy 135.004022 115.995494)
			)
		)
	)
	(zone
		(net 660)
		(net_name "Net-(U43B-~{PDTRXB})")
		(layer "B.Cu")
		(name "$teardrop_padvia$")
		(hatch none 0.1)
		(priority 30223)
		(attr
			(teardrop
				(type padvia)
			)
		)
		(connect_pads yes
			(clearance 0)
		)
		(min_thickness 0.0254)
		(filled_areas_thickness no)
		(fill yes
			(thermal_gap 0.5)
			(thermal_bridge_width 0.5)
			(island_removal_mode 1)
			(island_area_min 10)
		)
		(polygon
			(pts
				(xy 149.038944 134.259444) (xy 149.116761 134.209591) (xy 149.238204 134.181471) (xy 149.312476 134.180257)
				(xy 149.392762 134.189508) (xy 149.395474 134.19) (xy 149.340707 133.869293) (xy 149.045 133.789526)
				(xy 149.048538 133.875966) (xy 149.042454 133.955599) (xy 149.027419 134.028138) (xy 149.004456 134.090952)
				(xy 148.950556 134.171056)
			)
		)
	)
	(zone
		(net 2)
		(net_name "+3V3")
		(layer "B.Cu")
		(name "$teardrop_padvia$")
		(hatch none 0.1)
		(priority 30359)
		(attr
			(teardrop
				(type padvia)
			)
		)
		(connect_pads yes
			(clearance 0)
		)
		(min_thickness 0.0254)
		(filled_areas_thickness no)
		(fill yes
			(thermal_gap 0.5)
			(thermal_bridge_width 0.5)
			(island_removal_mode 1)
			(island_area_min 10)
		)
		(polygon
			(pts
				(xy 123.8175 108.372) (xy 123.797531 108.434866) (xy 123.771079 108.466844) (xy 123.733668 108.495358)
				(xy 123.686473 108.517882) (xy 123.628833 108.533093) (xy 123.628202 108.533202) (xy 123.88 108.811)
				(xy 124.131798 108.533202) (xy 124.076365 108.518905) (xy 124.03048 108.497825) (xy 123.992799 108.47046)
				(xy 123.965566 108.439552) (xy 123.948528 108.406265) (xy 123.942511 108.373434) (xy 123.9425 108.372)
			)
		)
	)
	(zone
		(net 347)
		(net_name "/2xUSB3.0+RJ45/~{GBE0_ACT}")
		(layer "B.Cu")
		(name "$teardrop_padvia$")
		(hatch none 0.1)
		(priority 30691)
		(attr
			(teardrop
				(type padvia)
			)
		)
		(connect_pads yes
			(clearance 0)
		)
		(min_thickness 0.0254)
		(filled_areas_thickness no)
		(fill yes
			(thermal_gap 0.5)
			(thermal_bridge_width 0.5)
			(island_removal_mode 1)
			(island_area_min 10)
		)
		(polygon
			(pts
				(xy 172.2875 125.499323) (xy 172.282682 125.568763) (xy 172.26896 125.620087) (xy 172.222245 125.695628)
				(xy 172.212702 125.707768) (xy 172.162919 125.774997) (xy 172.35 125.901) (xy 172.537081 125.774997)
				(xy 172.487299 125.707769) (xy 172.432894 125.624603) (xy 172.41781 125.571748) (xy 172.4125 125.499323)
			)
		)
	)
	(zone
		(net 74)
		(net_name "+1V0")
		(layer "B.Cu")
		(name "$teardrop_padvia$")
		(hatch none 0.1)
		(priority 30066)
		(attr
			(teardrop
				(type padvia)
			)
		)
		(connect_pads yes
			(clearance 0)
		)
		(min_thickness 0.0254)
		(filled_areas_thickness no)
		(fill yes
			(thermal_gap 0.5)
			(thermal_bridge_width 0.5)
			(island_removal_mode 1)
			(island_area_min 10)
		)
		(polygon
			(pts
				(xy 135.766 133.1) (xy 135.822935 133.090213) (xy 135.879278 133.078953) (xy 135.936423 133.08011)
				(xy 135.987282 133.10797) (xy 136.008141 133.136379) (xy 136.024771 133.176821) (xy 136.427 132.789)
				(xy 135.948995 132.471582) (xy 135.940814 132.528752) (xy 135.925519 132.568016) (xy 135.906905 132.590689)
				(xy 135.885003 132.603517) (xy 135.82962 132.608196) (xy 135.800948 132.604083) (xy 135.766 132.6)
			)
		)
	)
	(zone
		(net 90)
		(net_name "/Com Express 7 Interfaces/PCIe_{B2Ax4}.RX0+")
		(layer "B.Cu")
		(name "$teardrop_padvia$")
		(hatch none 0.1)
		(priority 30488)
		(attr
			(teardrop
				(type padvia)
			)
		)
		(connect_pads yes
			(clearance 0)
		)
		(min_thickness 0.0254)
		(filled_areas_thickness no)
		(fill yes
			(thermal_gap 0.5)
			(thermal_bridge_width 0.5)
			(island_removal_mode 1)
			(island_area_min 10)
		)
		(polygon
			(pts
				(xy 211.195708 165.02794) (xy 211.166403 164.991938) (xy 211.151009 164.957945) (xy 211.149514 164.892838)
				(xy 211.160451 164.847937) (xy 211.172609 164.797983) (xy 211.177177 164.742327) (xy 210.955793 164.749293)
				(xy 210.812116 164.9177) (xy 210.937315 165.045296) (xy 211.052874 165.170774)
			)
		)
	)
	(zone
		(net 1)
		(net_name "GND")
		(layer "B.Cu")
		(name "$teardrop_padvia$")
		(hatch none 0.1)
		(priority 30268)
		(attr
			(teardrop
				(type padvia)
			)
		)
		(connect_pads yes
			(clearance 0)
		)
		(min_thickness 0.0254)
		(filled_areas_thickness no)
		(fill yes
			(thermal_gap 0.5)
			(thermal_bridge_width 0.5)
			(island_removal_mode 1)
			(island_area_min 10)
		)
		(polygon
			(pts
				(xy 99.860677 166.45) (xy 99.703106 166.443069) (xy 99.589578 166.414549) (xy 99.547778 166.3975)
				(xy 99.459 166.6) (xy 99.547778 166.8025) (xy 99.643817 166.768118) (xy 99.745689 166.7529) (xy 99.860677 166.75)
			)
		)
	)
	(zone
		(net 64)
		(net_name "Net-(U19-V_{CC})")
		(layer "B.Cu")
		(name "$teardrop_padvia$")
		(hatch none 0.1)
		(priority 30334)
		(attr
			(teardrop
				(type padvia)
			)
		)
		(connect_pads yes
			(clearance 0)
		)
		(min_thickness 0.0254)
		(filled_areas_thickness no)
		(fill yes
			(thermal_gap 0.5)
			(thermal_bridge_width 0.5)
			(island_removal_mode 1)
			(island_area_min 10)
		)
		(polygon
			(pts
				(xy 310.262999 106.5675) (xy 310.200133 106.547531) (xy 310.168155 106.521079) (xy 310.139641 106.483668)
				(xy 310.117117 106.436473) (xy 310.101906 106.378833) (xy 310.101797 106.378202) (xy 309.823999 106.63)
				(xy 310.101797 106.881798) (xy 310.116094 106.826365) (xy 310.137174 106.78048) (xy 310.164539 106.742799)
				(xy 310.195447 106.715566) (xy 310.228734 106.698528) (xy 310.261565 106.692511) (xy 310.262999 106.6925)
			)
		)
	)
	(zone
		(net 104)
		(net_name "/OCuLink/PCIe_{x4}.TX2+")
		(layer "B.Cu")
		(name "$teardrop_padvia$")
		(hatch none 0.1)
		(priority 31002)
		(attr
			(teardrop
				(type padvia)
			)
		)
		(connect_pads yes
			(clearance 0)
		)
		(min_thickness 0.0254)
		(filled_areas_thickness no)
		(fill yes
			(thermal_gap 0.5)
			(thermal_bridge_width 0.5)
			(island_removal_mode 1)
			(island_area_min 10)
		)
		(polygon
			(pts
				(xy 104.708 160.509) (xy 104.687352 160.516199) (xy 104.655017 160.525792) (xy 104.640994 160.518965)
				(xy 104.631005 160.4975) (xy 104.382 160.61) (xy 104.631005 160.7225) (xy 104.64073 160.701324)
				(xy 104.654358 160.694269) (xy 104.687352 160.703801) (xy 104.708 160.711)
			)
		)
	)
	(zone
		(net 1)
		(net_name "GND")
		(layer "B.Cu")
		(name "$teardrop_padvia$")
		(hatch none 0.1)
		(priority 30372)
		(attr
			(teardrop
				(type padvia)
			)
		)
		(connect_pads yes
			(clearance 0)
		)
		(min_thickness 0.0254)
		(filled_areas_thickness no)
		(fill yes
			(thermal_gap 0.5)
			(thermal_bridge_width 0.5)
			(island_removal_mode 1)
			(island_area_min 10)
		)
		(polygon
			(pts
				(xy 125.5475 141.622) (xy 125.527531 141.684866) (xy 125.501079 141.716844) (xy 125.463668 141.745358)
				(xy 125.416473 141.767882) (xy 125.358833 141.783093) (xy 125.358202 141.783202) (xy 125.61 142.061)
				(xy 125.861798 141.783202) (xy 125.806365 141.768905) (xy 125.76048 141.747825) (xy 125.722799 141.72046)
				(xy 125.695566 141.689552) (xy 125.678528 141.656265) (xy 125.672511 141.623434) (xy 125.6725 141.622)
			)
		)
	)
	(zone
		(net 1)
		(net_name "GND")
		(layer "B.Cu")
		(name "$teardrop_padvia$")
		(hatch none 0.1)
		(priority 30860)
		(attr
			(teardrop
				(type padvia)
			)
		)
		(connect_pads yes
			(clearance 0)
		)
		(min_thickness 0.0254)
		(filled_areas_thickness no)
		(fill yes
			(thermal_gap 0.5)
			(thermal_bridge_width 0.5)
			(island_removal_mode 1)
			(island_area_min 10)
		)
		(polygon
			(pts
				(xy 314.72 165.61) (xy 314.709885 165.610153) (xy 314.679169 165.60954) (xy 314.64668 165.601218)
				(xy 314.617526 165.577325) (xy 314.596809 165.53) (xy 314.364 165.71) (xy 314.596809 165.89) (xy 314.610168 165.854099)
				(xy 314.628399 165.830801) (xy 314.673725 165.811101) (xy 314.709885 165.809847) (xy 314.72 165.81)
			)
		)
	)
	(zone
		(net 709)
		(net_name "Net-(U37-SCLK)")
		(layer "B.Cu")
		(name "$teardrop_padvia$")
		(hatch none 0.1)
		(priority 30702)
		(attr
			(teardrop
				(type padvia)
			)
		)
		(connect_pads yes
			(clearance 0)
		)
		(min_thickness 0.0254)
		(filled_areas_thickness no)
		(fill yes
			(thermal_gap 0.5)
			(thermal_bridge_width 0.5)
			(island_removal_mode 1)
			(island_area_min 10)
		)
		(polygon
			(pts
				(xy 214.308181 125.185986) (xy 214.303363 125.255426) (xy 214.289641 125.30675) (xy 214.242926 125.382291)
				(xy 214.233383 125.394431) (xy 214.1836 125.46166) (xy 214.370681 125.587663) (xy 214.557762 125.46166)
				(xy 214.50798 125.394432) (xy 214.453575 125.311266) (xy 214.438491 125.258411) (xy 214.433181 125.185986)
			)
		)
	)
	(zone
		(net 160)
		(net_name "/2xUSB3.0+RJ45/USBSS_2.RX-")
		(layer "B.Cu")
		(name "$teardrop_padvia$")
		(hatch none 0.1)
		(priority 30957)
		(attr
			(teardrop
				(type padvia)
			)
		)
		(connect_pads yes
			(clearance 0)
		)
		(min_thickness 0.0254)
		(filled_areas_thickness no)
		(fill yes
			(thermal_gap 0.5)
			(thermal_bridge_width 0.5)
			(island_removal_mode 1)
			(island_area_min 10)
		)
		(polygon
			(pts
				(xy 124.11 105.1475) (xy 124.029692 105.163252) (xy 123.941833 105.182671) (xy 123.893195 105.184154)
				(xy 123.841649 105.175) (xy 123.784 105.3) (xy 124.059774 105.363633) (xy 124.064254 105.3352) (xy 124.075265 105.325347)
				(xy 124.097475 105.32922) (xy 124.11 105.3325)
			)
		)
	)
	(zone
		(net 269)
		(net_name "/Com Express 7 Interfaces/PCIe_{B2Bx4}.TX0+")
		(layer "B.Cu")
		(name "$teardrop_padvia$")
		(hatch none 0.1)
		(priority 30163)
		(attr
			(teardrop
				(type padvia)
			)
		)
		(connect_pads yes
			(clearance 0)
		)
		(min_thickness 0.0254)
		(filled_areas_thickness no)
		(fill yes
			(thermal_gap 0.5)
			(thermal_bridge_width 0.5)
			(island_removal_mode 1)
			(island_area_min 10)
		)
		(polygon
			(pts
				(xy 175.39 104.5165) (xy 175.541135 104.505396) (xy 175.739483 104.490783) (xy 175.855984 104.49382)
				(xy 175.986425 104.51) (xy 176.201 104.36) (xy 175.45 104.276078) (xy 175.445523 104.306714) (xy 175.434181 104.319642)
				(xy 175.404152 104.317508) (xy 175.39 104.3145)
			)
		)
	)
	(zone
		(net 312)
		(net_name "/2xUSB3.0+RJ45/USB_1.D-")
		(layer "B.Cu")
		(name "$teardrop_padvia$")
		(hatch none 0.1)
		(priority 30582)
		(attr
			(teardrop
				(type padvia)
			)
		)
		(connect_pads yes
			(clearance 0)
		)
		(min_thickness 0.0254)
		(filled_areas_thickness no)
		(fill yes
			(thermal_gap 0.5)
			(thermal_bridge_width 0.5)
			(island_removal_mode 1)
			(island_area_min 10)
		)
		(polygon
			(pts
				(xy 147.045978 115.395494) (xy 147.074172 115.430391) (xy 147.088468 115.463324) (xy 147.087628 115.525816)
				(xy 147.073636 115.572096) (xy 147.057949 115.624069) (xy 147.051281 115.682491) (xy 147.272665 115.678749)
				(xy 147.419205 115.513205) (xy 147.290113 115.383916) (xy 147.176793 115.264679)
			)
		)
	)
	(zone
		(net 347)
		(net_name "/2xUSB3.0+RJ45/~{GBE0_ACT}")
		(layer "B.Cu")
		(name "$teardrop_padvia$")
		(hatch none 0.1)
		(priority 30719)
		(attr
			(teardrop
				(type padvia)
			)
		)
		(connect_pads yes
			(clearance 0)
		)
		(min_thickness 0.0254)
		(filled_areas_thickness no)
		(fill yes
			(thermal_gap 0.5)
			(thermal_bridge_width 0.5)
			(island_removal_mode 1)
			(island_area_min 10)
		)
		(polygon
			(pts
				(xy 123.9425 98.260677) (xy 123.947318 98.191236) (xy 123.96104 98.139912) (xy 124.007755 98.06437)
				(xy 124.017299 98.052229) (xy 124.067081 97.985003) (xy 123.88 97.859) (xy 123.692919 97.985003)
				(xy 123.742701 98.052231) (xy 123.797106 98.135397) (xy 123.81219 98.188251) (xy 123.8175 98.260677)
			)
		)
	)
	(zone
		(net 1)
		(net_name "GND")
		(layer "B.Cu")
		(name "$teardrop_padvia$")
		(hatch none 0.1)
		(priority 30857)
		(attr
			(teardrop
				(type padvia)
			)
		)
		(connect_pads yes
			(clearance 0)
		)
		(min_thickness 0.0254)
		(filled_areas_thickness no)
		(fill yes
			(thermal_gap 0.5)
			(thermal_bridge_width 0.5)
			(island_removal_mode 1)
			(island_area_min 10)
		)
		(polygon
			(pts
				(xy 104.735002 162.51) (xy 104.724887 162.510153) (xy 104.694171 162.50954) (xy 104.661682 162.501218)
				(xy 104.632528 162.477325) (xy 104.611811 162.43) (xy 104.379002 162.61) (xy 104.611811 162.79)
				(xy 104.62517 162.754099) (xy 104.643401 162.730801) (xy 104.688727 162.711101) (xy 104.724887 162.709847)
				(xy 104.735002 162.71)
			)
		)
	)
	(zone
		(net 879)
		(net_name "/2xSFP+/SFI1.TX+")
		(layer "B.Cu")
		(name "$teardrop_padvia$")
		(hatch none 0.1)
		(priority 30627)
		(attr
			(teardrop
				(type padvia)
			)
		)
		(connect_pads yes
			(clearance 0)
		)
		(min_thickness 0.0254)
		(filled_areas_thickness no)
		(fill yes
			(thermal_gap 0.5)
			(thermal_bridge_width 0.5)
			(island_removal_mode 1)
			(island_area_min 10)
		)
		(polygon
			(pts
				(xy 129.065 147.977084) (xy 129.069756 147.936299) (xy 129.083046 147.906971) (xy 129.127406 147.872311)
				(xy 129.170219 147.855729) (xy 129.255003 147.817081) (xy 129.13 147.629) (xy 128.909323 147.632143)
				(xy 128.907568 147.797771) (xy 128.905 147.977084)
			)
		)
	)
	(zone
		(net 718)
		(net_name "Net-(U40-I2C_{DONE})")
		(layer "B.Cu")
		(name "$teardrop_padvia$")
		(hatch none 0.1)
		(priority 30929)
		(attr
			(teardrop
				(type padvia)
			)
		)
		(connect_pads yes
			(clearance 0)
		)
		(min_thickness 0.0254)
		(filled_areas_thickness no)
		(fill yes
			(thermal_gap 0.5)
			(thermal_bridge_width 0.5)
			(island_removal_mode 1)
			(island_area_min 10)
		)
		(polygon
			(pts
				(xy 197.999569 134.611182) (xy 197.994726 134.606552) (xy 197.973022 134.577672) (xy 197.971994 134.556417)
				(xy 197.985032 134.529119) (xy 197.612466 134.307441) (xy 197.818661 134.676927) (xy 197.845997 134.66676)
				(xy 197.868063 134.6677) (xy 197.906422 134.694655) (xy 197.911182 134.699569)
			)
		)
	)
	(zone
		(net 1)
		(net_name "GND")
		(layer "B.Cu")
		(name "$teardrop_padvia$")
		(hatch none 0.1)
		(priority 30772)
		(attr
			(teardrop
				(type padvia)
			)
		)
		(connect_pads yes
			(clearance 0)
		)
		(min_thickness 0.0254)
		(filled_areas_thickness no)
		(fill yes
			(thermal_gap 0.5)
			(thermal_bridge_width 0.5)
			(island_removal_mode 1)
			(island_area_min 10)
		)
		(polygon
			(pts
				(xy 199.110873 133.352515) (xy 199.163382 133.306819) (xy 199.209376 133.280231) (xy 199.295824 133.259847)
				(xy 199.31116 133.258011) (xy 199.393895 133.245677) (xy 199.350707 133.024293) (xy 199.129323 132.981105)
				(xy 199.116988 133.063841) (xy 199.096651 133.161119) (xy 199.069943 133.209159) (xy 199.022485 133.264127)
			)
		)
	)
	(zone
		(net 2)
		(net_name "+3V3")
		(layer "B.Cu")
		(name "$teardrop_padvia$")
		(hatch none 0.1)
		(priority 30151)
		(attr
			(teardrop
				(type padvia)
			)
		)
		(connect_pads yes
			(clearance 0)
		)
		(min_thickness 0.0254)
		(filled_areas_thickness no)
		(fill yes
			(thermal_gap 0.5)
			(thermal_bridge_width 0.5)
			(island_removal_mode 1)
			(island_area_min 10)
		)
		(polygon
			(pts
				(xy 124.154539 99.444039) (xy 124.10583 99.484585) (xy 124.042024 99.519535) (xy 123.983139 99.538331)
				(xy 123.915559 99.54697) (xy 123.824526 99.54) (xy 123.879293 99.860707) (xy 124.175 99.940474)
				(xy 124.180044 99.807289) (xy 124.218852 99.69195) (xy 124.285677 99.596127) (xy 124.295961 99.585461)
			)
		)
	)
	(zone
		(net 205)
		(net_name "/Backplane/PCIe_{REF}.CK-")
		(layer "B.Cu")
		(name "$teardrop_padvia$")
		(hatch none 0.1)
		(priority 31005)
		(attr
			(teardrop
				(type padvia)
			)
		)
		(connect_pads yes
			(clearance 0)
		)
		(min_thickness 0.0254)
		(filled_areas_thickness no)
		(fill yes
			(thermal_gap 0.5)
			(thermal_bridge_width 0.5)
			(island_removal_mode 1)
			(island_area_min 10)
		)
		(polygon
			(pts
				(xy 314.69 165.109) (xy 314.669352 165.116199) (xy 314.637017 165.125792) (xy 314.622994 165.118965)
				(xy 314.613005 165.0975) (xy 314.364 165.21) (xy 314.613005 165.3225) (xy 314.62273 165.301324)
				(xy 314.636358 165.294269) (xy 314.669352 165.303801) (xy 314.69 165.311)
			)
		)
	)
	(zone
		(net 891)
		(net_name "Net-(D13-A)")
		(layer "B.Cu")
		(name "$teardrop_padvia$")
		(hatch none 0.1)
		(priority 30122)
		(attr
			(teardrop
				(type padvia)
			)
		)
		(connect_pads yes
			(clearance 0)
		)
		(min_thickness 0.0254)
		(filled_areas_thickness no)
		(fill yes
			(thermal_gap 0.5)
			(thermal_bridge_width 0.5)
			(island_removal_mode 1)
			(island_area_min 10)
		)
		(polygon
			(pts
				(xy 178.56 88.6975) (xy 178.50156 88.678243) (xy 178.447486 88.617235) (xy 178.407203 88.507634)
				(xy 178.396022 88.4) (xy 177.999 88.76) (xy 178.396022 89.12) (xy 178.401642 89.044212) (xy 178.415856 88.977749)
				(xy 178.437451 88.921481) (xy 178.465051 88.876792) (xy 178.495041 88.846501) (xy 178.528017 88.828124)
				(xy 178.56 88.8225)
			)
		)
	)
	(zone
		(net 2)
		(net_name "+3V3")
		(layer "B.Cu")
		(name "$teardrop_padvia$")
		(hatch none 0.1)
		(priority 30210)
		(attr
			(teardrop
				(type padvia)
			)
		)
		(connect_pads yes
			(clearance 0)
		)
		(min_thickness 0.0254)
		(filled_areas_thickness no)
		(fill yes
			(thermal_gap 0.5)
			(thermal_bridge_width 0.5)
			(island_removal_mode 1)
			(island_area_min 10)
		)
		(polygon
			(pts
				(xy 115.388 70.19) (xy 115.37113 70.190338) (xy 115.326174 70.189759) (xy 115.278831 70.177941)
				(xy 115.236427 70.143362) (xy 115.206292 70.0745) (xy 114.949 70.34) (xy 115.206292 70.6055) (xy 115.221849 70.560731)
				(xy 115.242565 70.529115) (xy 115.293701 70.496381) (xy 115.37113 70.489662) (xy 115.388 70.49)
			)
		)
	)
	(zone
		(net 243)
		(net_name "/Com Express 7 Interfaces/PCIe_{B2Bx4}.RX2-")
		(layer "B.Cu")
		(name "$teardrop_padvia$")
		(hatch none 0.1)
		(priority 30563)
		(attr
			(teardrop
				(type padvia)
			)
		)
		(connect_pads yes
			(clearance 0)
		)
		(min_thickness 0.0254)
		(filled_areas_thickness no)
		(fill yes
			(thermal_gap 0.5)
			(thermal_bridge_width 0.5)
			(island_removal_mode 1)
			(island_area_min 10)
		)
		(polygon
			(pts
				(xy 173.967496 97.2035) (xy 173.805964 97.208895) (xy 173.721554 97.212445) (xy 173.61986 97.207823)
				(xy 173.599 97.4285) (xy 173.748852 97.591731) (xy 173.802992 97.523062) (xy 173.812883 97.506608)
				(xy 173.837383 97.467935) (xy 173.86689 97.435721) (xy 173.908046 97.413673) (xy 173.967496 97.4055)
			)
		)
	)
	(zone
		(net 74)
		(net_name "+1V0")
		(layer "B.Cu")
		(name "$teardrop_padvia$")
		(hatch none 0.1)
		(priority 30159)
		(attr
			(teardrop
				(type padvia)
			)
		)
		(connect_pads yes
			(clearance 0)
		)
		(min_thickness 0.0254)
		(filled_areas_thickness no)
		(fill yes
			(thermal_gap 0.5)
			(thermal_bridge_width 0.5)
			(island_removal_mode 1)
			(island_area_min 10)
		)
		(polygon
			(pts
				(xy 153.843 132.61) (xy 153.798355 132.630403) (xy 153.764808 132.649221) (xy 153.732345 132.657795)
				(xy 153.705635 132.643697) (xy 153.689347 132.5945) (xy 153.429 132.86) (xy 153.689347 133.1255)
				(xy 153.699167 133.087407) (xy 153.714574 133.067642) (xy 153.7489 133.064648) (xy 153.798355 133.089597)
				(xy 153.843 133.11)
			)
		)
	)
	(zone
		(net 162)
		(net_name "Net-(J2A-TX_{FAULT})")
		(layer "B.Cu")
		(name "$teardrop_padvia$")
		(hatch none 0.1)
		(priority 30095)
		(attr
			(teardrop
				(type padvia)
			)
		)
		(connect_pads yes
			(clearance 0)
		)
		(min_thickness 0.0254)
		(filled_areas_thickness no)
		(fill yes
			(thermal_gap 0.5)
			(thermal_bridge_width 0.5)
			(island_removal_mode 1)
			(island_area_min 10)
		)
		(polygon
			(pts
				(xy 143.121993 167.726396) (xy 143.183423 167.671775) (xy 143.23932 167.635259) (xy 143.338191 167.602229)
				(xy 143.441905 167.59498) (xy 143.525099 167.591201) (xy 143.623159 167.577794) (xy 143.550707 167.209293)
				(xy 143.182206 167.136841) (xy 143.16583 167.290423) (xy 143.16502 167.318096) (xy 143.160967 167.397317)
				(xy 143.145512 167.472488) (xy 143.106956 167.550441) (xy 143.033604 167.638007)
			)
		)
	)
	(zone
		(net 171)
		(net_name "/2xSFP+/SFI0.RX+")
		(layer "B.Cu")
		(name "$teardrop_padvia$")
		(hatch none 0.1)
		(priority 30632)
		(attr
			(teardrop
				(type padvia)
			)
		)
		(connect_pads yes
			(clearance 0)
		)
		(min_thickness 0.0254)
		(filled_areas_thickness no)
		(fill yes
			(thermal_gap 0.5)
			(thermal_bridge_width 0.5)
			(island_removal_mode 1)
			(island_area_min 10)
		)
		(polygon
			(pts
				(xy 149.84 147.977084) (xy 149.837432 147.797777) (xy 149.835677 147.632143) (xy 149.615 147.629)
				(xy 149.489997 147.817081) (xy 149.574781 147.855729) (xy 149.615597 147.871388) (xy 149.649058 147.892373)
				(xy 149.671685 147.925376) (xy 149.68 147.977084)
			)
		)
	)
	(zone
		(net 201)
		(net_name "/OCuLink/~{CPRSNT_D0}")
		(layer "B.Cu")
		(name "$teardrop_padvia$")
		(hatch none 0.1)
		(priority 30343)
		(attr
			(teardrop
				(type padvia)
			)
		)
		(connect_pads yes
			(clearance 0)
		)
		(min_thickness 0.0254)
		(filled_areas_thickness no)
		(fill yes
			(thermal_gap 0.5)
			(thermal_bridge_width 0.5)
			(island_removal_mode 1)
			(island_area_min 10)
		)
		(polygon
			(pts
				(xy 121.1575 161.122) (xy 121.137531 161.184866) (xy 121.111079 161.216844) (xy 121.073668 161.245358)
				(xy 121.026473 161.267882) (xy 120.968833 161.283093) (xy 120.968202 161.283202) (xy 121.22 161.561)
				(xy 121.471798 161.283202) (xy 121.416365 161.268905) (xy 121.37048 161.247825) (xy 121.332799 161.22046)
				(xy 121.305566 161.189552) (xy 121.288528 161.156265) (xy 121.282511 161.123434) (xy 121.2825 161.122)
			)
		)
	)
	(zone
		(net 974)
		(net_name "/PCIe redriver/RX_FG1")
		(layer "B.Cu")
		(name "$teardrop_padvia$")
		(hatch none 0.1)
		(priority 30934)
		(attr
			(teardrop
				(type padvia)
			)
		)
		(connect_pads yes
			(clearance 0)
		)
		(min_thickness 0.0254)
		(filled_areas_thickness no)
		(fill yes
			(thermal_gap 0.5)
			(thermal_bridge_width 0.5)
			(island_removal_mode 1)
			(island_area_min 10)
		)
		(polygon
			(pts
				(xy 192.354694 140.313378) (xy 192.352908 140.310757) (xy 192.322053 140.254789) (xy 192.316384 140.220993)
				(xy 192.327764 140.18805) (xy 191.956319 139.964002) (xy 192.17729 140.336861) (xy 192.197545 140.322291)
				(xy 192.220248 140.307583) (xy 192.229694 140.313378)
			)
		)
	)
	(zone
		(net 209)
		(net_name "/Com Express 7 Interfaces/PCIe_{B1x4}.RX3-")
		(layer "B.Cu")
		(name "$teardrop_padvia$")
		(hatch none 0.1)
		(priority 30552)
		(attr
			(teardrop
				(type padvia)
			)
		)
		(connect_pads yes
			(clearance 0)
		)
		(min_thickness 0.0254)
		(filled_areas_thickness no)
		(fill yes
			(thermal_gap 0.5)
			(thermal_bridge_width 0.5)
			(island_removal_mode 1)
			(island_area_min 10)
		)
		(polygon
			(pts
				(xy 204.8685 161.032504) (xy 204.873895 161.194035) (xy 204.877445 161.278446) (xy 204.872823 161.38014)
				(xy 205.0935 161.401) (xy 205.256731 161.251147) (xy 205.188062 161.197007) (xy 205.171608 161.187116)
				(xy 205.132935 161.162616) (xy 205.100721 161.133109) (xy 205.078673 161.091953) (xy 205.0705 161.032504)
			)
		)
	)
	(zone
		(net 196)
		(net_name "/OCuLink/PCIe_{x4}.RX3+")
		(layer "B.Cu")
		(name "$teardrop_padvia$")
		(hatch none 0.1)
		(priority 30557)
		(attr
			(teardrop
				(type padvia)
			)
		)
		(connect_pads yes
			(clearance 0)
		)
		(min_thickness 0.0254)
		(filled_areas_thickness no)
		(fill yes
			(thermal_gap 0.5)
			(thermal_bridge_width 0.5)
			(island_removal_mode 1)
			(island_area_min 10)
		)
		(polygon
			(pts
				(xy 99.392496 158.4435) (xy 99.230964 158.448895) (xy 99.146554 158.452445) (xy 99.04486 158.447823)
				(xy 99.024 158.6685) (xy 99.173852 158.831731) (xy 99.227992 158.763062) (xy 99.237883 158.746608)
				(xy 99.262383 158.707935) (xy 99.29189 158.675721) (xy 99.333046 158.653673) (xy 99.392496 158.6455)
			)
		)
	)
	(zone
		(net 206)
		(net_name "/Backplane/USB.D+")
		(layer "B.Cu")
		(name "$teardrop_padvia$")
		(hatch none 0.1)
		(priority 30944)
		(attr
			(teardrop
				(type padvia)
			)
		)
		(connect_pads yes
			(clearance 0)
		)
		(min_thickness 0.0254)
		(filled_areas_thickness no)
		(fill yes
			(thermal_gap 0.5)
			(thermal_bridge_width 0.5)
			(island_removal_mode 1)
			(island_area_min 10)
		)
		(polygon
			(pts
				(xy 315.462 166.1755) (xy 315.449475 166.17878) (xy 315.424498 166.181714) (xy 315.415392 166.170753)
				(xy 315.411774 166.144366) (xy 315.136 166.208) (xy 315.193649 166.333) (xy 315.281774 166.324159)
				(xy 315.381692 166.344748) (xy 315.462 166.3605)
			)
		)
	)
	(zone
		(net 167)
		(net_name "Net-(J2A-RS0)")
		(layer "B.Cu")
		(name "$teardrop_padvia$")
		(hatch none 0.1)
		(priority 30418)
		(attr
			(teardrop
				(type padvia)
			)
		)
		(connect_pads yes
			(clearance 0)
		)
		(min_thickness 0.0254)
		(filled_areas_thickness no)
		(fill yes
			(thermal_gap 0.5)
			(thermal_bridge_width 0.5)
			(island_removal_mode 1)
			(island_area_min 10)
		)
		(polygon
			(pts
				(xy 145.9875 168.267) (xy 145.967727 168.326412) (xy 145.904453 168.382496) (xy 145.855828 168.404198)
				(xy 145.796469 168.418872) (xy 145.7845 168.420652) (xy 146.05 168.681) (xy 146.3155 168.420652)
				(xy 146.255362 168.407803) (xy 146.205478 168.387869) (xy 146.165358 168.361944) (xy 146.136345 168.332124)
				(xy 146.118854 168.300706) (xy 146.112521 168.268895) (xy 146.1125 168.267)
			)
		)
	)
	(zone
		(net 285)
		(net_name "/2xUSB3.0+RJ45/GbE.MDI3-")
		(layer "B.Cu")
		(name "$teardrop_padvia$")
		(hatch none 0.1)
		(priority 30662)
		(attr
			(teardrop
				(type padvia)
			)
		)
		(connect_pads yes
			(clearance 0)
		)
		(min_thickness 0.0254)
		(filled_areas_thickness no)
		(fill yes
			(thermal_gap 0.5)
			(thermal_bridge_width 0.5)
			(island_removal_mode 1)
			(island_area_min 10)
		)
		(polygon
			(pts
				(xy 176.675 167.742084) (xy 176.672797 167.536718) (xy 176.670677 167.398242) (xy 176.45 167.399)
				(xy 176.324997 167.587081) (xy 176.401138 167.620995) (xy 176.417738 167.62605) (xy 176.459281 167.639844)
				(xy 176.493398 167.659262) (xy 176.516501 167.691083) (xy 176.525 167.742084)
			)
		)
	)
	(zone
		(net 1)
		(net_name "GND")
		(layer "B.Cu")
		(name "$teardrop_padvia$")
		(hatch none 0.1)
		(priority 30262)
		(attr
			(teardrop
				(type padvia)
			)
		)
		(connect_pads yes
			(clearance 0)
		)
		(min_thickness 0.0254)
		(filled_areas_thickness no)
		(fill yes
			(thermal_gap 0.5)
			(thermal_bridge_width 0.5)
			(island_removal_mode 1)
			(island_area_min 10)
		)
		(polygon
			(pts
				(xy 99.860677 161.95) (xy 99.703106 161.943069) (xy 99.589578 161.914549) (xy 99.547778 161.8975)
				(xy 99.459 162.1) (xy 99.547778 162.3025) (xy 99.643817 162.268118) (xy 99.745689 162.2529) (xy 99.860677 162.25)
			)
		)
	)
	(zone
		(net 659)
		(net_name "Net-(U43C-PRTAD3)")
		(layer "B.Cu")
		(name "$teardrop_padvia$")
		(hatch none 0.1)
		(priority 30821)
		(attr
			(teardrop
				(type padvia)
			)
		)
		(connect_pads yes
			(clearance 0)
		)
		(min_thickness 0.0254)
		(filled_areas_thickness no)
		(fill yes
			(thermal_gap 0.5)
			(thermal_bridge_width 0.5)
			(island_removal_mode 1)
			(island_area_min 10)
		)
		(polygon
			(pts
				(xy 148.369972 136.51836) (xy 148.391126 136.546262) (xy 148.397606 136.571695) (xy 148.380399 136.614244)
				(xy 148.331809 136.662514) (xy 148.262919 136.734997) (xy 148.450707 136.860707) (xy 148.637081 136.734997)
				(xy 148.579376 136.62356) (xy 148.573136 136.607691) (xy 148.535714 136.526403) (xy 148.45836 136.429972)
			)
		)
	)
	(zone
		(net 90)
		(net_name "/Com Express 7 Interfaces/PCIe_{B2Ax4}.RX0+")
		(layer "B.Cu")
		(name "$teardrop_padvia$")
		(hatch none 0.1)
		(priority 30496)
		(attr
			(teardrop
				(type padvia)
			)
		)
		(connect_pads yes
			(clearance 0)
		)
		(min_thickness 0.0254)
		(filled_areas_thickness no)
		(fill yes
			(thermal_gap 0.5)
			(thermal_bridge_width 0.5)
			(island_removal_mode 1)
			(island_area_min 10)
		)
		(polygon
			(pts
				(xy 296.153 75.019852) (xy 296.148265 75.066638) (xy 296.135121 75.10209) (xy 296.090113 75.150287)
				(xy 296.051893 75.174463) (xy 296.008726 75.201832) (xy 295.966768 75.238495) (xy 296.13 75.388348)
				(xy 296.350677 75.367488) (xy 296.346048 75.266817) (xy 296.34948 75.18345) (xy 296.349605 75.181383)
				(xy 296.355 75.019852)
			)
		)
	)
	(zone
		(net 358)
		(net_name "/Com Express 7 MGMT/SMBus.SDA")
		(layer "B.Cu")
		(name "$teardrop_padvia$")
		(hatch none 0.1)
		(priority 30407)
		(attr
			(teardrop
				(type padvia)
			)
		)
		(connect_pads yes
			(clearance 0)
		)
		(min_thickness 0.0254)
		(filled_areas_thickness no)
		(fill yes
			(thermal_gap 0.5)
			(thermal_bridge_width 0.5)
			(island_removal_mode 1)
			(island_area_min 10)
		)
		(polygon
			(pts
				(xy 108.393 161.9975) (xy 108.333588 161.977727) (xy 108.277503 161.914453) (xy 108.255801 161.865828)
				(xy 108.241127 161.806468) (xy 108.239347 161.7945) (xy 107.979 162.06) (xy 108.239347 162.3255)
				(xy 108.252197 162.265361) (xy 108.272131 162.215477) (xy 108.298056 162.175358) (xy 108.327876 162.146345)
				(xy 108.359294 162.128854) (xy 108.391105 162.122521) (xy 108.393 162.1225)
			)
		)
	)
	(zone
		(net 161)
		(net_name "/2xUSB3.0+RJ45/USBSS_2.RX+")
		(layer "B.Cu")
		(name "$teardrop_padvia$")
		(hatch none 0.1)
		(priority 30942)
		(attr
			(teardrop
				(type padvia)
			)
		)
		(connect_pads yes
			(clearance 0)
		)
		(min_thickness 0.0254)
		(filled_areas_thickness no)
		(fill yes
			(thermal_gap 0.5)
			(thermal_bridge_width 0.5)
			(island_removal_mode 1)
			(island_area_min 10)
		)
		(polygon
			(pts
				(xy 124.11 104.7675) (xy 124.097475 104.77078) (xy 124.072498 104.773714) (xy 124.063392 104.762753)
				(xy 124.059774 104.736366) (xy 123.784 104.8) (xy 123.841649 104.925) (xy 123.929774 104.916159)
				(xy 124.029692 104.936748) (xy 124.11 104.9525)
			)
		)
	)
	(zone
		(net 1)
		(net_name "GND")
		(layer "B.Cu")
		(name "$teardrop_padvia$")
		(hatch none 0.1)
		(priority 30688)
		(attr
			(teardrop
				(type padvia)
			)
		)
		(connect_pads yes
			(clearance 0)
		)
		(min_thickness 0.0254)
		(filled_areas_thickness no)
		(fill yes
			(thermal_gap 0.5)
			(thermal_bridge_width 0.5)
			(island_removal_mode 1)
			(island_area_min 10)
		)
		(polygon
			(pts
				(xy 147.4875 169.909323) (xy 147.482682 169.978763) (xy 147.46896 170.030087) (xy 147.422245 170.105628)
				(xy 147.412702 170.117768) (xy 147.362919 170.184997) (xy 147.55 170.311) (xy 147.737081 170.184997)
				(xy 147.687299 170.117769) (xy 147.632894 170.034603) (xy 147.61781 169.981748) (xy 147.6125 169.909323)
			)
		)
	)
	(zone
		(net 2)
		(net_name "+3V3")
		(layer "B.Cu")
		(name "$teardrop_padvia$")
		(hatch none 0.1)
		(priority 30342)
		(attr
			(teardrop
				(type padvia)
			)
		)
		(connect_pads yes
			(clearance 0)
		)
		(min_thickness 0.0254)
		(filled_areas_thickness no)
		(fill yes
			(thermal_gap 0.5)
			(thermal_bridge_width 0.5)
			(island_removal_mode 1)
			(island_area_min 10)
		)
		(polygon
			(pts
				(xy 145.612 169.7025) (xy 145.674866 169.722469) (xy 145.706844 169.748921) (xy 145.735358 169.786332)
				(xy 145.757882 169.833527) (xy 145.773093 169.891167) (xy 145.773202 169.891798) (xy 146.051 169.64)
				(xy 145.773202 169.388202) (xy 145.758905 169.443635) (xy 145.737825 169.48952) (xy 145.71046 169.527201)
				(xy 145.679552 169.554434) (xy 145.646265 169.571472) (xy 145.613434 169.577489) (xy 145.612 169.5775)
			)
		)
	)
	(zone
		(net 231)
		(net_name "/M.2 key M #1/PCIE_{REF}.CK+")
		(layer "B.Cu")
		(name "$teardrop_padvia$")
		(hatch none 0.1)
		(priority 30297)
		(attr
			(teardrop
				(type padvia)
			)
		)
		(connect_pads yes
			(clearance 0)
		)
		(min_thickness 0.0254)
		(filled_areas_thickness no)
		(fill yes
			(thermal_gap 0.5)
			(thermal_bridge_width 0.5)
			(island_removal_mode 1)
			(island_area_min 10)
		)
		(polygon
			(pts
				(xy 175.39 106.461) (xy 175.404678 106.457463) (xy 175.434685 106.454192) (xy 175.445673 106.466143)
				(xy 175.45 106.495) (xy 176.201 106.36) (xy 175.45 106.225) (xy 175.445525 106.254204) (xy 175.434203 106.265997)
				(xy 175.404678 106.262537) (xy 175.39 106.259)
			)
		)
	)
	(zone
		(net 206)
		(net_name "/Backplane/USB.D+")
		(layer "B.Cu")
		(name "$teardrop_padvia$")
		(hatch none 0.1)
		(priority 31019)
		(attr
			(teardrop
				(type padvia)
			)
		)
		(connect_pads yes
			(clearance 0)
		)
		(min_thickness 0.0254)
		(filled_areas_thickness no)
		(fill yes
			(thermal_gap 0.5)
			(thermal_bridge_width 0.5)
			(island_removal_mode 1)
			(island_area_min 10)
		)
		(polygon
			(pts
				(xy 314.69 166.1175) (xy 314.671686 166.122322) (xy 314.639156 166.128314) (xy 314.625085 166.119851)
				(xy 314.615308 166.097039) (xy 314.364 166.208) (xy 314.610735 166.322015) (xy 314.621132 166.30009)
				(xy 314.635379 166.29151) (xy 314.670616 166.297516) (xy 314.69 166.3025)
			)
		)
	)
	(zone
		(net 78)
		(net_name "+1V8")
		(layer "B.Cu")
		(name "$teardrop_padvia$")
		(hatch none 0.1)
		(priority 30312)
		(attr
			(teardrop
				(type padvia)
			)
		)
		(connect_pads yes
			(clearance 0)
		)
		(min_thickness 0.0254)
		(filled_areas_thickness no)
		(fill yes
			(thermal_gap 0.5)
			(thermal_bridge_width 0.5)
			(island_removal_mode 1)
			(island_area_min 10)
		)
		(polygon
			(pts
				(xy 307.564999 122.853) (xy 307.570771 122.812263) (xy 307.591175 122.770348) (xy 307.61835 122.742047)
				(xy 307.657896 122.718618) (xy 307.730499 122.699347) (xy 307.464999 122.439) (xy 307.199499 122.699347)
				(xy 307.252641 122.711214) (xy 307.29368 122.729662) (xy 307.345381 122.780336) (xy 307.364717 122.843905)
				(xy 307.364999 122.853)
			)
		)
	)
	(zone
		(net 869)
		(net_name "/Backplane/PCIe_{x2}.TX1-")
		(layer "B.Cu")
		(name "$teardrop_padvia$")
		(hatch none 0.1)
		(priority 30989)
		(attr
			(teardrop
				(type padvia)
			)
		)
		(connect_pads yes
			(clearance 0)
		)
		(min_thickness 0.0254)
		(filled_areas_thickness no)
		(fill yes
			(thermal_gap 0.5)
			(thermal_bridge_width 0.5)
			(island_removal_mode 1)
			(island_area_min 10)
		)
		(polygon
			(pts
				(xy 314.812 162.009) (xy 314.832648 162.001802) (xy 314.864984 161.992208) (xy 314.879007 161.999035)
				(xy 314.888995 162.0205) (xy 315.138 161.908) (xy 314.888995 161.7955) (xy 314.879271 161.816676)
				(xy 314.865643 161.823731) (xy 314.832648 161.814198) (xy 314.812 161.807)
			)
		)
	)
	(zone
		(net 264)
		(net_name "/Com Express 7 Interfaces/PCIe_{B2Bx4}.RX0+")
		(layer "B.Cu")
		(name "$teardrop_padvia$")
		(hatch none 0.1)
		(priority 30514)
		(attr
			(teardrop
				(type padvia)
			)
		)
		(connect_pads yes
			(clearance 0)
		)
		(min_thickness 0.0254)
		(filled_areas_thickness no)
		(fill yes
			(thermal_gap 0.5)
			(thermal_bridge_width 0.5)
			(island_removal_mode 1)
			(island_area_min 10)
		)
		(polygon
			(pts
				(xy 173.967496 102.8145) (xy 173.92071 102.809765) (xy 173.885258 102.796621) (xy 173.83706 102.751613)
				(xy 173.812884 102.713392) (xy 173.785514 102.670225) (xy 173.748852 102.628268) (xy 173.599 102.7915)
				(xy 173.61986 103.012177) (xy 173.720531 103.007548) (xy 173.803897 103.01098) (xy 173.805964 103.011105)
				(xy 173.967496 103.0165)
			)
		)
	)
	(zone
		(net 196)
		(net_name "/OCuLink/PCIe_{x4}.RX3+")
		(layer "B.Cu")
		(name "$teardrop_padvia$")
		(hatch none 0.1)
		(priority 30836)
		(attr
			(teardrop
				(type padvia)
			)
		)
		(connect_pads yes
			(clearance 0)
		)
		(min_thickness 0.0254)
		(filled_areas_thickness no)
		(fill yes
			(thermal_gap 0.5)
			(thermal_bridge_width 0.5)
			(island_removal_mode 1)
			(island_area_min 10)
		)
		(polygon
			(pts
				(xy 190.253606 136.205315) (xy 190.267831 136.211115) (xy 190.290309 136.222487) (xy 190.290619 136.234427)
				(xy 190.276416 136.253476) (xy 190.631201 136.518564) (xy 190.646298 136.356885) (xy 190.549807 136.273518)
				(xy 190.463598 136.154287) (xy 190.396441 136.06248)
			)
		)
	)
	(zone
		(net 78)
		(net_name "+1V8")
		(layer "B.Cu")
		(name "$teardrop_padvia$")
		(hatch none 0.1)
		(priority 30074)
		(attr
			(teardrop
				(type padvia)
			)
		)
		(connect_pads yes
			(clearance 0)
		)
		(min_thickness 0.0254)
		(filled_areas_thickness no)
		(fill yes
			(thermal_gap 0.5)
			(thermal_bridge_width 0.5)
			(island_removal_mode 1)
			(island_area_min 10)
		)
		(polygon
			(pts
				(xy 129.54 133.35) (xy 129.520089 133.270432) (xy 129.501663 133.21135) (xy 129.493589 133.151728)
				(xy 129.508329 133.097203) (xy 129.558343 133.053408) (xy 129.063 132.789) (xy 128.836903 133.19)
				(xy 128.914277 133.194709) (xy 128.969226 133.207669) (xy 129.00245 133.224807) (xy 129.023498 133.245891)
				(xy 129.040051 133.296784) (xy 129.040332 133.333217) (xy 129.04 133.35)
			)
		)
	)
	(zone
		(net 533)
		(net_name "/Com Express 7 MGMT/PSON")
		(layer "B.Cu")
		(name "$teardrop_padvia$")
		(hatch none 0.1)
		(priority 30733)
		(attr
			(teardrop
				(type padvia)
			)
		)
		(connect_pads yes
			(clearance 0)
		)
		(min_thickness 0.0254)
		(filled_areas_thickness no)
		(fill yes
			(thermal_gap 0.5)
			(thermal_bridge_width 0.5)
			(island_removal_mode 1)
			(island_area_min 10)
		)
		(polygon
			(pts
				(xy 304.275677 137.7465) (xy 304.206236 137.741682) (xy 304.154913 137.72796) (xy 304.079371 137.681246)
				(xy 304.067231 137.671701) (xy 304.000003 137.621919) (xy 303.874 137.809) (xy 304.000003 137.996081)
				(xy 304.067229 137.946299) (xy 304.150396 137.891894) (xy 304.203251 137.87681) (xy 304.275677 137.8715)
			)
		)
	)
	(zone
		(net 2)
		(net_name "+3V3")
		(layer "B.Cu")
		(name "$teardrop_padvia$")
		(hatch none 0.1)
		(priority 30281)
		(attr
			(teardrop
				(type padvia)
			)
		)
		(connect_pads yes
			(clearance 0)
		)
		(min_thickness 0.0254)
		(filled_areas_thickness no)
		(fill yes
			(thermal_gap 0.5)
			(thermal_bridge_width 0.5)
			(island_removal_mode 1)
			(island_area_min 10)
		)
		(polygon
			(pts
				(xy 105.269323 170.11) (xy 105.397794 170.115605) (xy 105.489843 170.134841) (xy 105.576705 170.170214)
				(xy 105.671 169.97) (xy 105.587397 169.765356) (xy 105.501794 169.793727) (xy 105.416219 169.806563)
				(xy 105.269323 169.81)
			)
		)
	)
	(zone
		(net 2)
		(net_name "+3V3")
		(layer "B.Cu")
		(name "$teardrop_padvia$")
		(hatch none 0.1)
		(priority 30919)
		(attr
			(teardrop
				(type padvia)
			)
		)
		(connect_pads yes
			(clearance 0)
		)
		(min_thickness 0.0254)
		(filled_areas_thickness no)
		(fill yes
			(thermal_gap 0.5)
			(thermal_bridge_width 0.5)
			(island_removal_mode 1)
			(island_area_min 10)
		)
		(polygon
			(pts
				(xy 114.3385 145.1855) (xy 114.338596 145.191822) (xy 114.333011 145.231325) (xy 114.318078 145.249547)
				(xy 114.2885 145.262495) (xy 114.401 145.674) (xy 114.5135 145.262495) (xy 114.486507 145.251379)
				(xy 114.471405 145.235852) (xy 114.463404 145.191822) (xy 114.4635 145.1855)
			)
		)
	)
	(zone
		(net 2)
		(net_name "+3V3")
		(layer "B.Cu")
		(name "$teardrop_padvia$")
		(hatch none 0.1)
		(priority 30286)
		(attr
			(teardrop
				(type padvia)
			)
		)
		(connect_pads yes
			(clearance 0)
		)
		(min_thickness 0.0254)
		(filled_areas_thickness no)
		(fill yes
			(thermal_gap 0.5)
			(thermal_bridge_width 0.5)
			(island_removal_mode 1)
			(island_area_min 10)
		)
		(polygon
			(pts
				(xy 219 127.70558) (xy 218.98651 127.553415) (xy 218.983137 127.533847) (xy 218.972541 127.455442)
				(xy 218.979345 127.37111) (xy 218.76 127.323) (xy 218.584288 127.460372) (xy 218.616801 127.499456)
				(xy 218.675295 127.580923) (xy 218.693335 127.634404) (xy 218.7 127.70558)
			)
		)
	)
	(zone
		(net 1)
		(net_name "GND")
		(layer "B.Cu")
		(hatch edge 0.5)
		(priority 3)
		(connect_pads
			(clearance 0.15)
		)
		(min_thickness 0.25)
		(filled_areas_thickness no)
		(fill yes
			(thermal_gap 0.2)
			(thermal_bridge_width 0.5)
		)
		(polygon
			(pts
				(xy 103.96 82.605) (xy 104.75 82.605) (xy 105.38 83.235) (xy 105.38 86.655) (xy 104.75 87.285) (xy 103.96 87.285)
			)
		)
	)
	(zone
		(net 973)
		(net_name "/PCIe redriver/RX_SW")
		(layer "B.Cu")
		(name "$teardrop_padvia$")
		(hatch none 0.1)
		(priority 30809)
		(attr
			(teardrop
				(type padvia)
			)
		)
		(connect_pads yes
			(clearance 0)
		)
		(min_thickness 0.0254)
		(filled_areas_thickness no)
		(fill yes
			(thermal_gap 0.5)
			(thermal_bridge_width 0.5)
			(island_removal_mode 1)
			(island_area_min 10)
		)
		(polygon
			(pts
				(xy 188.826727 136.039915) (xy 188.781374 135.987757) (xy 188.754972 135.942001) (xy 188.734849 135.855986)
				(xy 188.733014 135.840172) (xy 188.720677 135.756105) (xy 188.499293 135.799293) (xy 188.456105 136.020677)
				(xy 188.537475 136.032996) (xy 188.635099 136.053742) (xy 188.683214 136.080634) (xy 188.738339 136.128303)
			)
		)
	)
	(zone
		(net 1)
		(net_name "GND")
		(layer "B.Cu")
		(name "$teardrop_padvia$")
		(hatch none 0.1)
		(priority 30703)
		(attr
			(teardrop
				(type padvia)
			)
		)
		(connect_pads yes
			(clearance 0)
		)
		(min_thickness 0.0254)
		(filled_areas_thickness no)
		(fill yes
			(thermal_gap 0.5)
			(thermal_bridge_width 0.5)
			(island_removal_mode 1)
			(island_area_min 10)
		)
		(polygon
			(pts
				(xy 137.4875 169.909323) (xy 137.482682 169.978763) (xy 137.46896 170.030087) (xy 137.422245 170.105628)
				(xy 137.412702 170.117768) (xy 137.362919 170.184997) (xy 137.55 170.311) (xy 137.737081 170.184997)
				(xy 137.687299 170.117769) (xy 137.632894 170.034603) (xy 137.61781 169.981748) (xy 137.6125 169.909323)
			)
		)
	)
	(zone
		(net 1)
		(net_name "GND")
		(layer "B.Cu")
		(name "$teardrop_padvia$")
		(hatch none 0.1)
		(priority 30619)
		(attr
			(teardrop
				(type padvia)
			)
		)
		(connect_pads yes
			(clearance 0)
		)
		(min_thickness 0.0254)
		(filled_areas_thickness no)
		(fill yes
			(thermal_gap 0.5)
			(thermal_bridge_width 0.5)
			(island_removal_mode 1)
			(island_area_min 10)
		)
		(polygon
			(pts
				(xy 311.080993 105.1725) (xy 311.160879 105.177131) (xy 311.220598 105.189549) (xy 311.297339 105.219734)
				(xy 311.415145 105.264066) (xy 311.475999 105.05) (xy 311.348348 104.864566) (xy 311.276673 104.931213)
				(xy 311.258154 104.954153) (xy 311.227905 104.990265) (xy 311.193076 105.019961) (xy 311.146495 105.04009)
				(xy 311.080993 105.0475)
			)
		)
	)
	(zone
		(net 1)
		(net_name "GND")
		(layer "B.Cu")
		(name "$teardrop_padvia$")
		(hatch none 0.1)
		(priority 30864)
		(attr
			(teardrop
				(type padvia)
			)
		)
		(connect_pads yes
			(clearance 0)
		)
		(min_thickness 0.0254)
		(filled_areas_thickness no)
		(fill yes
			(thermal_gap 0.5)
			(thermal_bridge_width 0.5)
			(island_removal_mode 1)
			(island_area_min 10)
		)
		(polygon
			(pts
				(xy 314.72 165.61) (xy 314.709885 165.610153) (xy 314.679169 165.60954) (xy 314.64668 165.601218)
				(xy 314.617526 165.577325) (xy 314.596809 165.53) (xy 314.364 165.71) (xy 314.596809 165.89) (xy 314.610168 165.854099)
				(xy 314.628399 165.830801) (xy 314.673725 165.811101) (xy 314.709885 165.809847) (xy 314.72 165.81)
			)
		)
	)
	(zone
		(net 201)
		(net_name "/OCuLink/~{CPRSNT_D0}")
		(layer "B.Cu")
		(name "$teardrop_padvia$")
		(hatch none 0.1)
		(priority 30348)
		(attr
			(teardrop
				(type padvia)
			)
		)
		(connect_pads yes
			(clearance 0)
		)
		(min_thickness 0.0254)
		(filled_areas_thickness no)
		(fill yes
			(thermal_gap 0.5)
			(thermal_bridge_width 0.5)
			(island_removal_mode 1)
			(island_area_min 10)
		)
		(polygon
			(pts
				(xy 121.2825 160.998) (xy 121.302469 160.935134) (xy 121.328921 160.903156) (xy 121.366332 160.874642)
				(xy 121.413527 160.852118) (xy 121.471167 160.836907) (xy 121.471798 160.836798) (xy 121.22 160.559)
				(xy 120.968202 160.836798) (xy 121.023635 160.851095) (xy 121.06952 160.872175) (xy 121.107201 160.89954)
				(xy 121.134434 160.930448) (xy 121.151472 160.963735) (xy 121.157489 160.996566) (xy 121.1575 160.998)
			)
		)
	)
	(zone
		(net 1)
		(net_name "GND")
		(layer "B.Cu")
		(hatch edge 0.5)
		(priority 14)
		(connect_pads
			(clearance 0.15)
		)
		(min_thickness 0.25)
		(filled_areas_thickness no)
		(fill yes
			(thermal_gap 0.2)
			(thermal_bridge_width 0.3)
		)
		(polygon
			(pts
				(xy 310.914999 121.81) (xy 311.814999 121.81) (xy 312.414999 121.21) (xy 312.414999 119.91) (xy 310.914999 119.91)
			)
		)
	)
	(zone
		(net 44)
		(net_name "/2xUSB3.0+RJ45/USBSS_1.TX+")
		(layer "B.Cu")
		(name "$teardrop_padvia$")
		(hatch none 0.1)
		(priority 30974)
		(attr
			(teardrop
				(type padvia)
			)
		)
		(connect_pads yes
			(clearance 0)
		)
		(min_thickness 0.0254)
		(filled_areas_thickness no)
		(fill yes
			(thermal_gap 0.5)
			(thermal_bridge_width 0.5)
			(island_removal_mode 1)
			(island_area_min 10)
		)
		(polygon
			(pts
				(xy 101.624805 104.334553) (xy 101.616832 104.338802) (xy 101.605329 104.341936) (xy 101.6 104.306822)
				(xy 101.324001 104.367033) (xy 101.376191 104.492) (xy 101.465506 104.483319) (xy 101.557278 104.503873)
				(xy 101.631029 104.519447)
			)
		)
	)
	(zone
		(net 357)
		(net_name "/Com Express 7 MGMT/SMBus.SCL")
		(layer "B.Cu")
		(name "$teardrop_padvia$")
		(hatch none 0.1)
		(priority 30396)
		(attr
			(teardrop
				(type padvia)
			)
		)
		(connect_pads yes
			(clearance 0)
		)
		(min_thickness 0.0254)
		(filled_areas_thickness no)
		(fill yes
			(thermal_gap 0.5)
			(thermal_bridge_width 0.5)
			(island_removal_mode 1)
			(island_area_min 10)
		)
		(polygon
			(pts
				(xy 108.393 162.9475) (xy 108.333588 162.927727) (xy 108.277503 162.864453) (xy 108.255801 162.815828)
				(xy 108.241127 162.756468) (xy 108.239347 162.7445) (xy 107.979 163.01) (xy 108.239347 163.2755)
				(xy 108.252197 163.215361) (xy 108.272131 163.165477) (xy 108.298056 163.125358) (xy 108.327876 163.096345)
				(xy 108.359294 163.078854) (xy 108.391105 163.072521) (xy 108.393 163.0725)
			)
		)
	)
	(zone
		(net 45)
		(net_name "/2xUSB3.0+RJ45/USBSS_2.TX+")
		(layer "B.Cu")
		(name "$teardrop_padvia$")
		(hatch none 0.1)
		(priority 30019)
		(attr
			(teardrop
				(type padvia)
			)
		)
		(connect_pads yes
			(clearance 0)
		)
		(min_thickness 0.0254)
		(filled_areas_thickness no)
		(fill yes
			(thermal_gap 0.5)
			(thermal_bridge_width 0.5)
			(island_removal_mode 1)
			(island_area_min 10)
		)
		(polygon
			(pts
				(xy 112.316517 102.0825) (xy 112.246209 102.077619) (xy 112.190294 102.063448) (xy 112.151456 102.043584)
				(xy 112.121897 102.017417) (xy 112.086642 101.948385) (xy 112.076468 101.843328) (xy 112.098156 101.64456)
				(xy 112.122309 101.439651) (xy 112.123809 101.335496) (xy 112.11203 101.233314) (xy 111.449 101.365)
				(xy 111.318314 102.02703) (xy 111.560039 102.091504) (xy 111.712521 102.14928) (xy 111.829891 102.194394)
				(xy 111.957688 102.232072) (xy 112.1139 102.257909) (xy 112.316517 102.2675)
			)
		)
	)
	(zone
		(net 867)
		(net_name "/Backplane/PCIe_{x2}.TX0-")
		(layer "B.Cu")
		(name "$teardrop_padvia$")
		(hatch none 0.1)
		(priority 30936)
		(attr
			(teardrop
				(type padvia)
			)
		)
		(connect_pads yes
			(clearance 0)
		)
		(min_thickness 0.0254)
		(filled_areas_thickness no)
		(fill yes
			(thermal_gap 0.5)
			(thermal_bridge_width 0.5)
			(island_removal_mode 1)
			(island_area_min 10)
		)
		(polygon
			(pts
				(xy 314.04 160.4555) (xy 314.053941 160.450168) (xy 314.078365 160.443442) (xy 314.087289 160.452549)
				(xy 314.090953 160.477292) (xy 314.366 160.41) (xy 314.302083 160.285) (xy 314.219652 160.294335)
				(xy 314.119272 160.271146) (xy 314.04 160.2535)
			)
		)
	)
	(zone
		(net 1)
		(net_name "GND")
		(layer "B.Cu")
		(name "$teardrop_padvia$")
		(hatch none 0.1)
		(priority 30139)
		(attr
			(teardrop
				(type padvia)
			)
		)
		(connect_pads yes
			(clearance 0)
		)
		(min_thickness 0.0254)
		(filled_areas_thickness no)
		(fill yes
			(thermal_gap 0.5)
			(thermal_bridge_width 0.5)
			(island_removal_mode 1)
			(island_area_min 10)
		)
		(polygon
			(pts
				(xy 140.978698 137.755829) (xy 140.991958 137.768945) (xy 141.042378 137.821413) (xy 141.089857 137.888127)
				(xy 141.121646 137.973687) (xy 141.125 138.08269) (xy 141.420707 138.010707) (xy 141.484917 137.69)
				(xy 141.432052 137.692454) (xy 141.385344 137.685707) (xy 141.302275 137.648098) (xy 141.213513 137.567404)
				(xy 141.190829 137.543698)
			)
		)
	)
	(zone
		(net 677)
		(net_name "Net-(U45C-PRTAD1)")
		(layer "B.Cu")
		(name "$teardrop_padvia$")
		(hatch none 0.1)
		(priority 30774)
		(attr
			(teardrop
				(type padvia)
			)
		)
		(connect_pads yes
			(clearance 0)
		)
		(min_thickness 0.0254)
		(filled_areas_thickness no)
		(fill yes
			(thermal_gap 0.5)
			(thermal_bridge_width 0.5)
			(island_removal_mode 1)
			(island_area_min 10)
		)
		(polygon
			(pts
				(xy 132.050873 140.187515) (xy 132.103382 140.141819) (xy 132.149376 140.115231) (xy 132.235824 140.094847)
				(xy 132.25116 140.093011) (xy 132.333895 140.080677) (xy 132.290707 139.859293) (xy 132.069323 139.816105)
				(xy 132.056988 139.898841) (xy 132.036651 139.996119) (xy 132.009943 140.044159) (xy 131.962485 140.099127)
			)
		)
	)
	(zone
		(net 78)
		(net_name "+1V8")
		(layer "B.Cu")
		(name "$teardrop_padvia$")
		(hatch none 0.1)
		(priority 30453)
		(attr
			(teardrop
				(type padvia)
			)
		)
		(connect_pads yes
			(clearance 0)
		)
		(min_thickness 0.0254)
		(filled_areas_thickness no)
		(fill yes
			(thermal_gap 0.5)
			(thermal_bridge_width 0.5)
			(island_removal_mode 1)
			(island_area_min 10)
		)
		(polygon
			(pts
				(xy 129.807 133.9325) (xy 129.866412 133.952273) (xy 129.922497 134.015547) (xy 129.944199 134.064172)
				(xy 129.958873 134.123531) (xy 129.960653 134.1355) (xy 130.221 133.87) (xy 129.960653 133.6045)
				(xy 129.947804 133.664638) (xy 129.92787 133.714522) (xy 129.901945 133.754641) (xy 129.872125 133.783654)
				(xy 129.840707 133.801146) (xy 129.808896 133.807479) (xy 129.807 133.8075)
			)
		)
	)
	(zone
		(net 200)
		(net_name "/OCuLink/~{PERST_D0}")
		(layer "B.Cu")
		(name "$teardrop_padvia$")
		(hatch none 0.1)
		(priority 31034)
		(attr
			(teardrop
				(type padvia)
			)
		)
		(connect_pads yes
			(clearance 0)
		)
		(min_thickness 0.0254)
		(filled_areas_thickness no)
		(fill yes
			(thermal_gap 0.5)
			(thermal_bridge_width 0.5)
			(island_removal_mode 1)
			(island_area_min 10)
		)
		(polygon
			(pts
				(xy 104.827002 162.1745) (xy 104.833324 162.174404) (xy 104.872827 162.179989) (xy 104.891049 162.194922)
				(xy 104.903997 162.2245) (xy 105.153002 162.112) (xy 104.903997 161.9995) (xy 104.892881 162.026493)
				(xy 104.877354 162.041595) (xy 104.833324 162.049596) (xy 104.827002 162.0495)
			)
		)
	)
	(zone
		(net 652)
		(net_name "/2xSFP+/KR to SFI #1/PRBSEN")
		(layer "B.Cu")
		(name "$teardrop_padvia$")
		(hatch none 0.1)
		(priority 30440)
		(attr
			(teardrop
				(type padvia)
			)
		)
		(connect_pads yes
			(clearance 0)
		)
		(min_thickness 0.0254)
		(filled_areas_thickness no)
		(fill yes
			(thermal_gap 0.5)
			(thermal_bridge_width 0.5)
			(island_removal_mode 1)
			(island_area_min 10)
		)
		(polygon
			(pts
				(xy 157.007 140.4225) (xy 157.066412 140.442273) (xy 157.122497 140.505547) (xy 157.144199 140.554172)
				(xy 157.158873 140.613531) (xy 157.160653 140.6255) (xy 157.421 140.36) (xy 157.160653 140.0945)
				(xy 157.147804 140.154638) (xy 157.12787 140.204522) (xy 157.101945 140.244641) (xy 157.072125 140.273654)
				(xy 157.040707 140.291146) (xy 157.008896 140.297479) (xy 157.007 140.2975)
			)
		)
	)
	(zone
		(net 439)
		(net_name "Net-(J12L-RAPID_SHUTDOWN)")
		(layer "B.Cu")
		(name "$teardrop_padvia$")
		(hatch none 0.1)
		(priority 30118)
		(attr
			(teardrop
				(type padvia)
			)
		)
		(connect_pads yes
			(clearance 0)
		)
		(min_thickness 0.0254)
		(filled_areas_thickness no)
		(fill yes
			(thermal_gap 0.5)
			(thermal_bridge_width 0.5)
			(island_removal_mode 1)
			(island_area_min 10)
		)
		(polygon
			(pts
				(xy 208.9125 156.617794) (xy 208.9174 156.520569) (xy 208.9317 156.445243) (xy 208.97903 156.34177)
				(xy 209.034731 156.264701) (xy 209.111801 156.158339) (xy 208.8 155.949) (xy 208.488199 156.158339)
				(xy 208.576512 156.262316) (xy 208.636298 156.314929) (xy 208.695237 156.367425) (xy 208.743289 156.427155)
				(xy 208.775646 156.506489) (xy 208.7875 156.617794)
			)
		)
	)
	(zone
		(net 576)
		(net_name "Net-(U19-MODE)")
		(layer "B.Cu")
		(name "$teardrop_padvia$")
		(hatch none 0.1)
		(priority 30642)
		(attr
			(teardrop
				(type padvia)
			)
		)
		(connect_pads yes
			(clearance 0)
		)
		(min_thickness 0.0254)
		(filled_areas_thickness no)
		(fill yes
			(thermal_gap 0.5)
			(thermal_bridge_width 0.5)
			(island_removal_mode 1)
			(island_area_min 10)
		)
		(polygon
			(pts
				(xy 309.575872 105.967515) (xy 309.624602 105.92553) (xy 309.668036 105.901031) (xy 309.749841 105.883767)
				(xy 309.771285 105.882237) (xy 309.868894 105.870677) (xy 309.825706 105.649293) (xy 309.622737 105.561645)
				(xy 309.589771 105.671457) (xy 309.586976 105.685947) (xy 309.561758 105.77701) (xy 309.533988 105.825109)
				(xy 309.487484 105.879127)
			)
		)
	)
	(zone
		(net 677)
		(net_name "Net-(U45C-PRTAD1)")
		(layer "B.Cu")
		(name "$teardrop_padvia$")
		(hatch none 0.1)
		(priority 30362)
		(attr
			(teardrop
				(type padvia)
			)
		)
		(connect_pads yes
			(clearance 0)
		)
		(min_thickness 0.0254)
		(filled_areas_thickness no)
		(fill yes
			(thermal_gap 0.5)
			(thermal_bridge_width 0.5)
			(island_removal_mode 1)
			(island_area_min 10)
		)
		(polygon
			(pts
				(xy 126.6325 137.498) (xy 126.652469 137.435134) (xy 126.678921 137.403156) (xy 126.716332 137.374642)
				(xy 126.763527 137.352118) (xy 126.821167 137.336907) (xy 126.821798 137.336798) (xy 126.57 137.059)
				(xy 126.318202 137.336798) (xy 126.373635 137.351095) (xy 126.41952 137.372175) (xy 126.457201 137.39954)
				(xy 126.484434 137.430448) (xy 126.501472 137.463735) (xy 126.507489 137.496566) (xy 126.5075 137.498)
			)
		)
	)
	(zone
		(net 2)
		(net_name "+3V3")
		(layer "B.Cu")
		(name "$teardrop_padvia$")
		(hatch none 0.1)
		(priority 30804)
		(attr
			(teardrop
				(type padvia)
			)
		)
		(connect_pads yes
			(clearance 0)
		)
		(min_thickness 0.0254)
		(filled_areas_thickness no)
		(fill yes
			(thermal_gap 0.5)
			(thermal_bridge_width 0.5)
			(island_removal_mode 1)
			(island_area_min 10)
		)
		(polygon
			(pts
				(xy 190.001293 136.507375) (xy 189.955906 136.455182) (xy 189.929484 136.409401) (xy 189.909335 136.323343)
				(xy 189.9075 136.307577) (xy 189.895162 136.223645) (xy 189.673778 136.266833) (xy 189.63059 136.488217)
				(xy 189.712102 136.500538) (xy 189.809689 136.521243) (xy 189.857796 136.548115) (xy 189.912905 136.595763)
			)
		)
	)
	(zone
		(net 193)
		(net_name "/OCuLink/PCIe_{REF0}.CK-")
		(layer "B.Cu")
		(name "$teardrop_padvia$")
		(hatch none 0.1)
		(priority 30506)
		(attr
			(teardrop
				(type padvia)
			)
		)
		(connect_pads yes
			(clearance 0)
		)
		(min_thickness 0.0254)
		(filled_areas_thickness no)
		(fill yes
			(thermal_gap 0.5)
			(thermal_bridge_width 0.5)
			(island_removal_mode 1)
			(island_area_min 10)
		)
		(polygon
			(pts
				(xy 151.292496 113.4795) (xy 151.24571 113.474765) (xy 151.210258 113.461621) (xy 151.16206 113.416613)
				(xy 151.137884 113.378392) (xy 151.110514 113.335225) (xy 151.073852 113.293268) (xy 150.924 113.4565)
				(xy 150.94486 113.677177) (xy 151.045531 113.672548) (xy 151.128897 113.67598) (xy 151.130964 113.676105)
				(xy 151.292496 113.6815)
			)
		)
	)
	(zone
		(net 678)
		(net_name "Net-(U45A-~{PDTRXA})")
		(layer "B.Cu")
		(name "$teardrop_padvia$")
		(hatch none 0.1)
		(priority 30444)
		(attr
			(teardrop
				(type padvia)
			)
		)
		(connect_pads yes
			(clearance 0)
		)
		(min_thickness 0.0254)
		(filled_areas_thickness no)
		(fill yes
			(thermal_gap 0.5)
			(thermal_bridge_width 0.5)
			(island_removal_mode 1)
			(island_area_min 10)
		)
		(polygon
			(pts
				(xy 138.847 139.4225) (xy 138.906412 139.442273) (xy 138.962497 139.505547) (xy 138.984199 139.554172)
				(xy 138.998873 139.613531) (xy 139.000653 139.6255) (xy 139.261 139.36) (xy 139.000653 139.0945)
				(xy 138.987804 139.154638) (xy 138.96787 139.204522) (xy 138.941945 139.244641) (xy 138.912125 139.273654)
				(xy 138.880707 139.291146) (xy 138.848896 139.297479) (xy 138.847 139.2975)
			)
		)
	)
	(zone
		(net 389)
		(net_name "Net-(J12D-~{BIOS_DIS1})")
		(layer "B.Cu")
		(name "$teardrop_padvia$")
		(hatch none 0.1)
		(priority 30313)
		(attr
			(teardrop
				(type padvia)
			)
		)
		(connect_pads yes
			(clearance 0)
		)
		(min_thickness 0.0254)
		(filled_areas_thickness no)
		(fill yes
			(thermal_gap 0.5)
			(thermal_bridge_width 0.5)
			(island_removal_mode 1)
			(island_area_min 10)
		)
		(polygon
			(pts
				(xy 219.4 164.807) (xy 219.394228 164.847737) (xy 219.373824 164.889652) (xy 219.346649 164.917953)
				(xy 219.307103 164.941381) (xy 219.2345 164.960652) (xy 219.5 165.221) (xy 219.7655 164.960652)
				(xy 219.712358 164.948785) (xy 219.671319 164.930338) (xy 219.619618 164.879664) (xy 219.600282 164.816095)
				(xy 219.6 164.807)
			)
		)
	)
	(zone
		(net 198)
		(net_name "/OCuLink/SCL")
		(layer "B.Cu")
		(name "$teardrop_padvia$")
		(hatch none 0.1)
		(priority 30443)
		(attr
			(teardrop
				(type padvia)
			)
		)
		(connect_pads yes
			(clearance 0)
		)
		(min_thickness 0.0254)
		(filled_areas_thickness no)
		(fill yes
			(thermal_gap 0.5)
			(thermal_bridge_width 0.5)
			(island_removal_mode 1)
			(island_area_min 10)
		)
		(polygon
			(pts
				(xy 106.607 163.0725) (xy 106.666412 163.092273) (xy 106.722497 163.155547) (xy 106.744199 163.204172)
				(xy 106.758873 163.263531) (xy 106.760653 163.2755) (xy 107.021 163.01) (xy 106.760653 162.7445)
				(xy 106.747804 162.804638) (xy 106.72787 162.854522) (xy 106.701945 162.894641) (xy 106.672125 162.923654)
				(xy 106.640707 162.941146) (xy 106.608896 162.947479) (xy 106.607 162.9475)
			)
		)
	)
	(zone
		(net 171)
		(net_name "/2xSFP+/SFI0.RX+")
		(layer "B.Cu")
		(name "$teardrop_padvia$")
		(hatch none 0.1)
		(priority 30064)
		(attr
			(teardrop
				(type padvia)
			)
		)
		(connect_pads yes
			(clearance 0)
		)
		(min_thickness 0.0254)
		(filled_areas_thickness no)
		(fill yes
			(thermal_gap 0.5)
			(thermal_bridge_width 0.5)
			(island_removal_mode 1)
			(island_area_min 10)
		)
		(polygon
			(pts
				(xy 148.445738 164.03) (xy 148.355634 164.025169) (xy 148.282949 164.011353) (xy 148.178432 163.964302)
				(xy 148.075448 163.879395) (xy 148.006386 163.818142) (xy 147.918895 163.752468) (xy 147.679 164.11)
				(xy 147.918895 164.467532) (xy 148.052617 164.361451) (xy 148.075447 164.340605) (xy 148.144427 164.2803)
				(xy 148.218963 164.232615) (xy 148.314314 164.201274) (xy 148.445738 164.19)
			)
		)
	)
	(zone
		(net 247)
		(net_name "/Com Express 7 Interfaces/PCIe_{B2Bx4}.TX2-")
		(layer "B.Cu")
		(name "$teardrop_padvia$")
		(hatch none 0.1)
		(priority 30310)
		(attr
			(teardrop
				(type padvia)
			)
		)
		(connect_pads yes
			(clearance 0)
		)
		(min_thickness 0.0254)
		(filled_areas_thickness no)
		(fill yes
			(thermal_gap 0.5)
			(thermal_bridge_width 0.5)
			(island_removal_mode 1)
			(island_area_min 10)
		)
		(polygon
			(pts
				(xy 175.39 98.961) (xy 175.404678 98.957463) (xy 175.434685 98.954192) (xy 175.445673 98.966143)
				(xy 175.45 98.995) (xy 176.201 98.86) (xy 175.45 98.725) (xy 175.445525 98.754204) (xy 175.434203 98.765997)
				(xy 175.404678 98.762537) (xy 175.39 98.759)
			)
		)
	)
	(zone
		(net 97)
		(net_name "/OCuLink/PCIe_{x4}.TX2-")
		(layer "B.Cu")
		(name "$teardrop_padvia$")
		(hatch none 0.1)
		(priority 30977)
		(attr
			(teardrop
				(type padvia)
			)
		)
		(connect_pads yes
			(clearance 0)
		)
		(min_thickness 0.0254)
		(filled_areas_thickness no)
		(fill yes
			(thermal_gap 0.5)
			(thermal_bridge_width 0.5)
			(island_removal_mode 1)
			(island_area_min 10)
		)
		(polygon
			(pts
				(xy 104.058 160.211) (xy 104.078648 160.203802) (xy 104.110984 160.194208) (xy 104.125007 160.201035)
				(xy 104.134995 160.2225) (xy 104.384 160.11) (xy 104.134995 159.9975) (xy 104.125271 160.018676)
				(xy 104.111643 160.025731) (xy 104.078648 160.016198) (xy 104.058 160.009)
			)
		)
	)
	(zone
		(net 182)
		(net_name "Net-(J3-CC_{2})")
		(layer "B.Cu")
		(name "$teardrop_padvia$")
		(hatch none 0.1)
		(priority 30290)
		(attr
			(teardrop
				(type padvia)
			)
		)
		(connect_pads yes
			(clearance 0)
		)
		(min_thickness 0.0254)
		(filled_areas_thickness no)
		(fill yes
			(thermal_gap 0.5)
			(thermal_bridge_width 0.5)
			(island_removal_mode 1)
			(island_area_min 10)
		)
		(polygon
			(pts
				(xy 100.48 84.022) (xy 100.47379 84.068211) (xy 100.450323 84.11661) (xy 100.422416 84.144966) (xy 100.38219 84.168012)
				(xy 100.328202 84.183202) (xy 100.58 84.461) (xy 100.831798 84.183202) (xy 100.782946 84.170069)
				(xy 100.745436 84.150665) (xy 100.698013 84.098055) (xy 100.680257 84.031554) (xy 100.68 84.022)
			)
		)
	)
	(zone
		(net 1)
		(net_name "GND")
		(layer "B.Cu")
		(name "$teardrop_padvia$")
		(hatch none 0.1)
		(priority 30859)
		(attr
			(teardrop
				(type padvia)
			)
		)
		(connect_pads yes
			(clearance 0)
		)
		(min_thickness 0.0254)
		(filled_areas_thickness no)
		(fill yes
			(thermal_gap 0.5)
			(thermal_bridge_width 0.5)
			(island_removal_mode 1)
			(island_area_min 10)
		)
		(polygon
			(pts
				(xy 314.72 160.81) (xy 314.709885 160.810153) (xy 314.679169 160.80954) (xy 314.64668 160.801218)
				(xy 314.617526 160.777325) (xy 314.596809 160.73) (xy 314.364 160.91) (xy 314.596809 161.09) (xy 314.610168 161.054099)
				(xy 314.628399 161.030801) (xy 314.673725 161.011101) (xy 314.709885 161.009847) (xy 314.72 161.01)
			)
		)
	)
	(zone
		(net 631)
		(net_name "Net-(U39-RXDET)")
		(layer "B.Cu")
		(name "$teardrop_padvia$")
		(hatch none 0.1)
		(priority 30606)
		(attr
			(teardrop
				(type padvia)
			)
		)
		(connect_pads yes
			(clearance 0)
		)
		(min_thickness 0.0254)
		(filled_areas_thickness no)
		(fill yes
			(thermal_gap 0.5)
			(thermal_bridge_width 0.5)
			(island_removal_mode 1)
			(island_area_min 10)
		)
		(polygon
			(pts
				(xy 121.175401 149.973788) (xy 121.175887 149.993475) (xy 121.165222 150.010352) (xy 121.109801 150.035225)
				(xy 121.021054 150.046228) (xy 121.250707 150.330707) (xy 121.495813 150.057498) (xy 121.40024 150.030924)
				(xy 121.318001 149.971994) (xy 121.286379 149.932893) (xy 121.26649 149.893747) (xy 121.263788 149.885401)
			)
		)
	)
	(zone
		(net 93)
		(net_name "/Com Express 7 Interfaces/PCIe_{B2Ax4}.RX3+")
		(layer "B.Cu")
		(name "$teardrop_padvia$")
		(hatch none 0.1)
		(priority 30531)
		(attr
			(teardrop
				(type padvia)
			)
		)
		(connect_pads yes
			(clearance 0)
		)
		(min_thickness 0.0254)
		(filled_areas_thickness no)
		(fill yes
			(thermal_gap 0.5)
			(thermal_bridge_width 0.5)
			(island_removal_mode 1)
			(island_area_min 10)
		)
		(polygon
			(pts
				(xy 216.1815 165.067496) (xy 216.176105 164.905964) (xy 216.172555 164.821553) (xy 216.177177 164.719859)
				(xy 215.9565 164.699) (xy 215.793268 164.848852) (xy 215.861936 164.902992) (xy 215.878392 164.912884)
				(xy 215.917064 164.937384) (xy 215.949279 164.96689) (xy 215.971327 165.008046) (xy 215.9795 165.067496)
			)
		)
	)
	(zone
		(net 84)
		(net_name "/Com Express 7 MGMT/PWRBTN")
		(layer "B.Cu")
		(name "$teardrop_padvia$")
		(hatch none 0.1)
		(priority 30708)
		(attr
			(teardrop
				(type padvia)
			)
		)
		(connect_pads yes
			(clearance 0)
		)
		(min_thickness 0.0254)
		(filled_areas_thickness no)
		(fill yes
			(thermal_gap 0.5)
			(thermal_bridge_width 0.5)
			(island_removal_mode 1)
			(island_area_min 10)
		)
		(polygon
			(pts
				(xy 181.349323 84.9625) (xy 181.418764 84.967318) (xy 181.470088 84.98104) (xy 181.545629 85.027755)
				(xy 181.557769 85.037299) (xy 181.624997 85.087081) (xy 181.751 84.9) (xy 181.624997 84.712919)
				(xy 181.557768 84.762702) (xy 181.474602 84.817106) (xy 181.421748 84.83219) (xy 181.349323 84.8375)
			)
		)
	)
	(zone
		(net 1)
		(net_name "GND")
		(layer "B.Cu")
		(name "$teardrop_padvia$")
		(hatch none 0.1)
		(priority 30873)
		(attr
			(teardrop
				(type padvia)
			)
		)
		(connect_pads yes
			(clearance 0)
		)
		(min_thickness 0.0254)
		(filled_areas_thickness no)
		(fill yes
			(thermal_gap 0.5)
			(thermal_bridge_width 0.5)
			(island_removal_mode 1)
			(island_area_min 10)
		)
		(polygon
			(pts
				(xy 104.738 159.5475) (xy 104.704137 159.541719) (xy 104.669515 159.521254) (xy 104.647693 159.494188)
				(xy 104.632 159.454848) (xy 104.628711 159.439289) (xy 104.382 159.61) (xy 104.628711 159.780711)
				(xy 104.640301 159.74049) (xy 104.657885 159.711016) (xy 104.705468 159.677827) (xy 104.738 159.6725)
			)
		)
	)
	(zone
		(net 86)
		(net_name "/Com Express 7 Interfaces/PCIe_{B2Ax4}.RX0-")
		(layer "B.Cu")
		(name "$teardrop_padvia$")
		(hatch none 0.1)
		(priority 30607)
		(attr
			(teardrop
				(type padvia)
			)
		)
		(connect_pads yes
			(clearance 0)
		)
		(min_thickness 0.0254)
		(filled_areas_thickness no)
		(fill yes
			(thermal_gap 0.5)
			(thermal_bridge_width 0.5)
			(island_removal_mode 1)
			(island_area_min 10)
		)
		(polygon
			(pts
				(xy 211.741709 165.023807) (xy 211.721162 164.996557) (xy 211.714586 164.971345) (xy 211.730177 164.926307)
				(xy 211.75786 164.890355) (xy 211.789994 164.848371) (xy 211.811663 164.799962) (xy 211.592793 164.749293)
				(xy 211.415462 164.884046) (xy 211.482483 164.999043) (xy 211.523189 165.07515) (xy 211.598873 165.166643)
			)
		)
	)
	(zone
		(net 215)
		(net_name "/Com Express 7 Interfaces/PCIe_{B1x4}.TX2-")
		(layer "B.Cu")
		(name "$teardrop_padvia$")
		(hatch none 0.1)
		(priority 30833)
		(attr
			(teardrop
				(type padvia)
			)
		)
		(connect_pads yes
			(clearance 0)
		)
		(min_thickness 0.0254)
		(filled_areas_thickness no)
		(fill yes
			(thermal_gap 0.5)
			(thermal_bridge_width 0.5)
			(island_removal_mode 1)
			(island_area_min 10)
		)
		(polygon
			(pts
				(xy 116.3555 145.1855) (xy 116.361457 145.19966) (xy 116.36931 145.223595) (xy 116.361086 145.232257)
				(xy 116.337574 145.235684) (xy 116.401 145.674) (xy 116.526 145.570348) (xy 116.51672 145.443171)
				(xy 116.54007 145.297903) (xy 116.5575 145.1855)
			)
		)
	)
	(zone
		(net 945)
		(net_name "/GPIO expander/GPIOEX5")
		(layer "B.Cu")
		(name "$teardrop_padvia$")
		(hatch none 0.1)
		(priority 30622)
		(attr
			(teardrop
				(type padvia)
			)
		)
		(connect_pads yes
			(clearance 0)
		)
		(min_thickness 0.0254)
		(filled_areas_thickness no)
		(fill yes
			(thermal_gap 0.5)
			(thermal_bridge_width 0.5)
			(island_removal_mode 1)
			(island_area_min 10)
		)
		(polygon
			(pts
				(xy 122.168835 147.6715) (xy 122.217981 147.676243) (xy 122.255152 147.689448) (xy 122.305037 147.734282)
				(xy 122.331258 147.774777) (xy 122.364885 147.825888) (xy 122.413285 147.875369) (xy 122.551 147.7)
				(xy 122.503306 147.480482) (xy 122.387151 147.512307) (xy 122.297454 147.536536) (xy 122.168835 147.5465)
			)
		)
	)
	(zone
		(net 718)
		(net_name "Net-(U40-I2C_{DONE})")
		(layer "B.Cu")
		(name "$teardrop_padvia$")
		(hatch none 0.1)
		(priority 30781)
		(attr
			(teardrop
				(type padvia)
			)
		)
		(connect_pads yes
			(clearance 0)
		)
		(min_thickness 0.0254)
		(filled_areas_thickness no)
		(fill yes
			(thermal_gap 0.5)
			(thermal_bridge_width 0.5)
			(island_removal_mode 1)
			(island_area_min 10)
		)
		(polygon
			(pts
				(xy 198.177515 133.939127) (xy 198.131819 133.886618) (xy 198.105231 133.840623) (xy 198.084847 133.754175)
				(xy 198.083011 133.73884) (xy 198.070677 133.656105) (xy 197.849293 133.699293) (xy 197.806105 133.920677)
				(xy 197.88884 133.933011) (xy 197.986119 133.953349) (xy 198.034159 133.980057) (xy 198.089127 134.027515)
			)
		)
	)
	(zone
		(net 53)
		(net_name "/2xSFP+/SH")
		(layer "B.Cu")
		(name "$teardrop_padvia$")
		(hatch none 0.1)
		(priority 30237)
		(attr
			(teardrop
				(type padvia)
			)
		)
		(connect_pads yes
			(clearance 0)
		)
		(min_thickness 0.0254)
		(filled_areas_thickness no)
		(fill yes
			(thermal_gap 0.5)
			(thermal_bridge_width 0.5)
			(island_removal_mode 1)
			(island_area_min 10)
		)
		(polygon
			(pts
				(xy 152.1 159.337) (xy 152.100337 159.35209) (xy 152.09976 159.392326) (xy 152.087946 159.43387)
				(xy 152.053367 159.469164) (xy 151.9845 159.490652) (xy 152.25 159.751) (xy 152.5155 159.490652)
				(xy 152.469062 159.479708) (xy 152.436865 159.462609) (xy 152.405422 159.418144) (xy 152.399663 159.35209)
				(xy 152.4 159.337)
			)
		)
	)
	(zone
		(net 54)
		(net_name "/USB-C console/SH")
		(layer "B.Cu")
		(name "$teardrop_padvia$")
		(hatch none 0.1)
		(priority 30030)
		(attr
			(teardrop
				(type padvia)
			)
		)
		(connect_pads yes
			(clearance 0)
		)
		(min_thickness 0.0254)
		(filled_areas_thickness no)
		(fill yes
			(thermal_gap 0.5)
			(thermal_bridge_width 0.5)
			(island_removal_mode 1)
			(island_area_min 10)
		)
		(polygon
			(pts
				(xy 99.540393 81.697) (xy 99.503764 81.697387) (xy 99.39464 81.695835) (xy 99.274824 81.674997)
				(xy 99.214184 81.651215) (xy 99.154802 81.615257) (xy 99.097992 81.564669) (xy 99.045062 81.497)
				(xy 98.324 81.947) (xy 99.045062 82.397) (xy 99.087864 82.340494) (xy 99.133404 82.295633) (xy 99.234131 82.233706)
				(xy 99.35071 82.202622) (xy 99.503764 82.196613) (xy 99.540393 82.197)
			)
		)
	)
	(zone
		(net 47)
		(net_name "/2xUSB3.0+RJ45/USBSS_1.TX-")
		(layer "B.Cu")
		(name "$teardrop_padvia$")
		(hatch none 0.1)
		(priority 30961)
		(attr
			(teardrop
				(type padvia)
			)
		)
		(connect_pads yes
			(clearance 0)
		)
		(min_thickness 0.0254)
		(filled_areas_thickness no)
		(fill yes
			(thermal_gap 0.5)
			(thermal_bridge_width 0.5)
			(island_removal_mode 1)
			(island_area_min 10)
		)
		(polygon
			(pts
				(xy 101 104.9025) (xy 101.012655 104.89915) (xy 101.037765 104.896051) (xy 101.046968 104.906877)
				(xy 101.05071 104.933073) (xy 101.326 104.867) (xy 101.264271 104.742) (xy 101.177415 104.752063)
				(xy 101.077915 104.732419) (xy 101 104.7175)
			)
		)
	)
	(zone
		(net 97)
		(net_name "/OCuLink/PCIe_{x4}.TX2-")
		(layer "B.Cu")
		(name "$teardrop_padvia$")
		(hatch none 0.1)
		(priority 31012)
		(attr
			(teardrop
				(type padvia)
			)
		)
		(connect_pads yes
			(clearance 0)
		)
		(min_thickness 0.0254)
		(filled_areas_thickness no)
		(fill yes
			(thermal_gap 0.5)
			(thermal_bridge_width 0.5)
			(island_removal_mode 1)
			(island_area_min 10)
		)
		(polygon
			(pts
				(xy 105.48 160.009) (xy 105.459352 160.016199) (xy 105.427017 160.025792) (xy 105.412994 160.018965)
				(xy 105.403005 159.9975) (xy 105.154 160.11) (xy 105.403005 160.2225) (xy 105.41273 160.201324)
				(xy 105.426358 160.194269) (xy 105.459352 160.203801) (xy 105.48 160.211)
			)
		)
	)
	(zone
		(net 314)
		(net_name "/2xUSB3.0+RJ45/FLG_1")
		(layer "B.Cu")
		(name "$teardrop_padvia$")
		(hatch none 0.1)
		(priority 30758)
		(attr
			(teardrop
				(type padvia)
			)
		)
		(connect_pads yes
			(clearance 0)
		)
		(min_thickness 0.0254)
		(filled_areas_thickness no)
		(fill yes
			(thermal_gap 0.5)
			(thermal_bridge_width 0.5)
			(island_removal_mode 1)
			(island_area_min 10)
		)
		(polygon
			(pts
				(xy 122.202485 92.720873) (xy 122.248181 92.773382) (xy 122.274768 92.819376) (xy 122.295152 92.905825)
				(xy 122.296988 92.921158) (xy 122.309323 93.003895) (xy 122.530707 92.960707) (xy 122.573895 92.739323)
				(xy 122.491158 92.726988) (xy 122.39388 92.706651) (xy 122.34584 92.679943) (xy 122.290873 92.632485)
			)
		)
	)
	(zone
		(net 59)
		(net_name "/OCuLink/V_{ACT_TX}0")
		(layer "B.Cu")
		(name "$teardrop_padvia$")
		(hatch none 0.1)
		(priority 30203)
		(attr
			(teardrop
				(type padvia)
			)
		)
		(connect_pads yes
			(clearance 0)
		)
		(min_thickness 0.0254)
		(filled_areas_thickness no)
		(fill yes
			(thermal_gap 0.5)
			(thermal_bridge_width 0.5)
			(island_removal_mode 1)
			(island_area_min 10)
		)
		(polygon
			(pts
				(xy 104.11 156.098) (xy 104.109662 156.08113) (xy 104.110241 156.036174) (xy 104.122059 155.988831)
				(xy 104.156638 155.946427) (xy 104.2255 155.916291) (xy 103.96 155.659) (xy 103.6945 155.916291)
				(xy 103.739269 155.931848) (xy 103.770885 155.952565) (xy 103.803619 156.003701) (xy 103.810338 156.08113)
				(xy 103.81 156.098)
			)
		)
	)
	(zone
		(net 621)
		(net_name "/PCIe misc/DIF5+")
		(layer "B.Cu")
		(name "$teardrop_padvia$")
		(hatch none 0.1)
		(priority 30571)
		(attr
			(teardrop
				(type padvia)
			)
		)
		(connect_pads yes
			(clearance 0)
		)
		(min_thickness 0.0254)
		(filled_areas_thickness no)
		(fill yes
			(thermal_gap 0.5)
			(thermal_bridge_width 0.5)
			(island_removal_mode 1)
			(island_area_min 10)
		)
		(polygon
			(pts
				(xy 220.735562 127.7685) (xy 220.57403 127.773895) (xy 220.48962 127.777445) (xy 220.387926 127.772823)
				(xy 220.367066 127.9935) (xy 220.516918 128.156731) (xy 220.571058 128.088062) (xy 220.580949 128.071608)
				(xy 220.605449 128.032935) (xy 220.634956 128.000721) (xy 220.676112 127.978673) (xy 220.735562 127.9705)
			)
		)
	)
	(zone
		(net 1)
		(net_name "GND")
		(layer "B.Cu")
		(hatch edge 0.5)
		(priority 1)
		(connect_pads
			(clearance 0.15)
		)
		(min_thickness 0.25)
		(filled_areas_thickness no)
		(fill yes
			(thermal_gap 0.2)
			(thermal_bridge_width 0.5)
			(smoothing fillet)
			(radius 0.2)
		)
		(polygon
			(pts
				(xy 152.925 89.81) (xy 152.925 70.81) (xy 148.875 70.81) (xy 148.875 89.81)
			)
		)
	)
	(zone
		(net 64)
		(net_name "Net-(U19-V_{CC})")
		(layer "B.Cu")
		(name "$teardrop_padvia$")
		(hatch none 0.1)
		(priority 30379)
		(attr
			(teardrop
				(type padvia)
			)
		)
		(connect_pads yes
			(clearance 0)
		)
		(min_thickness 0.0254)
		(filled_areas_thickness no)
		(fill yes
			(thermal_gap 0.5)
			(thermal_bridge_width 0.5)
			(island_removal_mode 1)
			(island_area_min 10)
		)
		(polygon
			(pts
				(xy 312.586999 106.6925) (xy 312.649865 106.712469) (xy 312.681843 106.738921) (xy 312.710357 106.776332)
				(xy 312.732881 106.823527) (xy 312.748092 106.881167) (xy 312.748201 106.881798) (xy 313.025999 106.63)
				(xy 312.748201 106.378202) (xy 312.733904 106.433635) (xy 312.712824 106.47952) (xy 312.685459 106.517201)
				(xy 312.654551 106.544434) (xy 312.621264 106.561472) (xy 312.588433 106.567489) (xy 312.586999 106.5675)
			)
		)
	)
	(zone
		(net 539)
		(net_name "/Misc/~{PWR_OK}")
		(layer "B.Cu")
		(name "$teardrop_padvia$")
		(hatch none 0.1)
		(priority 30131)
		(attr
			(teardrop
				(type padvia)
			)
		)
		(connect_pads yes
			(clearance 0)
		)
		(min_thickness 0.0254)
		(filled_areas_thickness no)
		(fill yes
			(thermal_gap 0.5)
			(thermal_bridge_width 0.5)
			(island_removal_mode 1)
			(island_area_min 10)
		)
		(polygon
			(pts
				(xy 98.6385 72.34) (xy 98.618779 72.39726) (xy 98.555967 72.449784) (xy 98.507347 72.46955) (xy 98.448049 72.482076)
				(xy 98.431 72.483927) (xy 98.701 72.961) (xy 98.971 72.483927) (xy 98.909756 72.473751) (xy 98.85883 72.456075)
				(xy 98.817987 72.432177) (xy 98.788303 72.403978) (xy 98.77037 72.373988) (xy 98.76356 72.343138)
				(xy 98.7635 72.34)
			)
		)
	)
	(zone
		(net 219)
		(net_name "/Com Express 7 Interfaces/PCIe_{B1x4}.TX1-")
		(layer "B.Cu")
		(name "$teardrop_padvia$")
		(hatch none 0.1)
		(priority 30542)
		(attr
			(teardrop
				(type padvia)
			)
		)
		(connect_pads yes
			(clearance 0)
		)
		(min_thickness 0.0254)
		(filled_areas_thickness no)
		(fill yes
			(thermal_gap 0.5)
			(thermal_bridge_width 0.5)
			(island_removal_mode 1)
			(island_area_min 10)
		)
		(polygon
			(pts
				(xy 207.174027 165.693744) (xy 207.284432 165.575708) (xy 207.341608 165.51351) (xy 207.416785 165.44487)
				(xy 207.275493 165.274079) (xy 207.054109 165.264618) (xy 207.064381 165.351455) (xy 207.069023 165.370088)
				(xy 207.079045 165.414757) (xy 207.08096 165.4584) (xy 207.067448 165.503092) (xy 207.031191 165.550908)
			)
		)
	)
	(zone
		(net 2)
		(net_name "+3V3")
		(layer "B.Cu")
		(name "$teardrop_padvia$")
		(hatch none 0.1)
		(priority 30806)
		(attr
			(teardrop
				(type padvia)
			)
		)
		(connect_pads yes
			(clearance 0)
		)
		(min_thickness 0.0254)
		(filled_areas_thickness no)
		(fill yes
			(thermal_gap 0.5)
			(thermal_bridge_width 0.5)
			(island_removal_mode 1)
			(island_area_min 10)
		)
		(polygon
			(pts
				(xy 193.182566 133.326101) (xy 193.137179 133.273907) (xy 193.110757 133.228127) (xy 193.090608 133.142068)
				(xy 193.088773 133.126304) (xy 193.076435 133.042372) (xy 192.855051 133.08556) (xy 192.811863 133.306944)
				(xy 192.893376 133.319265) (xy 192.990962 133.339969) (xy 193.039069 133.366842) (xy 193.094178 133.414489)
			)
		)
	)
	(zone
		(net 64)
		(net_name "Net-(U19-V_{CC})")
		(layer "B.Cu")
		(name "$teardrop_padvia$")
		(hatch none 0.1)
		(priority 30336)
		(attr
			(teardrop
				(type padvia)
			)
		)
		(connect_pads yes
			(clearance 0)
		)
		(min_thickness 0.0254)
		(filled_areas_thickness no)
		(fill yes
			(thermal_gap 0.5)
			(thermal_bridge_width 0.5)
			(island_removal_mode 1)
			(island_area_min 10)
		)
		(polygon
			(pts
				(xy 310.836999 106.6925) (xy 310.899865 106.712469) (xy 310.931843 106.738921) (xy 310.960357 106.776332)
				(xy 310.982881 106.823527) (xy 310.998092 106.881167) (xy 310.998201 106.881798) (xy 311.275999 106.63)
				(xy 310.998201 106.378202) (xy 310.983904 106.433635) (xy 310.962824 106.47952) (xy 310.935459 106.517201)
				(xy 310.904551 106.544434) (xy 310.871264 106.561472) (xy 310.838433 106.567489) (xy 310.836999 106.5675)
			)
		)
	)
	(zone
		(net 1)
		(net_name "GND")
		(layer "B.Cu")
		(name "$teardrop_padvia$")
		(hatch none 0.1)
		(priority 30256)
		(attr
			(teardrop
				(type padvia)
			)
		)
		(connect_pads yes
			(clearance 0)
		)
		(min_thickness 0.0254)
		(filled_areas_thickness no)
		(fill yes
			(thermal_gap 0.5)
			(thermal_bridge_width 0.5)
			(island_removal_mode 1)
			(island_area_min 10)
		)
		(polygon
			(pts
				(xy 102.789323 167.26) (xy 102.9469 167.266932) (xy 103.060434 167.295456) (xy 103.102222 167.3125)
				(xy 103.191 167.11) (xy 103.102222 166.9075) (xy 103.006177 166.941883) (xy 102.904296 166.957101)
				(xy 102.789323 166.96)
			)
		)
	)
	(zone
		(net 206)
		(net_name "/Backplane/USB.D+")
		(layer "B.Cu")
		(name "$teardrop_padvia$")
		(hatch none 0.1)
		(priority 31030)
		(attr
			(teardrop
				(type padvia)
			)
		)
		(connect_pads yes
			(clearance 0)
		)
		(min_thickness 0.0254)
		(filled_areas_thickness no)
		(fill yes
			(thermal_gap 0.5)
			(thermal_bridge_width 0.5)
			(island_removal_mode 1)
			(island_area_min 10)
		)
		(polygon
			(pts
				(xy 314.812 166.3025) (xy 314.831383 166.297516) (xy 314.86536 166.291265) (xy 314.880356 166.299516)
				(xy 314.891264 166.322015) (xy 315.138 166.208) (xy 314.886691 166.097039) (xy 314.877158 166.119554)
				(xy 314.863458 166.128188) (xy 314.830314 166.122322) (xy 314.812 166.1175)
			)
		)
	)
	(zone
		(net 2)
		(net_name "+3V3")
		(layer "B.Cu")
		(name "$teardrop_padvia$")
		(hatch none 0.1)
		(priority 30480)
		(attr
			(teardrop
				(type padvia)
			)
		)
		(connect_pads yes
			(clearance 0)
		)
		(min_thickness 0.0254)
		(filled_areas_thickness no)
		(fill yes
			(thermal_gap 0.5)
			(thermal_bridge_width 0.5)
			(island_removal_mode 1)
			(island_area_min 10)
		)
		(polygon
			(pts
				(xy 124.234031 97.07261) (xy 124.182272 97.014186) (xy 124.149889 96.963436) (xy 124.11529 96.869297)
				(xy 124.085257 96.778879) (xy 123.879293 96.859293) (xy 123.798879 97.065257) (xy 123.889297 97.09529)
				(xy 123.985111 97.130762) (xy 124.035114 97.162979) (xy 124.09261 97.214031)
			)
		)
	)
	(zone
		(net 1)
		(net_name "GND")
		(layer "B.Cu")
		(name "$teardrop_padvia$")
		(hatch none 0.1)
		(priority 30866)
		(attr
			(teardrop
				(type padvia)
			)
		)
		(connect_pads yes
			(clearance 0)
		)
		(min_thickness 0.0254)
		(filled_areas_thickness no)
		(fill yes
			(thermal_gap 0.5)
			(thermal_bridge_width 0.5)
			(island_removal_mode 1)
			(island_area_min 10)
		)
		(polygon
			(pts
				(xy 314.782 165.81) (xy 314.792115 165.809847) (xy 314.822832 165.81046) (xy 314.85532 165.818782)
				(xy 314.884475 165.842675) (xy 314.905191 165.89) (xy 315.138 165.71) (xy 314.905191 165.53) (xy 314.891833 165.565901)
				(xy 314.873601 165.589199) (xy 314.828276 165.608899) (xy 314.792115 165.610153) (xy 314.782 165.61)
			)
		)
	)
	(zone
		(net 712)
		(net_name "Net-(U39-SDA)")
		(layer "B.Cu")
		(name "$teardrop_padvia$")
		(hatch none 0.1)
		(priority 30922)
		(attr
			(teardrop
				(type padvia)
			)
		)
		(connect_pads yes
			(clearance 0)
		)
		(min_thickness 0.0254)
		(filled_areas_thickness no)
		(fill yes
			(thermal_gap 0.5)
			(thermal_bridge_width 0.5)
			(island_removal_mode 1)
			(island_area_min 10)
		)
		(polygon
			(pts
				(xy 122.3255 146.5475) (xy 122.319037 146.547599) (xy 122.279094 146.54205) (xy 122.260572 146.527161)
				(xy 122.247247 146.497659) (xy 121.837 146.611) (xy 122.249768 146.722655) (xy 122.26059 146.695524)
				(xy 122.275907 146.68038) (xy 122.319317 146.672407) (xy 122.3255 146.6725)
			)
		)
	)
	(zone
		(net 576)
		(net_name "Net-(U19-MODE)")
		(layer "B.Cu")
		(name "$teardrop_padvia$")
		(hatch none 0.1)
		(priority 30216)
		(attr
			(teardrop
				(type padvia)
			)
		)
		(connect_pads yes
			(clearance 0)
		)
		(min_thickness 0.0254)
		(filled_areas_thickness no)
		(fill yes
			(thermal_gap 0.5)
			(thermal_bridge_width 0.5)
			(island_removal_mode 1)
			(island_area_min 10)
		)
		(polygon
			(pts
				(xy 309.126055 106.240556) (xy 309.042712 106.295935) (xy 308.912723 106.332154) (xy 308.832133 106.338517)
				(xy 308.744525 106.335) (xy 308.824292 106.630707) (xy 309.144999 106.685474) (xy 309.135981 106.534316)
				(xy 309.145825 106.466785) (xy 309.16409 106.407974) (xy 309.214443 106.328944)
			)
		)
	)
	(zone
		(net 654)
		(net_name "Net-(U43C-GPI0)")
		(layer "B.Cu")
		(name "$teardrop_padvia$")
		(hatch none 0.1)
		(priority 30405)
		(attr
			(teardrop
				(type padvia)
			)
		)
		(connect_pads yes
			(clearance 0)
		)
		(min_thickness 0.0254)
		(filled_areas_thickness no)
		(fill yes
			(thermal_gap 0.5)
			(thermal_bridge_width 0.5)
			(island_removal_mode 1)
			(island_area_min 10)
		)
		(polygon
			(pts
				(xy 145.143 140.9975) (xy 145.083588 140.977727) (xy 145.027503 140.914453) (xy 145.005801 140.865828)
				(xy 144.991127 140.806468) (xy 144.989347 140.7945) (xy 144.729 141.06) (xy 144.989347 141.3255)
				(xy 145.002197 141.265361) (xy 145.022131 141.215477) (xy 145.048056 141.175358) (xy 145.077876 141.146345)
				(xy 145.109294 141.128854) (xy 145.141105 141.122521) (xy 145.143 141.1225)
			)
		)
	)
	(zone
		(net 540)
		(net_name "Net-(Q8-D)")
		(layer "B.Cu")
		(name "$teardrop_padvia$")
		(hatch none 0.1)
		(priority 30458)
		(attr
			(teardrop
				(type padvia)
			)
		)
		(connect_pads yes
			(clearance 0)
		)
		(min_thickness 0.0254)
		(filled_areas_thickness no)
		(fill yes
			(thermal_gap 0.5)
			(thermal_bridge_width 0.5)
			(island_removal_mode 1)
			(island_area_min 10)
		)
		(polygon
			(pts
				(xy 98.407 75.8725) (xy 98.466412 75.892273) (xy 98.522497 75.955547) (xy 98.544199 76.004172) (xy 98.558873 76.063531)
				(xy 98.560653 76.0755) (xy 98.821 75.81) (xy 98.560653 75.5445) (xy 98.547804 75.604638) (xy 98.52787 75.654522)
				(xy 98.501945 75.694641) (xy 98.472125 75.723654) (xy 98.440707 75.741146) (xy 98.408896 75.747479)
				(xy 98.407 75.7475)
			)
		)
	)
	(zone
		(net 375)
		(net_name "/2xUSB3.0+RJ45/USB_2.D+")
		(layer "B.Cu")
		(name "$teardrop_padvia$")
		(hatch none 0.1)
		(priority 30655)
		(attr
			(teardrop
				(type padvia)
			)
		)
		(connect_pads yes
			(clearance 0)
		)
		(min_thickness 0.0254)
		(filled_areas_thickness no)
		(fill yes
			(thermal_gap 0.5)
			(thermal_bridge_width 0.5)
			(island_removal_mode 1)
			(island_area_min 10)
		)
		(polygon
			(pts
				(xy 151.907278 115.1825) (xy 151.934813 115.187247) (xy 151.944876 115.200477) (xy 151.933389 115.237073)
				(xy 151.905568 115.280633) (xy 151.872376 115.332712) (xy 151.851281 115.384147) (xy 152.072958 115.428042)
				(xy 152.196961 115.240961) (xy 152.131651 115.177914) (xy 152.094447 115.119909) (xy 152.065225 115.073447)
				(xy 152.02961 115.034406) (xy 151.979622 115.007515) (xy 151.907278 114.9975)
			)
		)
	)
	(zone
		(net 182)
		(net_name "Net-(J3-CC_{2})")
		(layer "B.Cu")
		(name "$teardrop_padvia$")
		(hatch none 0.1)
		(priority 30469)
		(attr
			(teardrop
				(type padvia)
			)
		)
		(connect_pads yes
			(clearance 0)
		)
		(min_thickness 0.0254)
		(filled_areas_thickness no)
		(fill yes
			(thermal_gap 0.5)
			(thermal_bridge_width 0.5)
			(island_removal_mode 1)
			(island_area_min 10)
		)
		(polygon
			(pts
				(xy 101.199323 83.185) (xy 101.277235 83.189713) (xy 101.33602 83.2027) (xy 101.427051 83.244802)
				(xy 101.512222 83.2875) (xy 101.601 83.085) (xy 101.512222 82.8825) (xy 101.42705 82.925199) (xy 101.334217 82.967867)
				(xy 101.276078 82.980444) (xy 101.199323 82.985)
			)
		)
	)
	(zone
		(net 55)
		(net_name "/USB-C console/USB_D+")
		(layer "B.Cu")
		(name "$teardrop_padvia$")
		(hatch none 0.1)
		(priority 30485)
		(attr
			(teardrop
				(type padvia)
			)
		)
		(connect_pads yes
			(clearance 0)
		)
		(min_thickness 0.0254)
		(filled_areas_thickness no)
		(fill yes
			(thermal_gap 0.5)
			(thermal_bridge_width 0.5)
			(island_removal_mode 1)
			(island_area_min 10)
		)
		(polygon
			(pts
				(xy 102.252147 85.152965) (xy 102.301272 85.208737) (xy 102.331936 85.257645) (xy 102.364474 85.352552)
				(xy 102.395617 85.451998) (xy 102.601582 85.371585) (xy 102.681995 85.16562) (xy 102.582549 85.134477)
				(xy 102.488461 85.102351) (xy 102.439185 85.071613) (xy 102.382962 85.02215)
			)
		)
	)
	(zone
		(net 161)
		(net_name "/2xUSB3.0+RJ45/USBSS_2.RX+")
		(layer "B.Cu")
		(name "$teardrop_padvia$")
		(hatch none 0.1)
		(priority 31028)
		(attr
			(teardrop
				(type padvia)
			)
		)
		(connect_pads yes
			(clearance 0)
		)
		(min_thickness 0.0254)
		(filled_areas_thickness no)
		(fill yes
			(thermal_gap 0.5)
			(thermal_bridge_width 0.5)
			(island_removal_mode 1)
			(island_area_min 10)
		)
		(polygon
			(pts
				(xy 123.46 104.8925) (xy 123.478847 104.8876) (xy 123.512108 104.881482) (xy 123.526647 104.889841)
				(xy 123.536995 104.9125) (xy 123.786 104.8) (xy 123.536995 104.6875) (xy 123.527025 104.709717)
				(xy 123.51305 104.718331) (xy 123.478847 104.7124) (xy 123.46 104.7075)
			)
		)
	)
	(zone
		(net 101)
		(net_name "/PCIe redriver/PCIe_{I}_C.RX0-")
		(layer "B.Cu")
		(name "$teardrop_padvia$")
		(hatch none 0.1)
		(priority 30882)
		(attr
			(teardrop
				(type padvia)
			)
		)
		(connect_pads yes
			(clearance 0)
		)
		(min_thickness 0.0254)
		(filled_areas_thickness no)
		(fill yes
			(thermal_gap 0.5)
			(thermal_bridge_width 0.5)
			(island_removal_mode 1)
			(island_area_min 10)
		)
		(polygon
			(pts
				(xy 196.968645 135.642105) (xy 196.948954 135.632594) (xy 196.919306 135.616513) (xy 196.914218 135.60177)
				(xy 196.922333 135.579528) (xy 196.551806 135.368101) (xy 196.763233 135.738628) (xy 196.785084 135.730531)
				(xy 196.799709 135.735179) (xy 196.816299 135.765249) (xy 196.82581 135.78494)
			)
		)
	)
	(zone
		(net 710)
		(net_name "Net-(U37-SDAT)")
		(layer "B.Cu")
		(name "$teardrop_padvia$")
		(hatch none 0.1)
		(priority 30091)
		(attr
			(teardrop
				(type padvia)
			)
		)
		(connect_pads yes
			(clearance 0)
		)
		(min_thickness 0.0254)
		(filled_areas_thickness no)
		(fill yes
			(thermal_gap 0.5)
			(thermal_bridge_width 0.5)
			(island_removal_mode 1)
			(island_area_min 10)
		)
		(polygon
			(pts
				(xy 213.833331 125.335196) (xy 213.828662 125.229372) (xy 213.815978 125.146302) (xy 213.766514 124.997028)
				(xy 213.730681 124.9021) (xy 213.697794 124.776841) (xy 213.33 124.849) (xy 213.256841 125.217794)
				(xy 213.369687 125.223722) (xy 213.471499 125.213156) (xy 213.563398 125.203779) (xy 213.63871 125.210806)
				(xy 213.667705 125.225246) (xy 213.689624 125.249518) (xy 213.703492 125.285531) (xy 213.708331 125.335196)
			)
		)
	)
	(zone
		(net 1)
		(net_name "GND")
		(layer "B.Cu")
		(name "$teardrop_padvia$")
		(hatch none 0.1)
		(priority 30050)
		(attr
			(teardrop
				(type padvia)
			)
		)
		(connect_pads yes
			(clearance 0)
		)
		(min_thickness 0.0254)
		(filled_areas_thickness no)
		(fill yes
			(thermal_gap 0.5)
			(thermal_bridge_width 0.5)
			(island_removal_mode 1)
			(island_area_min 10)
		)
		(polygon
			(pts
				(xy 317.84 161.01) (xy 317.892671 161.017457) (xy 317.946335 161.049659) (xy 317.969018 161.080423)
				(xy 317.985714 161.123461) (xy 317.990273 161.144727) (xy 319.451 160.91) (xy 317.990273 160.675273)
				(xy 317.977656 160.721208) (xy 317.958906 160.755539) (xy 317.908407 160.796597) (xy 317.84 160.81)
			)
		)
	)
	(zone
		(net 1)
		(net_name "GND")
		(layer "B.Cu")
		(name "$teardrop_padvia$")
		(hatch none 0.1)
		(priority 30858)
		(attr
			(teardrop
				(type padvia)
			)
		)
		(connect_pads yes
			(clearance 0)
		)
		(min_thickness 0.0254)
		(filled_areas_thickness no)
		(fill yes
			(thermal_gap 0.5)
			(thermal_bridge_width 0.5)
			(island_removal_mode 1)
			(island_area_min 10)
		)
		(polygon
			(pts
				(xy 101.68 105.265) (xy 101.669885 105.265153) (xy 101.639169 105.26454) (xy 101.60668 105.256218)
				(xy 101.577526 105.232325) (xy 101.556809 105.185) (xy 101.324 105.365) (xy 101.556809 105.545)
				(xy 101.570168 105.509099) (xy 101.588399 105.485801) (xy 101.633725 105.466101) (xy 101.669885 105.464847)
				(xy 101.68 105.465)
			)
		)
	)
	(zone
		(net 2)
		(net_name "+3V3")
		(layer "B.Cu")
		(name "$teardrop_padvia$")
		(hatch none 0.1)
		(priority 30711)
		(attr
			(teardrop
				(type padvia)
			)
		)
		(connect_pads yes
			(clearance 0)
		)
		(min_thickness 0.0254)
		(filled_areas_thickness no)
		(fill yes
			(thermal_gap 0.5)
			(thermal_bridge_width 0.5)
			(island_removal_mode 1)
			(island_area_min 10)
		)
		(polygon
			(pts
				(xy 145.649323 169.7025) (xy 145.718764 169.707318) (xy 145.770088 169.72104) (xy 145.845629 169.767755)
				(xy 145.857769 169.777299) (xy 145.924997 169.827081) (xy 146.051 169.64) (xy 145.924997 169.452919)
				(xy 145.857768 169.502702) (xy 145.774602 169.557106) (xy 145.721748 169.57219) (xy 145.649323 169.5775)
			)
		)
	)
	(zone
		(net 295)
		(net_name "/2xUSB3.0+RJ45/GbE.MDI0+")
		(layer "B.Cu")
		(name "$teardrop_padvia$")
		(hatch none 0.1)
		(priority 30659)
		(attr
			(teardrop
				(type padvia)
			)
		)
		(connect_pads yes
			(clearance 0)
		)
		(min_thickness 0.0254)
		(filled_areas_thickness no)
		(fill yes
			(thermal_gap 0.5)
			(thermal_bridge_width 0.5)
			(island_removal_mode 1)
			(island_area_min 10)
		)
		(polygon
			(pts
				(xy 164.1 150.142084) (xy 164.097797 149.936718) (xy 164.095677 149.798242) (xy 163.875 149.799)
				(xy 163.749997 149.987081) (xy 163.826138 150.020995) (xy 163.842738 150.02605) (xy 163.884281 150.039844)
				(xy 163.918398 150.059262) (xy 163.941501 150.091083) (xy 163.95 150.142084)
			)
		)
	)
	(zone
		(net 540)
		(net_name "Net-(Q8-D)")
		(layer "B.Cu")
		(name "$teardrop_padvia$")
		(hatch none 0.1)
		(priority 30130)
		(attr
			(teardrop
				(type padvia)
			)
		)
		(connect_pads yes
			(clearance 0)
		)
		(min_thickness 0.0254)
		(filled_areas_thickness no)
		(fill yes
			(thermal_gap 0.5)
			(thermal_bridge_width 0.5)
			(island_removal_mode 1)
			(island_area_min 10)
		)
		(polygon
			(pts
				(xy 97.813 71.38) (xy 97.832721 71.32274) (xy 97.895533 71.270216) (xy 97.944153 71.250449) (xy 98.003451 71.237923)
				(xy 98.0205 71.236072) (xy 97.7505 70.759) (xy 97.4805 71.236072) (xy 97.541744 71.246248) (xy 97.592671 71.263925)
				(xy 97.633514 71.287823) (xy 97.663197 71.316022) (xy 97.68113 71.346012) (xy 97.687941 71.376862)
				(xy 97.688 71.38)
			)
		)
	)
	(zone
		(net 201)
		(net_name "/OCuLink/~{CPRSNT_D0}")
		(layer "B.Cu")
		(name "$teardrop_padvia$")
		(hatch none 0.1)
		(priority 31036)
		(attr
			(teardrop
				(type padvia)
			)
		)
		(connect_pads yes
			(clearance 0)
		)
		(min_thickness 0.0254)
		(filled_areas_thickness no)
		(fill yes
			(thermal_gap 0.5)
			(thermal_bridge_width 0.5)
			(island_removal_mode 1)
			(island_area_min 10)
		)
		(polygon
			(pts
				(xy 104.705002 161.5495) (xy 104.69868 161.549596) (xy 104.659177 161.544011) (xy 104.640955 161.529078)
				(xy 104.628007 161.4995) (xy 104.379002 161.612) (xy 104.628007 161.7245) (xy 104.639123 161.697506)
				(xy 104.65465 161.682405) (xy 104.69868 161.674404) (xy 104.705002 161.6745)
			)
		)
	)
	(zone
		(net 374)
		(net_name "/2xUSB3.0+RJ45/USB_2.D-")
		(layer "B.Cu")
		(name "$teardrop_padvia$")
		(hatch none 0.1)
		(priority 30584)
		(attr
			(teardrop
				(type padvia)
			)
		)
		(connect_pads yes
			(clearance 0)
		)
		(min_thickness 0.0254)
		(filled_areas_thickness no)
		(fill yes
			(thermal_gap 0.5)
			(thermal_bridge_width 0.5)
			(island_removal_mode 1)
			(island_area_min 10)
		)
		(polygon
			(pts
				(xy 132.854506 115.045978) (xy 132.819609 115.074171) (xy 132.786676 115.088468) (xy 132.724183 115.087628)
				(xy 132.677903 115.073636) (xy 132.625931 115.05795) (xy 132.56751 115.051281) (xy 132.571251 115.272665)
				(xy 132.736794 115.419205) (xy 132.866085 115.290111) (xy 132.985321 115.176793)
			)
		)
	)
	(zone
		(net 217)
		(net_name "/Com Express 7 Interfaces/PCIe_{B1x4}.RX1-")
		(layer "B.Cu")
		(name "$teardrop_padvia$")
		(hatch none 0.1)
		(priority 30546)
		(attr
			(teardrop
				(type padvia)
			)
		)
		(connect_pads yes
			(clearance 0)
		)
		(min_thickness 0.0254)
		(filled_areas_thickness no)
		(fill yes
			(thermal_gap 0.5)
			(thermal_bridge_width 0.5)
			(island_removal_mode 1)
			(island_area_min 10)
		)
		(polygon
			(pts
				(xy 207.8685 161.032504) (xy 207.873895 161.194035) (xy 207.877445 161.278446) (xy 207.872823 161.38014)
				(xy 208.0935 161.401) (xy 208.256731 161.251147) (xy 208.188062 161.197007) (xy 208.171608 161.187116)
				(xy 208.132935 161.162616) (xy 208.100721 161.133109) (xy 208.078673 161.091953) (xy 208.0705 161.032504)
			)
		)
	)
	(zone
		(net 370)
		(net_name "Net-(J12D-SPKR)")
		(layer "B.Cu")
		(name "$teardrop_padvia$")
		(hatch none 0.1)
		(priority 30112)
		(attr
			(teardrop
				(type padvia)
			)
		)
		(connect_pads yes
			(clearance 0)
		)
		(min_thickness 0.0254)
		(filled_areas_thickness no)
		(fill yes
			(thermal_gap 0.5)
			(thermal_bridge_width 0.5)
			(island_removal_mode 1)
			(island_area_min 10)
		)
		(polygon
			(pts
				(xy 191.6125 164.067794) (xy 191.617315 163.985733) (xy 191.631019 163.920388) (xy 191.677576 163.82712)
				(xy 191.745787 163.748657) (xy 191.801942 163.687158) (xy 191.861801 163.608339) (xy 191.55 163.399)
				(xy 191.238199 163.608339) (xy 191.335219 163.728517) (xy 191.354214 163.748658) (xy 191.407366 163.807541)
				(xy 191.449591 163.871624) (xy 191.477449 163.954008) (xy 191.4875 164.067794)
			)
		)
	)
	(zone
		(net 2)
		(net_name "+3V3")
		(layer "B.Cu")
		(name "$teardrop_padvia$")
		(hatch none 0.1)
		(priority 30353)
		(attr
			(teardrop
				(type padvia)
			)
		)
		(connect_pads yes
			(clearance 0)
		)
		(min_thickness 0.0254)
		(filled_areas_thickness no)
		(fill yes
			(thermal_gap 0.5)
			(thermal_bridge_width 0.5)
			(island_removal_mode 1)
			(island_area_min 10)
		)
		(polygon
			(pts
				(xy 139.488 169.5775) (xy 139.425134 169.557531) (xy 139.393156 169.531079) (xy 139.364642 169.493668)
				(xy 139.342118 169.446473) (xy 139.326907 169.388833) (xy 139.326798 169.388202) (xy 139.049 169.64)
				(xy 139.326798 169.891798) (xy 139.341095 169.836365) (xy 139.362175 169.79048) (xy 139.38954 169.752799)
				(xy 139.420448 169.725566) (xy 139.453735 169.708528) (xy 139.486566 169.702511) (xy 139.488 169.7025)
			)
		)
	)
	(zone
		(net 219)
		(net_name "/Com Express 7 Interfaces/PCIe_{B1x4}.TX1-")
		(layer "B.Cu")
		(name "$teardrop_padvia$")
		(hatch none 0.1)
		(priority 30843)
		(attr
			(teardrop
				(type padvia)
			)
		)
		(connect_pads yes
			(clearance 0)
		)
		(min_thickness 0.0254)
		(filled_areas_thickness no)
		(fill yes
			(thermal_gap 0.5)
			(thermal_bridge_width 0.5)
			(island_removal_mode 1)
			(island_area_min 10)
		)
		(polygon
			(pts
				(xy 117.8535 145.1855) (xy 117.859495 145.199751) (xy 117.86741 145.223792) (xy 117.859235 145.232524)
				(xy 117.835792 145.236038) (xy 117.901 145.674) (xy 118.026 145.566003) (xy 118.015931 145.44017)
				(xy 118.038615 145.29571) (xy 118.0555 145.1855)
			)
		)
	)
	(zone
		(net 2)
		(net_name "+3V3")
		(layer "B.Cu")
		(name "$teardrop_padvia$")
		(hatch none 0.1)
		(priority 30351)
		(attr
			(teardrop
				(type padvia)
			)
		)
		(connect_pads yes
			(clearance 0)
		)
		(min_thickness 0.0254)
		(filled_areas_thickness no)
		(fill yes
			(thermal_gap 0.5)
			(thermal_bridge_width 0.5)
			(island_removal_mode 1)
			(island_area_min 10)
		)
		(polygon
			(pts
				(xy 123.8175 107.372) (xy 123.797531 107.434866) (xy 123.771079 107.466844) (xy 123.733668 107.495358)
				(xy 123.686473 107.517882) (xy 123.628833 107.533093) (xy 123.628202 107.533202) (xy 123.88 107.811)
				(xy 124.131798 107.533202) (xy 124.076365 107.518905) (xy 124.03048 107.497825) (xy 123.992799 107.47046)
				(xy 123.965566 107.439552) (xy 123.948528 107.406265) (xy 123.942511 107.373434) (xy 123.9425 107.372)
			)
		)
	)
	(zone
		(net 44)
		(net_name "/2xUSB3.0+RJ45/USBSS_1.TX+")
		(layer "B.Cu")
		(name "$teardrop_padvia$")
		(hatch none 0.1)
		(priority 30966)
		(attr
			(teardrop
				(type padvia)
			)
		)
		(connect_pads yes
			(clearance 0)
		)
		(min_thickness 0.0254)
		(filled_areas_thickness no)
		(fill yes
			(thermal_gap 0.5)
			(thermal_bridge_width 0.5)
			(island_removal_mode 1)
			(island_area_min 10)
		)
		(polygon
			(pts
				(xy 100.878 104.3175) (xy 100.864708 104.321189) (xy 100.838984 104.325053) (xy 100.829339 104.314851)
				(xy 100.825023 104.289537) (xy 100.552 104.367) (xy 100.639379 104.492) (xy 100.717812 104.476152)
				(xy 100.812743 104.491205) (xy 100.878 104.5025)
			)
		)
	)
	(zone
		(net 869)
		(net_name "/Backplane/PCIe_{x2}.TX1-")
		(layer "B.Cu")
		(name "$teardrop_padvia$")
		(hatch none 0.1)
		(priority 30971)
		(attr
			(teardrop
				(type padvia)
			)
		)
		(connect_pads yes
			(clearance 0)
		)
		(min_thickness 0.0254)
		(filled_areas_thickness no)
		(fill yes
			(thermal_gap 0.5)
			(thermal_bridge_width 0.5)
			(island_removal_mode 1)
			(island_area_min 10)
		)
		(polygon
			(pts
				(xy 315.440808 161.751577) (xy 315.36886 161.768979) (xy 315.289937 161.790685) (xy 315.244412 161.792633)
				(xy 315.194173 161.783) (xy 315.136001 161.907987) (xy 315.411703 161.971988) (xy 315.415993 161.941572)
				(xy 315.425488 161.942977) (xy 315.429781 161.947245) (xy 315.438008 161.953557)
			)
		)
	)
	(zone
		(net 2)
		(net_name "+3V3")
		(layer "B.Cu")
		(name "$teardrop_padvia$")
		(hatch none 0.1)
		(priority 30432)
		(attr
			(teardrop
				(type padvia)
			)
		)
		(connect_pads yes
			(clearance 0)
		)
		(min_thickness 0.0254)
		(filled_areas_thickness no)
		(fill yes
			(thermal_gap 0.5)
			(thermal_bridge_width 0.5)
			(island_removal_mode 1)
			(island_area_min 10)
		)
		(polygon
			(pts
				(xy 310.4375 117.267) (xy 310.417727 117.326412) (xy 310.354453 117.382496) (xy 310.305828 117.404198)
				(xy 310.246469 117.418872) (xy 310.2345 117.420652) (xy 310.5 117.681) (xy 310.7655 117.420652)
				(xy 310.705362 117.407803) (xy 310.655478 117.387869) (xy 310.615358 117.361944) (xy 310.586345 117.332124)
				(xy 310.568854 117.300706) (xy 310.562521 117.268895) (xy 310.5625 117.267)
			)
		)
	)
	(zone
		(net 1)
		(net_name "GND")
		(layer "B.Cu")
		(hatch edge 0.5)
		(priority 1)
		(connect_pads
			(clearance 0.15)
		)
		(min_thickness 0.25)
		(filled_areas_thickness no)
		(fill yes
			(thermal_gap 0.2)
			(thermal_bridge_width 0.5)
			(smoothing fillet)
			(radius 0.2)
		)
		(polygon
			(pts
				(xy 116.75 87.71) (xy 116.75 93.31) (xy 115.35 93.31) (xy 115.35 87.71) (xy 115.35 84.81) (xy 116.75 84.81)
			)
		)
	)
	(zone
		(net 78)
		(net_name "+1V8")
		(layer "B.Cu")
		(name "$teardrop_padvia$")
		(hatch none 0.1)
		(priority 30338)
		(attr
			(teardrop
				(type padvia)
			)
		)
		(connect_pads yes
			(clearance 0)
		)
		(min_thickness 0.0254)
		(filled_areas_thickness no)
		(fill yes
			(thermal_gap 0.5)
			(thermal_bridge_width 0.5)
			(island_removal_mode 1)
			(island_area_min 10)
		)
		(polygon
			(pts
				(xy 143.7075 136.622) (xy 143.687531 136.684866) (xy 143.661079 136.716844) (xy 143.623668 136.745358)
				(xy 143.576473 136.767882) (xy 143.518833 136.783093) (xy 143.518202 136.783202) (xy 143.77 137.061)
				(xy 144.021798 136.783202) (xy 143.966365 136.768905) (xy 143.92048 136.747825) (xy 143.882799 136.72046)
				(xy 143.855566 136.689552) (xy 143.838528 136.656265) (xy 143.832511 136.623434) (xy 143.8325 136.622)
			)
		)
	)
	(zone
		(net 209)
		(net_name "/Com Express 7 Interfaces/PCIe_{B1x4}.RX3-")
		(layer "B.Cu")
		(name "$teardrop_padvia$")
		(hatch none 0.1)
		(priority 30165)
		(attr
			(teardrop
				(type padvia)
			)
		)
		(connect_pads yes
			(clearance 0)
		)
		(min_thickness 0.0254)
		(filled_areas_thickness no)
		(fill yes
			(thermal_gap 0.5)
			(thermal_bridge_width 0.5)
			(island_removal_mode 1)
			(island_area_min 10)
		)
		(polygon
			(pts
				(xy 197.165726 142.281637) (xy 197.158751 142.249992) (xy 197.162425 142.217424) (xy 197.202173 142.145836)
				(xy 197.332321 142.02069) (xy 197.05385 141.880555) (xy 196.804803 142.084056) (xy 196.887398 142.160578)
				(xy 196.959304 142.274142) (xy 197.015372 142.405104) (xy 197.022891 142.424472)
			)
		)
	)
	(zone
		(net 205)
		(net_name "/Backplane/PCIe_{REF}.CK-")
		(layer "B.Cu")
		(name "$teardrop_padvia$")
		(hatch none 0.1)
		(priority 30937)
		(attr
			(teardrop
				(type padvia)
			)
		)
		(connect_pads yes
			(clearance 0)
		)
		(min_thickness 0.0254)
		(filled_areas_thickness no)
		(fill yes
			(thermal_gap 0.5)
			(thermal_bridge_width 0.5)
			(island_removal_mode 1)
			(island_area_min 10)
		)
		(polygon
			(pts
				(xy 314.04 165.2555) (xy 314.053941 165.250168) (xy 314.078365 165.243442) (xy 314.087289 165.252549)
				(xy 314.090953 165.277292) (xy 314.366 165.21) (xy 314.302083 165.085) (xy 314.219652 165.094335)
				(xy 314.119272 165.071146) (xy 314.04 165.0535)
			)
		)
	)
	(zone
		(net 866)
		(net_name "/Backplane/PCIe_{x2}.TX0+")
		(layer "B.Cu")
		(name "$teardrop_padvia$")
		(hatch none 0.1)
		(priority 30940)
		(attr
			(teardrop
				(type padvia)
			)
		)
		(connect_pads yes
			(clearance 0)
		)
		(min_thickness 0.0254)
		(filled_areas_thickness no)
		(fill yes
			(thermal_gap 0.5)
			(thermal_bridge_width 0.5)
			(island_removal_mode 1)
			(island_area_min 10)
		)
		(polygon
			(pts
				(xy 314.04 160.0665) (xy 314.119272 160.048854) (xy 314.204896 160.027263) (xy 314.252145 160.025372)
				(xy 314.302083 160.035) (xy 314.366 159.91) (xy 314.090953 159.842707) (xy 314.08632 159.86951)
				(xy 314.075289 159.877052) (xy 314.053941 159.869832) (xy 314.04 159.8645)
			)
		)
	)
	(zone
		(net 157)
		(net_name "Net-(J1A-LED_D4)")
		(layer "B.Cu")
		(name "$teardrop_padvia$")
		(hatch none 0.1)
		(priority 30391)
		(attr
			(teardrop
				(type padvia)
			)
		)
		(connect_pads yes
			(clearance 0)
		)
		(min_thickness 0.0254)
		(filled_areas_thickness no)
		(fill yes
			(thermal_gap 0.5)
			(thermal_bridge_width 0.5)
			(island_removal_mode 1)
			(island_area_min 10)
		)
		(polygon
			(pts
				(xy 122.9825 112.248) (xy 123.002469 112.185134) (xy 123.028921 112.153156) (xy 123.066332 112.124642)
				(xy 123.113527 112.102118) (xy 123.171167 112.086907) (xy 123.171798 112.086798) (xy 122.92 111.809)
				(xy 122.668202 112.086798) (xy 122.723635 112.101095) (xy 122.76952 112.122175) (xy 122.807201 112.14954)
				(xy 122.834434 112.180448) (xy 122.851472 112.213735) (xy 122.857489 112.246566) (xy 122.8575 112.248)
			)
		)
	)
	(zone
		(net 60)
		(net_name "/OCuLink/V_{ACT_RX}0")
		(layer "B.Cu")
		(name "$teardrop_padvia$")
		(hatch none 0.1)
		(priority 30120)
		(attr
			(teardrop
				(type padvia)
			)
		)
		(connect_pads yes
			(clearance 0)
		)
		(min_thickness 0.0254)
		(filled_areas_thickness no)
		(fill yes
			(thermal_gap 0.5)
			(thermal_bridge_width 0.5)
			(island_removal_mode 1)
			(island_area_min 10)
		)
		(polygon
			(pts
				(xy 103.289792 168.851923) (xy 103.341453 168.861953) (xy 103.399308 168.884207) (xy 103.451116 168.91568)
				(xy 103.497031 168.958668) (xy 103.525452 169.000747) (xy 103.544607 169.050642) (xy 103.552022 169.110166)
				(xy 103.950707 168.760707) (xy 103.555964 168.390014) (xy 103.555344 168.473166) (xy 103.548406 168.604526)
				(xy 103.532596 168.633142) (xy 103.501923 168.639792)
			)
		)
	)
	(zone
		(net 577)
		(net_name "Net-(U18-EN)")
		(layer "B.Cu")
		(name "$teardrop_padvia$")
		(hatch none 0.1)
		(priority 30766)
		(attr
			(teardrop
				(type padvia)
			)
		)
		(connect_pads yes
			(clearance 0)
		)
		(min_thickness 0.0254)
		(filled_areas_thickness no)
		(fill yes
			(thermal_gap 0.5)
			(thermal_bridge_width 0.5)
			(island_removal_mode 1)
			(island_area_min 10)
		)
		(polygon
			(pts
				(xy 309.585872 120.436514) (xy 309.638381 120.390818) (xy 309.684375 120.36423) (xy 309.770823 120.343846)
				(xy 309.786159 120.34201) (xy 309.868894 120.329676) (xy 309.825706 120.108292) (xy 309.604322 120.065104)
				(xy 309.591987 120.14784) (xy 309.57165 120.245118) (xy 309.544942 120.293158) (xy 309.497484 120.348126)
			)
		)
	)
	(zone
		(net 966)
		(net_name "/PCIe redriver/PCIe_{O}_C.TX0-")
		(layer "B.Cu")
		(name "$teardrop_padvia$")
		(hatch none 0.1)
		(priority 30173)
		(attr
			(teardrop
				(type padvia)
			)
		)
		(connect_pads yes
			(clearance 0)
		)
		(min_thickness 0.0254)
		(filled_areas_thickness no)
		(fill yes
			(thermal_gap 0.5)
			(thermal_bridge_width 0.5)
			(island_removal_mode 1)
			(island_area_min 10)
		)
		(polygon
			(pts
				(xy 110.657154 166.062786) (xy 110.629576 166.048786) (xy 110.608537 166.026116) (xy 110.584334 165.95355)
				(xy 110.582581 165.809042) (xy 110.586 165.76617) (xy 110.29 165.869) (xy 110.264484 166.189) (xy 110.374856 166.184484)
				(xy 110.507405 166.212972) (xy 110.596943 166.243775) (xy 110.657154 166.264786)
			)
		)
	)
	(zone
		(net 78)
		(net_name "+1V8")
		(layer "B.Cu")
		(name "$teardrop_padvia$")
		(hatch none 0.1)
		(priority 30740)
		(attr
			(teardrop
				(type padvia)
			)
		)
		(connect_pads yes
			(clearance 0)
		)
		(min_thickness 0.0254)
		(filled_areas_thickness no)
		(fill yes
			(thermal_gap 0.5)
			(thermal_bridge_width 0.5)
			(island_removal_mode 1)
			(island_area_min 10)
		)
		(polygon
			(pts
				(xy 124.760677 134.8175) (xy 124.691236 134.812682) (xy 124.639913 134.79896) (xy 124.564371 134.752246)
				(xy 124.552231 134.742701) (xy 124.485003 134.692919) (xy 124.359 134.88) (xy 124.485003 135.067081)
				(xy 124.552229 135.017299) (xy 124.635396 134.962894) (xy 124.688251 134.94781) (xy 124.760677 134.9425)
			)
		)
	)
	(zone
		(net 63)
		(net_name "Net-(U18-V_{CC})")
		(layer "B.Cu")
		(name "$teardrop_padvia$")
		(hatch none 0.1)
		(priority 30331)
		(attr
			(teardrop
				(type padvia)
			)
		)
		(connect_pads yes
			(clearance 0)
		)
		(min_thickness 0.0254)
		(filled_areas_thickness no)
		(fill yes
			(thermal_gap 0.5)
			(thermal_bridge_width 0.5)
			(island_removal_mode 1)
			(island_area_min 10)
		)
		(polygon
			(pts
				(xy 310.836999 122.5025) (xy 310.899865 122.522469) (xy 310.931843 122.548921) (xy 310.960357 122.586332)
				(xy 310.982881 122.633527) (xy 310.998092 122.691167) (xy 310.998201 122.691798) (xy 311.275999 122.44)
				(xy 310.998201 122.188202) (xy 310.983904 122.243635) (xy 310.962824 122.28952) (xy 310.935459 122.327201)
				(xy 310.904551 122.354434) (xy 310.871264 122.371472) (xy 310.838433 122.377489) (xy 310.836999 122.3775)
			)
		)
	)
	(zone
		(net 1)
		(net_name "GND")
		(layer "B.Cu")
		(name "$teardrop_padvia$")
		(hatch none 0.1)
		(priority 30215)
		(attr
			(teardrop
				(type padvia)
			)
		)
		(connect_pads yes
			(clearance 0)
		)
		(min_thickness 0.0254)
		(filled_areas_thickness no)
		(fill yes
			(thermal_gap 0.5)
			(thermal_bridge_width 0.5)
			(island_removal_mode 1)
			(island_area_min 10)
		)
		(polygon
			(pts
				(xy 124.269444 96.161056) (xy 124.214065 96.077713) (xy 124.177846 95.947724) (xy 124.171483 95.867134)
				(xy 124.175 95.779526) (xy 123.879293 95.859293) (xy 123.824526 96.18) (xy 123.975684 96.170982)
				(xy 124.043215 96.180826) (xy 124.102026 96.199091) (xy 124.181056 96.249444)
			)
		)
	)
	(zone
		(net 365)
		(net_name "/Com Express 7 MGMT/PWR_OK")
		(layer "B.Cu")
		(name "$teardrop_padvia$")
		(hatch none 0.1)
		(priority 30767)
		(attr
			(teardrop
				(type padvia)
			)
		)
		(connect_pads yes
			(clearance 0)
		)
		(min_thickness 0.0254)
		(filled_areas_thickness no)
		(fill yes
			(thermal_gap 0.5)
			(thermal_bridge_width 0.5)
			(island_removal_mode 1)
			(island_area_min 10)
		)
		(polygon
			(pts
				(xy 102.210873 72.687515) (xy 102.263382 72.641819) (xy 102.309376 72.615231) (xy 102.395824 72.594847)
				(xy 102.41116 72.593011) (xy 102.493895 72.580677) (xy 102.450707 72.359293) (xy 102.229323 72.316105)
				(xy 102.216988 72.398841) (xy 102.196651 72.496119) (xy 102.169943 72.544159) (xy 102.122485 72.599127)
			)
		)
	)
	(zone
		(net 99)
		(net_name "/PCIe redriver/PCIe_{O}_C.TX3-")
		(layer "B.Cu")
		(name "$teardrop_padvia$")
		(hatch none 0.1)
		(priority 30845)
		(attr
			(teardrop
				(type padvia)
			)
		)
		(connect_pads yes
			(clearance 0)
		)
		(min_thickness 0.0254)
		(filled_areas_thickness no)
		(fill yes
			(thermal_gap 0.5)
			(thermal_bridge_width 0.5)
			(island_removal_mode 1)
			(island_area_min 10)
		)
		(polygon
			(pts
				(xy 115.0575 149.5355) (xy 115.04007 149.423096) (xy 115.018317 149.299222) (xy 115.016358 149.228305)
				(xy 115.026 149.150651) (xy 114.901 149.047) (xy 114.837574 149.485315) (xy 114.863182 149.489774)
				(xy 114.869601 149.500719) (xy 114.861457 149.52134) (xy 114.8555 149.5355)
			)
		)
	)
	(zone
		(net 78)
		(net_name "+1V8")
		(layer "B.Cu")
		(name "$teardrop_padvia$")
		(hatch none 0.1)
		(priority 30374)
		(attr
			(teardrop
				(type padvia)
			)
		)
		(connect_pads yes
			(clearance 0)
		)
		(min_thickness 0.0254)
		(filled_areas_thickness no)
		(fill yes
			(thermal_gap 0.5)
			(thermal_bridge_width 0.5)
			(island_removal_mode 1)
			(island_area_min 10)
		)
		(polygon
			(pts
				(xy 143.8325 136.498) (xy 143.852469 136.435134) (xy 143.878921 136.403156) (xy 143.916332 136.374642)
				(xy 143.963527 136.352118) (xy 144.021167 136.336907) (xy 144.021798 136.336798) (xy 143.77 136.059)
				(xy 143.518202 136.336798) (xy 143.573635 136.351095) (xy 143.61952 136.372175) (xy 143.657201 136.39954)
				(xy 143.684434 136.430448) (xy 143.701472 136.463735) (xy 143.707489 136.496566) (xy 143.7075 136.498)
			)
		)
	)
	(zone
		(net 157)
		(net_name "Net-(J1A-LED_D4)")
		(layer "B.Cu")
		(name "$teardrop_padvia$")
		(hatch none 0.1)
		(priority 30029)
		(attr
			(teardrop
				(type padvia)
			)
		)
		(connect_pads yes
			(clearance 0)
		)
		(min_thickness 0.0254)
		(filled_areas_thickness no)
		(fill yes
			(thermal_gap 0.5)
			(thermal_bridge_width 0.5)
			(island_removal_mode 1)
			(island_area_min 10)
		)
		(polygon
			(pts
				(xy 121.948411 112.353201) (xy 121.896031 112.398683) (xy 121.846691 112.42802) (xy 121.804362 112.441894)
				(xy 121.763779 112.444948) (xy 121.685579 112.422581) (xy 121.596394 112.357257) (xy 121.479061 112.233896)
				(xy 121.365292 112.112283) (xy 121.23501 112.003758) (xy 120.859293 112.565707) (xy 121.237559 113.123692)
				(xy 121.51462 112.928214) (xy 121.713641 112.760162) (xy 121.971925 112.506524) (xy 122.036799 112.441589)
			)
		)
	)
	(zone
		(net 975)
		(net_name "/PCIe redriver/RX_FG0")
		(layer "B.Cu")
		(name "$teardrop_padvia$")
		(hatch none 0.1)
		(priority 30909)
		(attr
			(teardrop
				(type padvia)
			)
		)
		(connect_pads yes
			(clearance 0)
		)
		(min_thickness 0.0254)
		(filled_areas_thickness no)
		(fill yes
			(thermal_gap 0.5)
			(thermal_bridge_width 0.5)
			(island_removal_mode 1)
			(island_area_min 10)
		)
		(polygon
			(pts
				(xy 192.698781 139.91197) (xy 192.694244 139.907568) (xy 192.670259 139.875685) (xy 192.667933 139.85224)
				(xy 192.679692 139.822169) (xy 192.309165 139.610742) (xy 192.520594 139.981269) (xy 192.547542 139.970042)
				(xy 192.5692 139.970343) (xy 192.605992 139.99582) (xy 192.610394 140.000357)
			)
		)
	)
	(zone
		(net 867)
		(net_name "/Backplane/PCIe_{x2}.TX0-")
		(layer "B.Cu")
		(name "$teardrop_padvia$")
		(hatch none 0.1)
		(priority 30043)
		(attr
			(teardrop
				(type padvia)
			)
		)
		(connect_pads yes
			(clearance 0)
		)
		(min_thickness 0.0254)
		(filled_areas_thickness no)
		(fill yes
			(thermal_gap 0.5)
			(thermal_bridge_width 0.5)
			(island_removal_mode 1)
			(island_area_min 10)
		)
		(polygon
			(pts
				(xy 317.860744 160.0055) (xy 317.893777 160.011457) (xy 317.923712 160.033158) (xy 317.939644 160.060607)
				(xy 317.949306 160.100407) (xy 317.95 160.165591) (xy 319.451 160.11) (xy 319.254117 159.835) (xy 318.774522 159.844225)
				(xy 318.255858 159.820754) (xy 317.860744 159.8035)
			)
		)
	)
	(zone
		(net 574)
		(net_name "Net-(U19-EN)")
		(layer "B.Cu")
		(name "$teardrop_padvia$")
		(hatch none 0.1)
		(priority 30221)
		(attr
			(teardrop
				(type padvia)
			)
		)
		(connect_pads yes
			(clearance 0)
		)
		(min_thickness 0.0254)
		(filled_areas_thickness no)
		(fill yes
			(thermal_gap 0.5)
			(thermal_bridge_width 0.5)
			(island_removal_mode 1)
			(island_area_min 10)
		)
		(polygon
			(pts
				(xy 309.435555 101.938944) (xy 309.485408 102.016761) (xy 309.513528 102.138204) (xy 309.514742 102.212476)
				(xy 309.505491 102.292762) (xy 309.504999 102.295474) (xy 309.825706 102.240707) (xy 309.905473 101.945)
				(xy 309.819033 101.948538) (xy 309.7394 101.942454) (xy 309.666861 101.927419) (xy 309.604047 101.904456)
				(xy 309.523943 101.850556)
			)
		)
	)
	(zone
		(net 57)
		(net_name "/USB-C console/FTDI_VCCIO")
		(layer "B.Cu")
		(name "$teardrop_padvia$")
		(hatch none 0.1)
		(priority 30201)
		(attr
			(teardrop
				(type padvia)
			)
		)
		(connect_pads yes
			(clearance 0)
		)
		(min_thickness 0.0254)
		(filled_areas_thickness no)
		(fill yes
			(thermal_gap 0.5)
			(thermal_bridge_width 0.5)
			(island_removal_mode 1)
			(island_area_min 10)
		)
		(polygon
			(pts
				(xy 113.11 76.287) (xy 113.110286 76.302759) (xy 113.109549 76.347148) (xy 113.097428 76.393818)
				(xy 113.06228 76.435336) (xy 112.992463 76.464272) (xy 113.254999 76.726) (xy 113.523398 76.473046)
				(xy 113.479348 76.45683) (xy 113.44824 76.435595) (xy 113.415972 76.383455) (xy 113.409604 76.30502)
				(xy 113.41 76.287)
			)
		)
	)
	(zone
		(net 2)
		(net_name "+3V3")
		(layer "B.Cu")
		(name "$teardrop_padvia$")
		(hatch none 0.1)
		(priority 30197)
		(attr
			(teardrop
				(type padvia)
			)
		)
		(connect_pads yes
			(clearance 0)
		)
		(min_thickness 0.0254)
		(filled_areas_thickness no)
		(fill yes
			(thermal_gap 0.5)
			(thermal_bridge_width 0.5)
			(island_removal_mode 1)
			(island_area_min 10)
		)
		(polygon
			(pts
				(xy 219 127.762) (xy 218.990716 127.69838) (xy 218.978771 127.59297) (xy 218.99068 127.541586) (xy 219.025 127.4965)
				(xy 218.73 127.323) (xy 218.540205 127.635586) (xy 218.601321 127.64192) (xy 218.644466 127.655803)
				(xy 218.671197 127.673836) (xy 218.687604 127.695255) (xy 218.699798 127.748423) (xy 218.7 127.762)
			)
		)
	)
	(zone
		(net 239)
		(net_name "/Com Express 7 Interfaces/PCIe_{B2Bx4}.RX3+")
		(layer "B.Cu")
		(name "$teardrop_padvia$")
		(hatch none 0.1)
		(priority 30518)
		(attr
			(teardrop
				(type padvia)
			)
		)
		(connect_pads yes
			(clearance 0)
		)
		(min_thickness 0.0254)
		(filled_areas_thickness no)
		(fill yes
			(thermal_gap 0.5)
			(thermal_bridge_width 0.5)
			(island_removal_mode 1)
			(island_area_min 10)
		)
		(polygon
			(pts
				(xy 173.967496 93.8145) (xy 173.92071 93.809765) (xy 173.885258 93.796621) (xy 173.83706 93.751613)
				(xy 173.812884 93.713392) (xy 173.785514 93.670225) (xy 173.748852 93.628268) (xy 173.599 93.7915)
				(xy 173.61986 94.012177) (xy 173.720531 94.007548) (xy 173.803897 94.01098) (xy 173.805964 94.011105)
				(xy 173.967496 94.0165)
			)
		)
	)
	(zone
		(net 143)
		(net_name "/2xSFP+/KR to SFI #2/~{RESET}")
		(layer "B.Cu")
		(name "$teardrop_padvia$")
		(hatch none 0.1)
		(priority 30757)
		(attr
			(teardrop
				(type padvia)
			)
		)
		(connect_pads yes
			(clearance 0)
		)
		(min_thickness 0.0254)
		(filled_areas_thickness no)
		(fill yes
			(thermal_gap 0.5)
			(thermal_bridge_width 0.5)
			(island_removal_mode 1)
			(island_area_min 10)
		)
		(polygon
			(pts
				(xy 130.962485 135.620873) (xy 131.008181 135.673382) (xy 131.034768 135.719376) (xy 131.055152 135.805825)
				(xy 131.056988 135.821158) (xy 131.069323 135.903895) (xy 131.290707 135.860707) (xy 131.333895 135.639323)
				(xy 131.251158 135.626988) (xy 131.15388 135.606651) (xy 131.10584 135.579943) (xy 131.050873 135.532485)
			)
		)
	)
	(zone
		(net 656)
		(net_name "Net-(U43C-PRTAD1)")
		(layer "B.Cu")
		(name "$teardrop_padvia$")
		(hatch none 0.1)
		(priority 30776)
		(attr
			(teardrop
				(type padvia)
			)
		)
		(connect_pads yes
			(clearance 0)
		)
		(min_thickness 0.0254)
		(filled_areas_thickness no)
		(fill yes
			(thermal_gap 0.5)
			(thermal_bridge_width 0.5)
			(island_removal_mode 1)
			(island_area_min 10)
		)
		(polygon
			(pts
				(xy 150.210873 140.187515) (xy 150.263382 140.141819) (xy 150.309376 140.115231) (xy 150.395824 140.094847)
				(xy 150.41116 140.093011) (xy 150.493895 140.080677) (xy 150.450707 139.859293) (xy 150.229323 139.816105)
				(xy 150.216988 139.898841) (xy 150.196651 139.996119) (xy 150.169943 140.044159) (xy 150.122485 140.099127)
			)
		)
	)
	(zone
		(net 201)
		(net_name "/OCuLink/~{CPRSNT_D0}")
		(layer "B.Cu")
		(name "$teardrop_padvia$")
		(hatch none 0.1)
		(priority 30644)
		(attr
			(teardrop
				(type padvia)
			)
		)
		(connect_pads yes
			(clearance 0)
		)
		(min_thickness 0.0254)
		(filled_areas_thickness no)
		(fill yes
			(thermal_gap 0.5)
			(thermal_bridge_width 0.5)
			(island_removal_mode 1)
			(island_area_min 10)
		)
		(polygon
			(pts
				(xy 103.285796 161.652593) (xy 103.315858 161.629283) (xy 103.343297 161.620827) (xy 103.389338 161.634795)
				(xy 103.442113 161.680327) (xy 103.494603 161.727175) (xy 103.557891 161.759791) (xy 103.616729 161.544304)
				(xy 103.488101 161.360847) (xy 103.378389 161.42799) (xy 103.297363 161.477419) (xy 103.197407 161.564204)
			)
		)
	)
	(zone
		(net 1)
		(net_name "GND")
		(layer "B.Cu")
		(name "$teardrop_padvia$")
		(hatch none 0.1)
		(priority 30899)
		(attr
			(teardrop
				(type padvia)
			)
		)
		(connect_pads yes
			(clearance 0)
		)
		(min_thickness 0.0254)
		(filled_areas_thickness no)
		(fill yes
			(thermal_gap 0.5)
			(thermal_bridge_width 0.5)
			(island_removal_mode 1)
			(island_area_min 10)
		)
		(polygon
			(pts
				(xy 190.223908 138.162587) (xy 190.219506 138.167124) (xy 190.187623 138.191109) (xy 190.164178 138.193435)
				(xy 190.134107 138.181675) (xy 189.92268 138.552203) (xy 190.293207 138.340775) (xy 190.28198 138.313827)
				(xy 190.282281 138.292169) (xy 190.307758 138.255375) (xy 190.312295 138.250974)
			)
		)
	)
	(zone
		(net 653)
		(net_name "Net-(U43C-TESTEN)")
		(layer "B.Cu")
		(name "$teardrop_padvia$")
		(hatch none 0.1)
		(priority 30823)
		(attr
			(teardrop
				(type padvia)
			)
		)
		(connect_pads yes
			(clearance 0)
		)
		(min_thickness 0.0254)
		(filled_areas_thickness no)
		(fill yes
			(thermal_gap 0.5)
			(thermal_bridge_width 0.5)
			(island_removal_mode 1)
			(island_area_min 10)
		)
		(polygon
			(pts
				(xy 146.362901 140.521289) (xy 146.383971 140.549104) (xy 146.390503 140.574568) (xy 146.373557 140.617676)
				(xy 146.327171 140.665489) (xy 146.262919 140.734997) (xy 146.450707 140.860707) (xy 146.637081 140.734997)
				(xy 146.57193 140.611746) (xy 146.531279 140.530407) (xy 146.451289 140.432901)
			)
		)
	)
	(zone
		(net 288)
		(net_name "/2xUSB3.0+RJ45/~{GBE0_LINK_1000}")
		(layer "B.Cu")
		(name "$teardrop_padvia$")
		(hatch none 0.1)
		(priority 30397)
		(attr
			(teardrop
				(type padvia)
			)
		)
		(connect_pads yes
			(clearance 0)
		)
		(min_thickness 0.0254)
		(filled_areas_thickness no)
		(fill yes
			(thermal_gap 0.5)
			(thermal_bridge_width 0.5)
			(island_removal_mode 1)
			(island_area_min 10)
		)
		(polygon
			(pts
				(xy 124.293 111.7475) (xy 124.233588 111.727727) (xy 124.177503 111.664453) (xy 124.155801 111.615828)
				(xy 124.141127 111.556468) (xy 124.139347 111.5445) (xy 123.879 111.81) (xy 124.139347 112.0755)
				(xy 124.152197 112.015361) (xy 124.172131 111.965477) (xy 124.198056 111.925358) (xy 124.227876 111.896345)
				(xy 124.259294 111.878854) (xy 124.291105 111.872521) (xy 124.293 111.8725)
			)
		)
	)
	(zone
		(net 629)
		(net_name "Net-(U39-EN_{I2C})")
		(layer "B.Cu")
		(name "$teardrop_padvia$")
		(hatch none 0.1)
		(priority 30449)
		(attr
			(teardrop
				(type padvia)
			)
		)
		(connect_pads yes
			(clearance 0)
		)
		(min_thickness 0.0254)
		(filled_areas_thickness no)
		(fill yes
			(thermal_gap 0.5)
			(thermal_bridge_width 0.5)
			(island_removal_mode 1)
			(island_area_min 10)
		)
		(polygon
			(pts
				(xy 123.809 147.8625) (xy 123.868412 147.882273) (xy 123.924497 147.945547) (xy 123.946199 147.994172)
				(xy 123.960873 148.053531) (xy 123.962653 148.0655) (xy 124.223 147.8) (xy 123.962653 147.5345)
				(xy 123.949804 147.594638) (xy 123.92987 147.644522) (xy 123.903945 147.684641) (xy 123.874125 147.713654)
				(xy 123.842707 147.731146) (xy 123.810896 147.737479) (xy 123.809 147.7375)
			)
		)
	)
	(zone
		(net 49)
		(net_name "/2xUSB3.0+RJ45/USBSS_2.TX-")
		(layer "B.Cu")
		(name "$teardrop_padvia$")
		(hatch none 0.1)
		(priority 30949)
		(attr
			(teardrop
				(type padvia)
			)
		)
		(connect_pads yes
			(clearance 0)
		)
		(min_thickness 0.0254)
		(filled_areas_thickness no)
		(fill yes
			(thermal_gap 0.5)
			(thermal_bridge_width 0.5)
			(island_removal_mode 1)
			(island_area_min 10)
		)
		(polygon
			(pts
				(xy 122.688 103.8345) (xy 122.700525 103.83122) (xy 122.725501 103.828286) (xy 122.734607 103.839247)
				(xy 122.738225 103.865633) (xy 123.014 103.802) (xy 122.956351 103.677) (xy 122.868227 103.685841)
				(xy 122.768309 103.665252) (xy 122.688 103.6495)
			)
		)
	)
	(zone
		(net 1)
		(net_name "GND")
		(layer "B.Cu")
		(hatch edge 0.5)
		(priority 43)
		(connect_pads yes
			(clearance 0.15)
		)
		(min_thickness 0.25)
		(filled_areas_thickness no)
		(fill yes
			(thermal_gap 0.5)
			(thermal_bridge_width 0.5)
		)
		(polygon
			(pts
				(xy 104.7 102.56) (xy 104.7 100.19) (xy 103.73 100.19) (xy 103.73 102.56)
			)
		)
	)
	(zone
		(net 2)
		(net_name "+3V3")
		(layer "B.Cu")
		(name "$teardrop_padvia$")
		(hatch none 0.1)
		(priority 30927)
		(attr
			(teardrop
				(type padvia)
			)
		)
		(connect_pads yes
			(clearance 0)
		)
		(min_thickness 0.0254)
		(filled_areas_thickness no)
		(fill yes
			(thermal_gap 0.5)
			(thermal_bridge_width 0.5)
			(island_removal_mode 1)
			(island_area_min 10)
		)
		(polygon
			(pts
				(xy 194.129966 132.328955) (xy 194.134606 132.333454) (xy 194.158925 132.365623) (xy 194.161495 132.389247)
				(xy 194.150055 132.41953) (xy 194.520288 132.629476) (xy 194.307368 132.258652) (xy 194.280532 132.270185)
				(xy 194.258992 132.270063) (xy 194.222659 132.245005) (xy 194.218353 132.240568)
			)
		)
	)
	(zone
		(net 1)
		(net_name "GND")
		(layer "B.Cu")
		(hatch edge 0.5)
		(priority 4)
		(connect_pads
			(clearance 0.2)
		)
		(min_thickness 0.15)
		(filled_areas_thickness no)
		(fill yes
			(thermal_gap 0.2)
			(thermal_bridge_width 0.5)
			(smoothing fillet)
			(radius 0.2)
		)
		(polygon
			(pts
				(xy 103.05 153.91) (xy 103.05 171.06) (xy 95.3 171.06) (xy 95.3 153.91)
			)
		)
	)
	(zone
		(net 2)
		(net_name "+3V3")
		(layer "B.Cu")
		(name "$teardrop_padvia$")
		(hatch none 0.1)
		(priority 30889)
		(attr
			(teardrop
				(type padvia)
			)
		)
		(connect_pads yes
			(clearance 0)
		)
		(min_thickness 0.0254)
		(filled_areas_thickness no)
		(fill yes
			(thermal_gap 0.5)
			(thermal_bridge_width 0.5)
			(island_removal_mode 1)
			(island_area_min 10)
		)
		(polygon
			(pts
				(xy 120.4625 149.5355) (xy 120.462407 149.529317) (xy 120.468026 149.490256) (xy 120.483003 149.472337)
				(xy 120.512655 149.459768) (xy 120.401 149.047) (xy 120.287659 149.457247) (xy 120.314517 149.468655)
				(xy 120.329575 149.484391) (xy 120.337599 149.529037) (xy 120.3375 149.5355)
			)
		)
	)
	(zone
		(net 200)
		(net_name "/OCuLink/~{PERST_D0}")
		(layer "B.Cu")
		(name "$teardrop_padvia$")
		(hatch none 0.1)
		(priority 30437)
		(attr
			(teardrop
				(type padvia)
			)
		)
		(connect_pads yes
			(clearance 0)
		)
		(min_thickness 0.0254)
		(filled_areas_thickness no)
		(fill yes
			(thermal_gap 0.5)
			(thermal_bridge_width 0.5)
			(island_removal_mode 1)
			(island_area_min 10)
		)
		(polygon
			(pts
				(xy 120.807 162.6225) (xy 120.866412 162.642273) (xy 120.922497 162.705547) (xy 120.944199 162.754172)
				(xy 120.958873 162.813531) (xy 120.960653 162.8255) (xy 121.221 162.56) (xy 120.960653 162.2945)
				(xy 120.947804 162.354638) (xy 120.92787 162.404522) (xy 120.901945 162.444641) (xy 120.872125 162.473654)
				(xy 120.840707 162.491146) (xy 120.808896 162.497479) (xy 120.807 162.4975)
			)
		)
	)
	(zone
		(net 894)
		(net_name "Net-(J2B-MOD_{ABS})")
		(layer "B.Cu")
		(name "$teardrop_padvia$")
		(hatch none 0.1)
		(priority 30070)
		(attr
			(teardrop
				(type padvia)
			)
		)
		(connect_pads yes
			(clearance 0)
		)
		(min_thickness 0.0254)
		(filled_areas_thickness no)
		(fill yes
			(thermal_gap 0.5)
			(thermal_bridge_width 0.5)
			(island_removal_mode 1)
			(island_area_min 10)
		)
		(polygon
			(pts
				(xy 142.702736 162.295652) (xy 142.767615 162.237595) (xy 142.827096 162.197584) (xy 142.932061 162.159114)
				(xy 143.068356 162.149873) (xy 143.16714 162.146966) (xy 143.283889 162.131738) (xy 143.200707 161.709293)
				(xy 142.778262 161.626111) (xy 142.760953 161.788348) (xy 142.760127 161.841644) (xy 142.757095 161.931998)
				(xy 142.74074 162.018037) (xy 142.697634 162.107285) (xy 142.614348 162.207264)
			)
		)
	)
	(zone
		(net 578)
		(net_name "/Power/PG_{1V0}")
		(layer "B.Cu")
		(name "$teardrop_padvia$")
		(hatch none 0.1)
		(priority 30715)
		(attr
			(teardrop
				(type padvia)
			)
		)
		(connect_pads yes
			(clearance 0)
		)
		(min_thickness 0.0254)
		(filled_areas_thickness no)
		(fill yes
			(thermal_gap 0.5)
			(thermal_bridge_width 0.5)
			(island_removal_mode 1)
			(island_area_min 10)
		)
		(polygon
			(pts
				(xy 310.864322 118.7225) (xy 310.933763 118.727318) (xy 310.985087 118.74104) (xy 311.060628 118.787755)
				(xy 311.072768 118.797299) (xy 311.139996 118.847081) (xy 311.265999 118.66) (xy 311.139996 118.472919)
				(xy 311.072767 118.522702) (xy 310.989601 118.577106) (xy 310.936747 118.59219) (xy 310.864322 118.5975)
			)
		)
	)
	(zone
		(net 1)
		(net_name "GND")
		(layer "B.Cu")
		(name "$teardrop_padvia$")
		(hatch none 0.1)
		(priority 30053)
		(attr
			(teardrop
				(type padvia)
			)
		)
		(connect_pads yes
			(clearance 0)
		)
		(min_thickness 0.0254)
		(filled_areas_thickness no)
		(fill yes
			(thermal_gap 0.5)
			(thermal_bridge_width 0.5)
			(island_removal_mode 1)
			(island_area_min 10)
		)
		(polygon
			(pts
				(xy 238.522114 73.380042) (xy 238.480328 73.430147) (xy 238.432225 73.4885) (xy 238.371367 73.53989)
				(xy 238.291556 73.568872) (xy 238.242605 73.570133) (xy 238.186591 73.56) (xy 238.195001 74.060707)
				(xy 238.595708 74.169116) (xy 238.599172 74.103793) (xy 238.611376 74.045697) (xy 238.659842 73.942942)
				(xy 238.741104 73.849913) (xy 238.810016 73.790822) (xy 238.875666 73.733594)
			)
		)
	)
	(zone
		(net 216)
		(net_name "/Com Express 7 Interfaces/PCIe_{B1x4}.TX2+")
		(layer "B.Cu")
		(name "$teardrop_padvia$")
		(hatch none 0.1)
		(priority 30832)
		(attr
			(teardrop
				(type padvia)
			)
		)
		(connect_pads yes
			(clearance 0)
		)
		(min_thickness 0.0254)
		(filled_areas_thickness no)
		(fill yes
			(thermal_gap 0.5)
			(thermal_bridge_width 0.5)
			(island_removal_mode 1)
			(island_area_min 10)
		)
		(polygon
			(pts
				(xy 205.554218 166.3955) (xy 205.570342 166.400101) (xy 205.574872 166.412307) (xy 205.564276 166.450172)
				(xy 205.554109 166.481319) (xy 205.775786 166.525214) (xy 205.861748 166.322376) (xy 205.76029 166.262624)
				(xy 205.678266 166.214193) (xy 205.624763 166.1991) (xy 205.554218 166.1935)
			)
		)
	)
	(zone
		(net 677)
		(net_name "Net-(U45C-PRTAD1)")
		(layer "B.Cu")
		(name "$teardrop_padvia$")
		(hatch none 0.1)
		(priority 30413)
		(attr
			(teardrop
				(type padvia)
			)
		)
		(connect_pads yes
			(clearance 0)
		)
		(min_thickness 0.0254)
		(filled_areas_thickness no)
		(fill yes
			(thermal_gap 0.5)
			(thermal_bridge_width 0.5)
			(island_removal_mode 1)
			(island_area_min 10)
		)
		(polygon
			(pts
				(xy 126.983 137.9975) (xy 126.923588 137.977727) (xy 126.867503 137.914453) (xy 126.845801 137.865828)
				(xy 126.831127 137.806468) (xy 126.829347 137.7945) (xy 126.569 138.06) (xy 126.829347 138.3255)
				(xy 126.842197 138.265361) (xy 126.862131 138.215477) (xy 126.888056 138.175358) (xy 126.917876 138.146345)
				(xy 126.949294 138.128854) (xy 126.981105 138.122521) (xy 126.983 138.1225)
			)
		)
	)
	(zone
		(net 252)
		(net_name "/Com Express 7 Interfaces/PCIe_{B2Bx4}.RX1-")
		(layer "B.Cu")
		(name "$teardrop_padvia$")
		(hatch none 0.1)
		(priority 30566)
		(attr
			(teardrop
				(type padvia)
			)
		)
		(connect_pads yes
			(clearance 0)
		)
		(min_thickness 0.0254)
		(filled_areas_thickness no)
		(fill yes
			(thermal_gap 0.5)
			(thermal_bridge_width 0.5)
			(island_removal_mode 1)
			(island_area_min 10)
		)
		(polygon
			(pts
				(xy 173.967496 100.2035) (xy 173.805964 100.208895) (xy 173.721554 100.212445) (xy 173.61986 100.207823)
				(xy 173.599 100.4285) (xy 173.748852 100.591731) (xy 173.802992 100.523062) (xy 173.812883 100.506608)
				(xy 173.837383 100.467935) (xy 173.86689 100.435721) (xy 173.908046 100.413673) (xy 173.967496 100.4055)
			)
		)
	)
	(zone
		(net 228)
		(net_name "/M.2 key M #1/~{PERST_D}")
		(layer "B.Cu")
		(name "$teardrop_padvia$")
		(hatch none 0.1)
		(priority 30822)
		(attr
			(teardrop
				(type padvia)
			)
		)
		(connect_pads yes
			(clearance 0)
		)
		(min_thickness 0.0254)
		(filled_areas_thickness no)
		(fill yes
			(thermal_gap 0.5)
			(thermal_bridge_width 0.5)
			(island_removal_mode 1)
			(island_area_min 10)
		)
		(polygon
			(pts
				(xy 178.028542 105.0475) (xy 177.993884 105.042729) (xy 177.971308 105.02933) (xy 177.953265 104.98703)
				(xy 177.953216 104.918962) (xy 177.950407 104.820182) (xy 177.72873 104.864077) (xy 177.685835 105.084754)
				(xy 177.807084 105.122935) (xy 177.820695 105.128741) (xy 177.905119 105.159256) (xy 178.028542 105.1725)
			)
		)
	)
	(zone
		(net 100)
		(net_name "/OCuLink/PCIe_{x4}.TX0+")
		(layer "B.Cu")
		(name "$teardrop_padvia$")
		(hatch none 0.1)
		(priority 30997)
		(attr
			(teardrop
				(type padvia)
			)
		)
		(connect_pads yes
			(clearance 0)
		)
		(min_thickness 0.0254)
		(filled_areas_thickness no)
		(fill yes
			(thermal_gap 0.5)
			(thermal_bridge_width 0.5)
			(island_removal_mode 1)
			(island_area_min 10)
		)
		(polygon
			(pts
				(xy 105.48 166.509) (xy 105.459352 166.516199) (xy 105.427017 166.525792) (xy 105.412994 166.518965)
				(xy 105.403005 166.4975) (xy 105.154 166.61) (xy 105.403005 166.7225) (xy 105.41273 166.701324)
				(xy 105.426358 166.694269) (xy 105.459352 166.703801) (xy 105.48 166.711)
			)
		)
	)
	(zone
		(net 1)
		(net_name "GND")
		(layer "B.Cu")
		(name "$teardrop_padvia$")
		(hatch none 0.1)
		(priority 30445)
		(attr
			(teardrop
				(type padvia)
			)
		)
		(connect_pads yes
			(clearance 0)
		)
		(min_thickness 0.0254)
		(filled_areas_thickness no)
		(fill yes
			(thermal_gap 0.5)
			(thermal_bridge_width 0.5)
			(island_removal_mode 1)
			(island_area_min 10)
		)
		(polygon
			(pts
				(xy 125.197 142.1225) (xy 125.256412 142.142273) (xy 125.312497 142.205547) (xy 125.334199 142.254172)
				(xy 125.348873 142.313531) (xy 125.350653 142.3255) (xy 125.611 142.06) (xy 125.350653 141.7945)
				(xy 125.337804 141.854638) (xy 125.31787 141.904522) (xy 125.291945 141.944641) (xy 125.262125 141.973654)
				(xy 125.230707 141.991146) (xy 125.198896 141.997479) (xy 125.197 141.9975)
			)
		)
	)
	(zone
		(net 1)
		(net_name "GND")
		(layer "B.Cu")
		(name "$teardrop_padvia$")
		(hatch none 0.1)
		(priority 30321)
		(attr
			(teardrop
				(type padvia)
			)
		)
		(connect_pads yes
			(clearance 0)
		)
		(min_thickness 0.0254)
		(filled_areas_thickness no)
		(fill yes
			(thermal_gap 0.5)
			(thermal_bridge_width 0.5)
			(island_removal_mode 1)
			(island_area_min 10)
		)
		(polygon
			(pts
				(xy 125.082 148.367) (xy 125.07497 148.419861) (xy 125.045762 148.475042) (xy 125.01642 148.500626)
				(xy 124.975098 148.520209) (xy 124.943202 148.528202) (xy 125.22 148.781) (xy 125.461231 148.504436)
				(xy 125.402905 148.495671) (xy 125.357833 148.479645) (xy 125.324882 148.458313) (xy 125.302252 148.433261)
				(xy 125.28223 148.374443) (xy 125.282 148.367)
			)
		)
	)
	(zone
		(net 2)
		(net_name "+3V3")
		(layer "B.Cu")
		(name "$teardrop_padvia$")
		(hatch none 0.1)
		(priority 30906)
		(attr
			(teardrop
				(type padvia)
			)
		)
		(connect_pads yes
			(clearance 0)
		)
		(min_thickness 0.0254)
		(filled_areas_thickness no)
		(fill yes
			(thermal_gap 0.5)
			(thermal_bridge_width 0.5)
			(island_removal_mode 1)
			(island_area_min 10)
		)
		(polygon
			(pts
				(xy 190.948693 135.510229) (xy 190.95323 135.514631) (xy 190.977214 135.546513) (xy 190.97954 135.569958)
				(xy 190.96778 135.600029) (xy 191.338308 135.811457) (xy 191.12688 135.440929) (xy 191.099932 135.452156)
				(xy 191.078274 135.451856) (xy 191.041482 135.426379) (xy 191.03708 135.421842)
			)
		)
	)
	(zone
		(net 894)
		(net_name "Net-(J2B-MOD_{ABS})")
		(layer "B.Cu")
		(name "$teardrop_padvia$")
		(hatch none 0.1)
		(priority 30420)
		(attr
			(teardrop
				(type padvia)
			)
		)
		(connect_pads yes
			(clearance 0)
		)
		(min_thickness 0.0254)
		(filled_areas_thickness no)
		(fill yes
			(thermal_gap 0.5)
			(thermal_bridge_width 0.5)
			(island_removal_mode 1)
			(island_area_min 10)
		)
		(polygon
			(pts
				(xy 140.9875 168.267) (xy 140.967727 168.326412) (xy 140.904453 168.382496) (xy 140.855828 168.404198)
				(xy 140.796469 168.418872) (xy 140.7845 168.420652) (xy 141.05 168.681) (xy 141.3155 168.420652)
				(xy 141.255362 168.407803) (xy 141.205478 168.387869) (xy 141.165358 168.361944) (xy 141.136345 168.332124)
				(xy 141.118854 168.300706) (xy 141.112521 168.268895) (xy 141.1125 168.267)
			)
		)
	)
	(zone
		(net 91)
		(net_name "/Com Express 7 Interfaces/PCIe_{B2Ax4}.RX1+")
		(layer "B.Cu")
		(name "$teardrop_padvia$")
		(hatch none 0.1)
		(priority 30498)
		(attr
			(teardrop
				(type padvia)
			)
		)
		(connect_pads yes
			(clearance 0)
		)
		(min_thickness 0.0254)
		(filled_areas_thickness no)
		(fill yes
			(thermal_gap 0.5)
			(thermal_bridge_width 0.5)
			(island_removal_mode 1)
			(island_area_min 10)
		)
		(polygon
			(pts
				(xy 293.154 75.019852) (xy 293.149265 75.066638) (xy 293.136121 75.10209) (xy 293.091113 75.150287)
				(xy 293.052893 75.174463) (xy 293.009726 75.201832) (xy 292.967768 75.238495) (xy 293.131 75.388348)
				(xy 293.351677 75.367488) (xy 293.347048 75.266817) (xy 293.35048 75.18345) (xy 293.350605 75.181383)
				(xy 293.356 75.019852)
			)
		)
	)
	(zone
		(net 2)
		(net_name "+3V3")
		(layer "B.Cu")
		(name "$teardrop_padvia$")
		(hatch none 0.1)
		(priority 30808)
		(attr
			(teardrop
				(type padvia)
			)
		)
		(connect_pads yes
			(clearance 0)
		)
		(min_thickness 0.0254)
		(filled_areas_thickness no)
		(fill yes
			(thermal_gap 0.5)
			(thermal_bridge_width 0.5)
			(island_removal_mode 1)
			(island_area_min 10)
		)
		(polygon
			(pts
				(xy 192.122613 134.386054) (xy 192.077226 134.33386) (xy 192.050804 134.28808) (xy 192.030655 134.202021)
				(xy 192.02882 134.186257) (xy 192.016482 134.102325) (xy 191.795098 134.145513) (xy 191.75191 134.366897)
				(xy 191.833423 134.379218) (xy 191.931009 134.399922) (xy 191.979116 134.426795) (xy 192.034225 134.474442)
			)
		)
	)
	(zone
		(net 2)
		(net_name "+3V3")
		(layer "B.Cu")
		(name "$teardrop_padvia$")
		(hatch none 0.1)
		(priority 30484)
		(attr
			(teardrop
				(type padvia)
			)
		)
		(connect_pads yes
			(clearance 0)
		)
		(min_thickness 0.0254)
		(filled_areas_thickness no)
		(fill yes
			(thermal_gap 0.5)
			(thermal_bridge_width 0.5)
			(island_removal_mode 1)
			(island_area_min 10)
		)
		(polygon
			(pts
				(xy 180.78 88.5175) (xy 180.673474 88.508509) (xy 180.617425 88.488746) (xy 180.573947 88.451228)
				(xy 180.369001 88.76) (xy 180.665001 88.92021) (xy 180.669528 88.825389) (xy 180.683788 88.747996)
				(xy 180.702908 88.698332) (xy 180.728386 88.663648) (xy 180.752386 88.647887) (xy 180.78 88.6425)
			)
		)
	)
	(zone
		(net 53)
		(net_name "/2xSFP+/SH")
		(layer "B.Cu")
		(name "$teardrop_padvia$")
		(hatch none 0.1)
		(priority 30012)
		(attr
			(teardrop
				(type padvia)
			)
		)
		(connect_pads yes
			(clearance 0)
		)
		(min_thickness 0.0254)
		(filled_areas_thickness no)
		(fill yes
			(thermal_gap 0.5)
			(thermal_bridge_width 0.5)
			(island_removal_mode 1)
			(island_area_min 10)
		)
		(polygon
			(pts
				(xy 123.114411 169.585) (xy 123.238176 169.589874) (xy 123.343135 169.603996) (xy 123.427771 169.625089)
				(xy 123.501356 169.653095) (xy 123.63157 169.731201) (xy 123.766203 169.845057) (xy 123.884598 169.947896)
				(xy 124.033322 170.058602) (xy 124.451 169.435) (xy 124.033322 168.811398) (xy 123.844772 168.955593)
				(xy 123.766202 169.024943) (xy 123.643924 169.129417) (xy 123.51251 169.211718) (xy 123.434951 169.242616)
				(xy 123.344995 169.265646) (xy 123.239272 169.280032) (xy 123.114411 169.285)
			)
		)
	)
	(zone
		(net 204)
		(net_name "/Backplane/USB.D-")
		(layer "B.Cu")
		(name "$teardrop_padvia$")
		(hatch none 0.1)
		(priority 30048)
		(attr
			(teardrop
				(type padvia)
			)
		)
		(connect_pads yes
			(clearance 0)
		)
		(min_thickness 0.0254)
		(filled_areas_thickness no)
		(fill yes
			(thermal_gap 0.5)
			(thermal_bridge_width 0.5)
			(island_removal_mode 1)
			(island_area_min 10)
		)
		(polygon
			(pts
				(xy 317.863751 167.1925) (xy 317.893326 167.198) (xy 317.920169 167.216497) (xy 317.937257 167.242722)
				(xy 317.94838 167.280763) (xy 317.95 167.361067) (xy 319.451 167.31) (xy 319.259449 167.035) (xy 318.758928 167.043703)
				(xy 318.257031 167.022942) (xy 317.863751 167.0075)
			)
		)
	)
	(zone
		(net 199)
		(net_name "/OCuLink/SDA")
		(layer "B.Cu")
		(name "$teardrop_padvia$")
		(hatch none 0.1)
		(priority 30598)
		(attr
			(teardrop
				(type padvia)
			)
		)
		(connect_pads yes
			(clearance 0)
		)
		(min_thickness 0.0254)
		(filled_areas_thickness no)
		(fill yes
			(thermal_gap 0.5)
			(thermal_bridge_width 0.5)
			(island_removal_mode 1)
			(island_area_min 10)
		)
		(polygon
			(pts
				(xy 106.652072 162.106315) (xy 106.673829 162.11083) (xy 106.69241 162.124858) (xy 106.721858 162.18584)
				(xy 106.736228 162.288946) (xy 107.020707 162.059293) (xy 106.759935 161.795573) (xy 106.729201 161.891992)
				(xy 106.667514 161.970637) (xy 106.628682 161.998251) (xy 106.589613 162.014238) (xy 106.563685 162.017928)
			)
		)
	)
	(zone
		(net 143)
		(net_name "/2xSFP+/KR to SFI #2/~{RESET}")
		(layer "B.Cu")
		(name "$teardrop_padvia$")
		(hatch none 0.1)
		(priority 30154)
		(attr
			(teardrop
				(type padvia)
			)
		)
		(connect_pads yes
			(clearance 0)
		)
		(min_thickness 0.0254)
		(filled_areas_thickness no)
		(fill yes
			(thermal_gap 0.5)
			(thermal_bridge_width 0.5)
			(island_removal_mode 1)
			(island_area_min 10)
		)
		(polygon
			(pts
				(xy 140.243984 134.865596) (xy 140.167172 134.804745) (xy 140.133379 134.7584) (xy 140.10827 134.703188)
				(xy 140.095884 134.63031) (xy 139.599293 134.860293) (xy 140.093149 135.105442) (xy 140.100455 135.019613)
				(xy 140.116187 134.968353) (xy 140.130765 134.95289) (xy 140.148545 134.951289) (xy 140.155596 134.953984)
			)
		)
	)
	(zone
		(net 1)
		(net_name "GND")
		(layer "B.Cu")
		(name "$teardrop_padvia$")
		(hatch none 0.1)
		(priority 30149)
		(attr
			(teardrop
				(type padvia)
			)
		)
		(connect_pads yes
			(clearance 0)
		)
		(min_thickness 0.0254)
		(filled_areas_thickness no)
		(fill yes
			(thermal_gap 0.5)
			(thermal_bridge_width 0.5)
			(island_removal_mode 1)
			(island_area_min 10)
		)
		(polygon
			(pts
				(xy 142.663528 149.33005) (xy 142.614261 149.371423) (xy 142.550825 149.407887) (xy 142.488102 149.430727)
				(xy 142.415755 149.444265) (xy 142.302756 149.443) (xy 142.376293 149.738707) (xy 142.697 149.801054)
				(xy 142.697228 149.679287) (xy 142.73166 149.572568) (xy 142.794791 149.482011) (xy 142.80495 149.471472)
			)
		)
	)
	(zone
		(net 288)
		(net_name "/2xUSB3.0+RJ45/~{GBE0_LINK_1000}")
		(layer "B.Cu")
		(name "$teardrop_padvia$")
		(hatch none 0.1)
		(priority 30713)
		(attr
			(teardrop
				(type padvia)
			)
		)
		(connect_pads yes
			(clearance 0)
		)
		(min_thickness 0.0254)
		(filled_areas_thickness no)
		(fill yes
			(thermal_gap 0.5)
			(thermal_bridge_width 0.5)
			(island_removal_mode 1)
			(island_area_min 10)
		)
		(polygon
			(pts
				(xy 124.099323 111.8725) (xy 124.168764 111.877318) (xy 124.220088 111.89104) (xy 124.295629 111.937755)
				(xy 124.307769 111.947299) (xy 124.374997 111.997081) (xy 124.501 111.81) (xy 124.374997 111.622919)
				(xy 124.307768 111.672702) (xy 124.224602 111.727106) (xy 124.171748 111.74219) (xy 124.099323 111.7475)
			)
		)
	)
	(zone
		(net 196)
		(net_name "/OCuLink/PCIe_{x4}.RX3+")
		(layer "B.Cu")
		(name "$teardrop_padvia$")
		(hatch none 0.1)
		(priority 30551)
		(attr
			(teardrop
				(type padvia)
			)
		)
		(connect_pads yes
			(clearance 0)
		)
		(min_thickness 0.0254)
		(filled_areas_thickness no)
		(fill yes
			(thermal_gap 0.5)
			(thermal_bridge_width 0.5)
			(island_removal_mode 1)
			(island_area_min 10)
		)
		(polygon
			(pts
				(xy 106.9455 150.432504) (xy 106.950895 150.594035) (xy 106.954445 150.678446) (xy 106.949823 150.78014)
				(xy 107.1705 150.801) (xy 107.333731 150.651147) (xy 107.265062 150.597007) (xy 107.248608 150.587116)
				(xy 107.209935 150.562616) (xy 107.177721 150.533109) (xy 107.155673 150.491953) (xy 107.1475 150.432504)
			)
		)
	)
	(zone
		(net 489)
		(net_name "Net-(J12K-10G_SDP1)")
		(layer "B.Cu")
		(name "$teardrop_padvia$")
		(hatch none 0.1)
		(priority 30773)
		(attr
			(teardrop
				(type padvia)
			)
		)
		(connect_pads yes
			(clearance 0)
		)
		(min_thickness 0.0254)
		(filled_areas_thickness no)
		(fill yes
			(thermal_gap 0.5)
			(thermal_bridge_width 0.5)
			(island_removal_mode 1)
			(island_area_min 10)
		)
		(polygon
			(pts
				(xy 194.760873 149.827515) (xy 194.813382 149.781819) (xy 194.859376 149.755231) (xy 194.945824 149.734847)
				(xy 194.96116 149.733011) (xy 195.043895 149.720677) (xy 195.000707 149.499293) (xy 194.779323 149.456105)
				(xy 194.766988 149.538841) (xy 194.746651 149.636119) (xy 194.719943 149.684159) (xy 194.672485 149.739127)
			)
		)
	)
	(zone
		(net 673)
		(net_name "/2xSFP+/KR to SFI #2/PRBSEN")
		(layer "B.Cu")
		(name "$teardrop_padvia$")
		(hatch none 0.1)
		(priority 30778)
		(attr
			(teardrop
				(type padvia)
			)
		)
		(connect_pads yes
			(clearance 0)
		)
		(min_thickness 0.0254)
		(filled_areas_thickness no)
		(fill yes
			(thermal_gap 0.5)
			(thermal_bridge_width 0.5)
			(island_removal_mode 1)
			(island_area_min 10)
		)
		(polygon
			(pts
				(xy 137.617515 140.099127) (xy 137.571819 140.046618) (xy 137.545231 140.000623) (xy 137.524847 139.914175)
				(xy 137.523011 139.89884) (xy 137.510677 139.816105) (xy 137.289293 139.859293) (xy 137.246105 140.080677)
				(xy 137.32884 140.093011) (xy 137.426119 140.113349) (xy 137.474159 140.140057) (xy 137.529127 140.187515)
			)
		)
	)
	(zone
		(net 60)
		(net_name "/OCuLink/V_{ACT_RX}0")
		(layer "B.Cu")
		(name "$teardrop_padvia$")
		(hatch none 0.1)
		(priority 30224)
		(attr
			(teardrop
				(type padvia)
			)
		)
		(connect_pads yes
			(clearance 0)
		)
		(min_thickness 0.0254)
		(filled_areas_thickness no)
		(fill yes
			(thermal_gap 0.5)
			(thermal_bridge_width 0.5)
			(island_removal_mode 1)
			(island_area_min 10)
		)
		(polygon
			(pts
				(xy 103.8 169.522) (xy 103.800463 169.541209) (xy 103.800231 169.587245) (xy 103.789058 169.635846)
				(xy 103.755662 169.679899) (xy 103.688765 169.712289) (xy 103.96 169.961) (xy 104.211798 169.683202)
				(xy 104.166776 169.67104) (xy 104.135523 169.653024) (xy 104.104809 169.6069) (xy 104.099556 169.53891)
				(xy 104.1 169.522)
			)
		)
	)
	(zone
		(net 1)
		(net_name "GND")
		(layer "B.Cu")
		(name "$teardrop_padvia$")
		(hatch none 0.1)
		(priority 30247)
		(attr
			(teardrop
				(type padvia)
			)
		)
		(connect_pads yes
			(clearance 0)
		)
		(min_thickness 0.0254)
		(filled_areas_thickness no)
		(fill yes
			(thermal_gap 0.5)
			(thermal_bridge_width 0.5)
			(island_removal_mode 1)
			(island_area_min 10)
		)
		(polygon
			(pts
				(xy 176.779323 95.01) (xy 176.9369 95.016932) (xy 177.050434 95.045456) (xy 177.092222 95.0625)
				(xy 177.181 94.86) (xy 177.092222 94.6575) (xy 176.996177 94.691883) (xy 176.894296 94.707101) (xy 176.779323 94.71)
			)
		)
	)
	(zone
		(net 163)
		(net_name "Net-(J2A-TX_{DISABLE})")
		(layer "B.Cu")
		(name "$teardrop_padvia$")
		(hatch none 0.1)
		(priority 30429)
		(attr
			(teardrop
				(type padvia)
			)
		)
		(connect_pads yes
			(clearance 0)
		)
		(min_thickness 0.0254)
		(filled_areas_thickness no)
		(fill yes
			(thermal_gap 0.5)
			(thermal_bridge_width 0.5)
			(island_removal_mode 1)
			(island_area_min 10)
		)
		(polygon
			(pts
				(xy 147.9875 168.267) (xy 147.967727 168.326412) (xy 147.904453 168.382496) (xy 147.855828 168.404198)
				(xy 147.796469 168.418872) (xy 147.7845 168.420652) (xy 148.05 168.681) (xy 148.3155 168.420652)
				(xy 148.255362 168.407803) (xy 148.205478 168.387869) (xy 148.165358 168.361944) (xy 148.136345 168.332124)
				(xy 148.118854 168.300706) (xy 148.112521 168.268895) (xy 148.1125 168.267)
			)
		)
	)
	(zone
		(net 578)
		(net_name "/Power/PG_{1V0}")
		(layer "B.Cu")
		(name "$teardrop_padvia$")
		(hatch none 0.1)
		(priority 30753)
		(attr
			(teardrop
				(type padvia)
			)
		)
		(connect_pads yes
			(clearance 0)
		)
		(min_thickness 0.0254)
		(filled_areas_thickness no)
		(fill yes
			(thermal_gap 0.5)
			(thermal_bridge_width 0.5)
			(island_removal_mode 1)
			(island_area_min 10)
		)
		(polygon
			(pts
				(xy 306.859127 130.212485) (xy 306.806618 130.258181) (xy 306.760623 130.284768) (xy 306.674174 130.305152)
				(xy 306.658841 130.306988) (xy 306.576105 130.319323) (xy 306.619293 130.540707) (xy 306.840677 130.583895)
				(xy 306.853011 130.50116) (xy 306.873349 130.403881) (xy 306.900057 130.355841) (xy 306.947515 130.300873)
			)
		)
	)
	(zone
		(net 2)
		(net_name "+3V3")
		(layer "B.Cu")
		(hatch edge 0.5)
		(priority 7)
		(connect_pads
			(clearance 0.15)
		)
		(min_thickness 0.25)
		(filled_areas_thickness no)
		(fill yes
			(thermal_gap 0.2)
			(thermal_bridge_width 0.5)
		)
		(polygon
			(pts
				(xy 148.54 89.81) (xy 146.35 89.81) (xy 146.35 70.81) (xy 148.54 70.81)
			)
		)
	)
	(zone
		(net 351)
		(net_name "Net-(J12D-LPC_AD2{slash}ESPI_IO_2)")
		(layer "B.Cu")
		(name "$teardrop_padvia$")
		(hatch none 0.1)
		(priority 30760)
		(attr
			(teardrop
				(type padvia)
			)
		)
		(connect_pads yes
			(clearance 0)
		)
		(min_thickness 0.0254)
		(filled_areas_thickness no)
		(fill yes
			(thermal_gap 0.5)
			(thermal_bridge_width 0.5)
			(island_removal_mode 1)
			(island_area_min 10)
		)
		(polygon
			(pts
				(xy 177.672485 165.460873) (xy 177.718181 165.513382) (xy 177.744768 165.559376) (xy 177.765152 165.645825)
				(xy 177.766988 165.661158) (xy 177.779323 165.743895) (xy 178.000707 165.700707) (xy 178.043895 165.479323)
				(xy 177.961158 165.466988) (xy 177.86388 165.446651) (xy 177.81584 165.419943) (xy 177.760873 165.372485)
			)
		)
	)
	(zone
		(net 1)
		(net_name "GND")
		(layer "B.Cu")
		(name "$teardrop_padvia$")
		(hatch none 0.1)
		(priority 30242)
		(attr
			(teardrop
				(type padvia)
			)
		)
		(connect_pads yes
			(clearance 0)
		)
		(min_thickness 0.0254)
		(filled_areas_thickness no)
		(fill yes
			(thermal_gap 0.5)
			(thermal_bridge_width 0.5)
			(island_removal_mode 1)
			(island_area_min 10)
		)
		(polygon
			(pts
				(xy 102.789323 162.76) (xy 102.9469 162.766932) (xy 103.060434 162.795456) (xy 103.102222 162.8125)
				(xy 103.191 162.61) (xy 103.102222 162.4075) (xy 103.006177 162.441883) (xy 102.904296 162.457101)
				(xy 102.789323 162.46)
			)
		)
	)
	(zone
		(net 98)
		(net_name "/OCuLink/PCIe_{x4}.TX3-")
		(layer "B.Cu")
		(name "$teardrop_padvia$")
		(hatch none 0.1)
		(priority 31017)
		(attr
			(teardrop
				(type padvia)
			)
		)
		(connect_pads yes
			(clearance 0)
		)
		(min_thickness 0.0254)
		(filled_areas_thickness no)
		(fill yes
			(thermal_gap 0.5)
			(thermal_bridge_width 0.5)
			(island_removal_mode 1)
			(island_area_min 10)
		)
		(polygon
			(pts
				(xy 104.708 158.511) (xy 104.687352 158.518199) (xy 104.655017 158.527792) (xy 104.640994 158.520965)
				(xy 104.631005 158.4995) (xy 104.382 158.612) (xy 104.631005 158.7245) (xy 104.64073 158.703324)
				(xy 104.654358 158.696269) (xy 104.687352 158.705801) (xy 104.708 158.713)
			)
		)
	)
	(zone
		(net 100)
		(net_name "/OCuLink/PCIe_{x4}.TX0+")
		(layer "B.Cu")
		(name "$teardrop_padvia$")
		(hatch none 0.1)
		(priority 30998)
		(attr
			(teardrop
				(type padvia)
			)
		)
		(connect_pads yes
			(clearance 0)
		)
		(min_thickness 0.0254)
		(filled_areas_thickness no)
		(fill yes
			(thermal_gap 0.5)
			(thermal_bridge_width 0.5)
			(island_removal_mode 1)
			(island_area_min 10)
		)
		(polygon
			(pts
				(xy 104.708 166.509) (xy 104.687352 166.516199) (xy 104.655017 166.525792) (xy 104.640994 166.518965)
				(xy 104.631005 166.4975) (xy 104.382 166.61) (xy 104.631005 166.7225) (xy 104.64073 166.701324)
				(xy 104.654358 166.694269) (xy 104.687352 166.703801) (xy 104.708 166.711)
			)
		)
	)
	(zone
		(net 2)
		(net_name "+3V3")
		(layer "B.Cu")
		(name "$teardrop_padvia$")
		(hatch none 0.1)
		(priority 30890)
		(attr
			(teardrop
				(type padvia)
			)
		)
		(connect_pads yes
			(clearance 0)
		)
		(min_thickness 0.0254)
		(filled_areas_thickness no)
		(fill yes
			(thermal_gap 0.5)
			(thermal_bridge_width 0.5)
			(island_removal_mode 1)
			(island_area_min 10)
		)
		(polygon
			(pts
				(xy 118.9625 149.5355) (xy 118.962407 149.529317) (xy 118.968026 149.490256) (xy 118.983003 149.472337)
				(xy 119.012655 149.459768) (xy 118.901 149.047) (xy 118.787659 149.457247) (xy 118.814517 149.468655)
				(xy 118.829575 149.484391) (xy 118.837599 149.529037) (xy 118.8375 149.5355)
			)
		)
	)
	(zone
		(net 2)
		(net_name "+3V3")
		(layer "B.Cu")
		(name "$teardrop_padvia$")
		(hatch none 0.1)
		(priority 30153)
		(attr
			(teardrop
				(type padvia)
			)
		)
		(connect_pads yes
			(clearance 0)
		)
		(min_thickness 0.0254)
		(filled_areas_thickness no)
		(fill yes
			(thermal_gap 0.5)
			(thermal_bridge_width 0.5)
			(island_removal_mode 1)
			(island_area_min 10)
		)
		(polygon
			(pts
				(xy 124.295961 97.134539) (xy 124.2514 97.081815) (xy 124.211719 97.013277) (xy 124.188535 96.949711)
				(xy 124.174925 96.876625) (xy 124.175 96.779526) (xy 123.879293 96.859293) (xy 123.824526 97.18)
				(xy 123.947661 97.175545) (xy 124.054414 97.205949) (xy 124.143309 97.265231) (xy 124.154539 97.275961)
			)
		)
	)
	(zone
		(net 893)
		(net_name "Net-(J2B-TX_{DISABLE})")
		(layer "B.Cu")
		(name "$teardrop_padvia$")
		(hatch none 0.1)
		(priority 30421)
		(attr
			(teardrop
				(type padvia)
			)
		)
		(connect_pads yes
			(clearance 0)
		)
		(min_thickness 0.0254)
		(filled_areas_thickness no)
		(fill yes
			(thermal_gap 0.5)
			(thermal_bridge_width 0.5)
			(island_removal_mode 1)
			(island_area_min 10)
		)
		(polygon
			(pts
				(xy 137.9875 168.267) (xy 137.967727 168.326412) (xy 137.904453 168.382496) (xy 137.855828 168.404198)
				(xy 137.796469 168.418872) (xy 137.7845 168.420652) (xy 138.05 168.681) (xy 138.3155 168.420652)
				(xy 138.255362 168.407803) (xy 138.205478 168.387869) (xy 138.165358 168.361944) (xy 138.136345 168.332124)
				(xy 138.118854 168.300706) (xy 138.112521 168.268895) (xy 138.1125 168.267)
			)
		)
	)
	(zone
		(net 104)
		(net_name "/OCuLink/PCIe_{x4}.TX2+")
		(layer "B.Cu")
		(name "$teardrop_padvia$")
		(hatch none 0.1)
		(priority 30170)
		(attr
			(teardrop
				(type padvia)
			)
		)
		(connect_pads yes
			(clearance 0)
		)
		(min_thickness 0.0254)
		(filled_areas_thickness no)
		(fill yes
			(thermal_gap 0.5)
			(thermal_bridge_width 0.5)
			(island_removal_mode 1)
			(island_area_min 10)
		)
		(polygon
			(pts
				(xy 108.964136 160.6555) (xy 108.991741 160.668972) (xy 109.012869 160.691194) (xy 109.037335 160.762856)
				(xy 109.039562 160.90593) (xy 109.036 160.951209) (xy 109.332 160.847571) (xy 109.356422 160.527571)
				(xy 109.246399 160.532123) (xy 109.113593 160.5038) (xy 109.029763 160.475592) (xy 108.964136 160.4535)
			)
		)
	)
	(zone
		(net 99)
		(net_name "/PCIe redriver/PCIe_{O}_C.TX3-")
		(layer "B.Cu")
		(name "$teardrop_padvia$")
		(hatch none 0.1)
		(priority 30172)
		(attr
			(teardrop
				(type padvia)
			)
		)
		(connect_pads yes
			(clearance 0)
		)
		(min_thickness 0.0254)
		(filled_areas_thickness no)
		(fill yes
			(thermal_gap 0.5)
			(thermal_bridge_width 0.5)
			(island_removal_mode 1)
			(island_area_min 10)
		)
		(polygon
			(pts
				(xy 108.739154 158.570786) (xy 108.711576 158.556786) (xy 108.690537 158.534116) (xy 108.666334 158.46155)
				(xy 108.664581 158.317042) (xy 108.668 158.27417) (xy 108.372 158.377) (xy 108.346484 158.697) (xy 108.456856 158.692484)
				(xy 108.589405 158.720972) (xy 108.678943 158.751775) (xy 108.739154 158.772786)
			)
		)
	)
	(zone
		(net 1)
		(net_name "GND")
		(layer "B.Cu")
		(name "$teardrop_padvia$")
		(hatch none 0.1)
		(priority 30148)
		(attr
			(teardrop
				(type padvia)
			)
		)
		(connect_pads yes
			(clearance 0)
		)
		(min_thickness 0.0254)
		(filled_areas_thickness no)
		(fill yes
			(thermal_gap 0.5)
			(thermal_bridge_width 0.5)
			(island_removal_mode 1)
			(island_area_min 10)
		)
		(polygon
			(pts
				(xy 124.506528 149.33205) (xy 124.457261 149.373423) (xy 124.393825 149.409887) (xy 124.331102 149.432727)
				(xy 124.258755 149.446265) (xy 124.145756 149.445) (xy 124.219293 149.740707) (xy 124.54 149.803054)
				(xy 124.540228 149.681287) (xy 124.57466 149.574568) (xy 124.637791 149.484011) (xy 124.64795 149.473472)
			)
		)
	)
	(zone
		(net 717)
		(net_name "Net-(U40-SCL)")
		(layer "B.Cu")
		(name "$teardrop_padvia$")
		(hatch none 0.1)
		(priority 30621)
		(attr
			(teardrop
				(type padvia)
			)
		)
		(connect_pads yes
			(clearance 0)
		)
		(min_thickness 0.0254)
		(filled_areas_thickness no)
		(fill yes
			(thermal_gap 0.5)
			(thermal_bridge_width 0.5)
			(island_removal_mode 1)
			(island_area_min 10)
		)
		(polygon
			(pts
				(xy 196.896789 132.373588) (xy 196.959622 132.317278) (xy 197.012322 132.281961) (xy 197.079573 132.249831)
				(xy 197.190401 132.194356) (xy 197.076479 132.002272) (xy 196.855095 131.967203) (xy 196.854908 132.061392)
				(xy 196.860243 132.095373) (xy 196.866829 132.142007) (xy 196.865334 132.187417) (xy 196.848332 132.234262)
				(xy 196.808401 132.2852)
			)
		)
	)
	(zone
		(net 84)
		(net_name "/Com Express 7 MGMT/PWRBTN")
		(layer "B.Cu")
		(name "$teardrop_padvia$")
		(hatch none 0.1)
		(priority 30323)
		(attr
			(teardrop
				(type padvia)
			)
		)
		(connect_pads yes
			(clearance 0)
		)
		(min_thickness 0.0254)
		(filled_areas_thickness no)
		(fill yes
			(thermal_gap 0.5)
			(thermal_bridge_width 0.5)
			(island_removal_mode 1)
			(island_area_min 10)
		)
		(polygon
			(pts
				(xy 100.119 121.2475) (xy 100.066123 121.227779) (xy 100.021531 121.165836) (xy 100.006531 121.117362)
				(xy 99.999373 121.058175) (xy 99.999 121.04) (xy 99.698 121.31) (xy 99.999 121.58) (xy 100.003722 121.51779)
				(xy 100.016774 121.466261) (xy 100.036499 121.425671) (xy 100.061219 121.396328) (xy 100.088124 121.378989)
				(xy 100.116614 121.372538) (xy 100.119 121.3725)
			)
		)
	)
	(zone
		(net 204)
		(net_name "/Backplane/USB.D-")
		(layer "B.Cu")
		(name "$teardrop_padvia$")
		(hatch none 0.1)
		(priority 30946)
		(attr
			(teardrop
				(type padvia)
			)
		)
		(connect_pads yes
			(clearance 0)
		)
		(min_thickness 0.0254)
		(filled_areas_thickness no)
		(fill yes
			(thermal_gap 0.5)
			(thermal_bridge_width 0.5)
			(island_removal_mode 1)
			(island_area_min 10)
		)
		(polygon
			(pts
				(xy 314.04 166.7405) (xy 314.052525 166.73722) (xy 314.077501 166.734286) (xy 314.086607 166.745247)
				(xy 314.090225 166.771633) (xy 314.366 166.708) (xy 314.308351 166.583) (xy 314.220227 166.591841)
				(xy 314.120309 166.571252) (xy 314.04 166.5555)
			)
		)
	)
	(zone
		(net 577)
		(net_name "Net-(U18-EN)")
		(layer "B.Cu")
		(name "$teardrop_padvia$")
		(hatch none 0.1)
		(priority 30433)
		(attr
			(teardrop
				(type padvia)
			)
		)
		(connect_pads yes
			(clearance 0)
		)
		(min_thickness 0.0254)
		(filled_areas_thickness no)
		(fill yes
			(thermal_gap 0.5)
			(thermal_bridge_width 0.5)
			(island_removal_mode 1)
			(island_area_min 10)
		)
		(polygon
			(pts
				(xy 307.402499 121.067) (xy 307.382726 121.126412) (xy 307.319452 121.182496) (xy 307.270827 121.204198)
				(xy 307.211468 121.218872) (xy 307.199499 121.220652) (xy 307.464999 121.481) (xy 307.730499 121.220652)
				(xy 307.670361 121.207803) (xy 307.620477 121.187869) (xy 307.580357 121.161944) (xy 307.551344 121.132124)
				(xy 307.533853 121.100706) (xy 307.52752 121.068895) (xy 307.527499 121.067)
			)
		)
	)
	(zone
		(net 675)
		(net_name "Net-(U45C-GPI0)")
		(layer "B.Cu")
		(name "$teardrop_padvia$")
		(hatch none 0.1)
		(priority 30667)
		(attr
			(teardrop
				(type padvia)
			)
		)
		(connect_pads yes
			(clearance 0)
		)
		(min_thickness 0.0254)
		(filled_areas_thickness no)
		(fill yes
			(thermal_gap 0.5)
			(thermal_bridge_width 0.5)
			(island_removal_mode 1)
			(island_area_min 10)
		)
		(polygon
			(pts
				(xy 129.971792 140.996596) (xy 130.002252 140.97288) (xy 130.030253 140.963802) (xy 130.078515 140.976218)
				(xy 130.128639 141.013334) (xy 130.181528 141.053314) (xy 130.244769 141.080123) (xy 130.290707 140.859293)
				(xy 130.152143 140.685772) (xy 130.064496 140.752284) (xy 129.985248 140.813478) (xy 129.883404 140.908208)
			)
		)
	)
	(zone
		(net 125)
		(net_name "/2xUSB3.0+RJ45/P2_D-")
		(layer "B.Cu")
		(name "$teardrop_padvia$")
		(hatch none 0.1)
		(priority 30315)
		(attr
			(teardrop
				(type padvia)
			)
		)
		(connect_pads yes
			(clearance 0)
		)
		(min_thickness 0.0254)
		(filled_areas_thickness no)
		(fill yes
			(thermal_gap 0.5)
			(thermal_bridge_width 0.5)
			(island_removal_mode 1)
			(island_area_min 10)
		)
		(polygon
			(pts
				(xy 114.1875 105.831) (xy 114.182112 105.86372) (xy 114.164394 105.895774) (xy 114.138243 105.919504)
				(xy 114.10034 105.937952) (xy 114.01 105.951) (xy 114.28 106.252) (xy 114.55 105.951) (xy 114.492616 105.946315)
				(xy 114.447963 105.933521) (xy 114.415117 105.914716) (xy 114.392431 105.891649) (xy 114.372642 105.836361)
				(xy 114.3725 105.831)
			)
		)
	)
	(zone
		(net 61)
		(net_name "/OCuLink/5V_CONN0")
		(layer "B.Cu")
		(name "$teardrop_padvia$")
		(hatch none 0.1)
		(priority 30230)
		(attr
			(teardrop
				(type padvia)
			)
		)
		(connect_pads yes
			(clearance 0)
		)
		(min_thickness 0.0254)
		(filled_areas_thickness no)
		(fill yes
			(thermal_gap 0.5)
			(thermal_bridge_width 0.5)
			(island_removal_mode 1)
			(island_area_min 10)
		)
		(polygon
			(pts
				(xy 100.759323 157.25) (xy 100.787979 157.249981) (xy 100.951177 157.254437) (xy 101.082288 157.286669)
				(xy 101.161 157.08) (xy 101.060779 156.882239) (xy 100.93234 156.934003) (xy 100.858234 156.946118)
				(xy 100.759323 156.95)
			)
		)
	)
	(zone
		(net 1)
		(net_name "GND")
		(layer "B.Cu")
		(name "$teardrop_padvia$")
		(hatch none 0.1)
		(priority 30875)
		(attr
			(teardrop
				(type padvia)
			)
		)
		(connect_pads yes
			(clearance 0)
		)
		(min_thickness 0.0254)
		(filled_areas_thickness no)
		(fill yes
			(thermal_gap 0.5)
			(thermal_bridge_width 0.5)
			(island_removal_mode 1)
			(island_area_min 10)
		)
		(polygon
			(pts
				(xy 105.51 165.5475) (xy 105.476137 165.541719) (xy 105.441515 165.521254) (xy 105.419693 165.494188)
				(xy 105.404 165.454848) (xy 105.400711 165.439289) (xy 105.154 165.61) (xy 105.400711 165.780711)
				(xy 105.412301 165.74049) (xy 105.429885 165.711016) (xy 105.477468 165.677827) (xy 105.51 165.6725)
			)
		)
	)
	(zone
		(net 958)
		(net_name "/PCIe redriver/PCIe_{I}_C.RX1+")
		(layer "B.Cu")
		(name "$teardrop_padvia$")
		(hatch none 0.1)
		(priority 30179)
		(attr
			(teardrop
				(type padvia)
			)
		)
		(connect_pads yes
			(clearance 0)
		)
		(min_thickness 0.0254)
		(filled_areas_thickness no)
		(fill yes
			(thermal_gap 0.5)
			(thermal_bridge_width 0.5)
			(island_removal_mode 1)
			(island_area_min 10)
		)
		(polygon
			(pts
				(xy 197.67609 139.38516) (xy 197.679148 139.421109) (xy 197.67167 139.457809) (xy 197.622849 139.53898)
				(xy 197.511409 139.649572) (xy 197.790656 139.788933) (xy 198.038676 139.584405) (xy 197.950591 139.509669)
				(xy 197.877358 139.401402) (xy 197.825252 139.267448) (xy 197.818925 139.242325)
			)
		)
	)
	(zone
		(net 1)
		(net_name "GND")
		(layer "B.Cu")
		(name "$teardrop_padvia$")
		(hatch none 0.1)
		(priority 30674)
		(attr
			(teardrop
				(type padvia)
			)
		)
		(connect_pads yes
			(clearance 0)
		)
		(min_thickness 0.0254)
		(filled_areas_thickness no)
		(fill yes
			(thermal_gap 0.5)
			(thermal_bridge_width 0.5)
			(island_removal_mode 1)
			(island_area_min 10)
		)
		(polygon
			(pts
				(xy 124.916817 142.114795) (xy 124.866549 142.164968) (xy 124.677847 142.362075) (xy 124.841037 142.51097)
				(xy 125.062421 142.466368) (xy 125.032367 142.39363) (xy 125.010365 142.359826) (xy 124.986047 142.321555)
				(xy 124.971852 142.284275) (xy 124.975623 142.24561) (xy 125.005205 142.203183)
			)
		)
	)
	(zone
		(net 374)
		(net_name "/2xUSB3.0+RJ45/USB_2.D-")
		(layer "B.Cu")
		(name "$teardrop_padvia$")
		(hatch none 0.1)
		(priority 30588)
		(attr
			(teardrop
				(type padvia)
			)
		)
		(connect_pads yes
			(clearance 0)
		)
		(min_thickness 0.0254)
		(filled_areas_thickness no)
		(fill yes
			(thermal_gap 0.5)
			(thermal_bridge_width 0.5)
			(island_removal_mode 1)
			(island_area_min 10)
		)
		(polygon
			(pts
				(xy 152.114679 114.876793) (xy 152.233916 114.990113) (xy 152.363205 115.119205) (xy 152.528749 114.972665)
				(xy 152.532491 114.751281) (xy 152.450181 114.764466) (xy 152.422096 114.773636) (xy 152.378512 114.786992)
				(xy 152.335897 114.791836) (xy 152.292231 114.780665) (xy 152.245494 114.745978)
			)
		)
	)
	(zone
		(net 1)
		(net_name "GND")
		(layer "B.Cu")
		(name "$teardrop_padvia$")
		(hatch none 0.1)
		(priority 30475)
		(attr
			(teardrop
				(type padvia)
			)
		)
		(connect_pads yes
			(clearance 0)
		)
		(min_thickness 0.0254)
		(filled_areas_thickness no)
		(fill yes
			(thermal_gap 0.5)
			(thermal_bridge_width 0.5)
			(island_removal_mode 1)
			(island_area_min 10)
		)
		(polygon
			(pts
				(xy 102.675677 105.265) (xy 102.597765 105.260287) (xy 102.538981 105.2473) (xy 102.447949 105.205198)
				(xy 102.362778 105.1625) (xy 102.274 105.365) (xy 102.362778 105.5675) (xy 102.447947 105.524802)
				(xy 102.540782 105.482133) (xy 102.598921 105.469556) (xy 102.675677 105.465)
			)
		)
	)
	(zone
		(net 53)
		(net_name "/2xSFP+/SH")
		(layer "B.Cu")
		(name "$teardrop_padvia$")
		(hatch none 0.1)
		(priority 30236)
		(attr
			(teardrop
				(type padvia)
			)
		)
		(connect_pads yes
			(clearance 0)
		)
		(min_thickness 0.0254)
		(filled_areas_thickness no)
		(fill yes
			(thermal_gap 0.5)
			(thermal_bridge_width 0.5)
			(island_removal_mode 1)
			(island_area_min 10)
		)
		(polygon
			(pts
				(xy 109.457 169.585) (xy 109.47209 169.584663) (xy 109.512327 169.58524) (xy 109.553871 169.597054)
				(xy 109.589165 169.631633) (xy 109.610653 169.7005) (xy 109.871 169.435) (xy 109.610653 169.1695)
				(xy 109.599709 169.215938) (xy 109.58261 169.248135) (xy 109.538145 169.279578) (xy 109.47209 169.285337)
				(xy 109.457 169.285)
			)
		)
	)
	(zone
		(net 113)
		(net_name "/2xSFP+/10GKR_SFP0.TX-")
		(layer "B.Cu")
		(name "$teardrop_padvia$")
		(hatch none 0.1)
		(priority 30623)
		(attr
			(teardrop
				(type padvia)
			)
		)
		(connect_pads yes
			(clearance 0)
		)
		(min_thickness 0.0254)
		(filled_areas_thickness no)
		(fill yes
			(thermal_gap 0.5)
			(thermal_bridge_width 0.5)
			(island_removal_mode 1)
			(island_area_min 10)
		)
		(polygon
			(pts
				(xy 156.22 147.977084) (xy 156.224756 147.936299) (xy 156.238046 147.906971) (xy 156.282406 147.872311)
				(xy 156.325219 147.855729) (xy 156.410003 147.817081) (xy 156.285 147.629) (xy 156.064323 147.632143)
				(xy 156.062568 147.797771) (xy 156.06 147.977084)
			)
		)
	)
	(zone
		(net 84)
		(net_name "/Com Express 7 MGMT/PWRBTN")
		(layer "B.Cu")
		(name "$teardrop_padvia$")
		(hatch none 0.1)
		(priority 30010)
		(attr
			(teardrop
				(type padvia)
			)
		)
		(connect_pads yes
			(clearance 0)
		)
		(min_thickness 0.0254)
		(filled_areas_thickness no)
		(fill yes
			(thermal_gap 0.5)
			(thermal_bridge_width 0.5)
			(island_removal_mode 1)
			(island_area_min 10)
		)
		(polygon
			(pts
				(xy 98.776873 120.824741) (xy 98.726147 120.767116) (xy 98.691643 120.712599) (xy 98.673007 120.665039)
				(xy 98.665552 120.619331) (xy 98.679677 120.531802) (xy 98.733755 120.434859) (xy 98.858796 120.290077)
				(xy 98.940367 120.200404) (xy 99.017773 120.103055) (xy 99.082254 119.995291) (xy 99.125048 119.874372)
				(xy 98.397293 119.709293) (xy 97.806934 120.157827) (xy 97.867263 120.237549) (xy 98.167139 120.618715)
				(xy 98.330134 120.79774) (xy 98.564741 121.036873)
			)
		)
	)
	(zone
		(net 961)
		(net_name "/PCIe redriver/PCIe_{O}_C.TX2+")
		(layer "B.Cu")
		(name "$teardrop_padvia$")
		(hatch none 0.1)
		(priority 30191)
		(attr
			(teardrop
				(type padvia)
			)
		)
		(connect_pads yes
			(clearance 0)
		)
		(min_thickness 0.0254)
		(filled_areas_thickness no)
		(fill yes
			(thermal_gap 0.5)
			(thermal_bridge_width 0.5)
			(island_removal_mode 1)
			(island_area_min 10)
		)
		(polygon
			(pts
				(xy 110.660959 160.451785) (xy 110.585988 160.485771) (xy 110.494499 160.517465) (xy 110.392508 160.536344)
				(xy 110.286031 160.531888) (xy 110.265937 160.527571) (xy 110.29 160.847571) (xy 110.586 160.951473)
				(xy 110.58338 160.828999) (xy 110.59576 160.739964) (xy 110.612495 160.699243) (xy 110.636895 160.669547)
				(xy 110.660959 160.653785)
			)
		)
	)
	(zone
		(net 1)
		(net_name "GND")
		(layer "B.Cu")
		(name "$teardrop_padvia$")
		(hatch none 0.1)
		(priority 30004)
		(attr
			(teardrop
				(type padvia)
			)
		)
		(connect_pads yes
			(clearance 0)
		)
		(min_thickness 0.0254)
		(filled_areas_thickness no)
		(fill yes
			(thermal_gap 0.5)
			(thermal_bridge_width 0.5)
			(island_removal_mode 1)
			(island_area_min 10)
		)
		(polygon
			(pts
				(xy 252.75071 73.221) (xy 252.755851 73.168476) (xy 252.771841 73.115561) (xy 252.797541 73.066933)
				(xy 252.834295 73.020842) (xy 252.879792 72.980901) (xy 252.936373 72.945645) (xy 253.002505 72.917002)
				(xy 253.0802 72.894967) (xy 253.169503 72.880672) (xy 253.271325 72.875045) (xy 253.281771 72.875)
				(xy 252.510709 71.859) (xy 251.724729 72.875) (xy 251.827613 72.879817) (xy 251.9178 72.893539)
				(xy 251.995291 72.914877) (xy 252.061376 72.942833) (xy 252.116905 72.976556) (xy 252.161995 73.014806)
				(xy 252.224354 73.103227) (xy 252.250044 73.202027) (xy 252.25071 73.221)
			)
		)
	)
	(zone
		(net 229)
		(net_name "/M.2 key M #1/PCIE_{REF}.CK-")
		(layer "B.Cu")
		(name "$teardrop_padvia$")
		(hatch none 0.1)
		(priority 30530)
		(attr
			(teardrop
				(type padvia)
			)
		)
		(connect_pads yes
			(clearance 0)
		)
		(min_thickness 0.0254)
		(filled_areas_thickness no)
		(fill yes
			(thermal_gap 0.5)
			(thermal_bridge_width 0.5)
			(island_removal_mode 1)
			(island_area_min 10)
		)
		(polygon
			(pts
				(xy 207.032504 128.6155) (xy 207.07929 128.620235) (xy 207.114742 128.633379) (xy 207.162939 128.678387)
				(xy 207.187116 128.716608) (xy 207.214485 128.759773) (xy 207.251147 128.801731) (xy 207.401 128.6385)
				(xy 207.38014 128.417823) (xy 207.279466 128.422452) (xy 207.196096 128.419019) (xy 207.194035 128.418895)
				(xy 207.032504 128.4135)
			)
		)
	)
	(zone
		(net 47)
		(net_name "/2xUSB3.0+RJ45/USBSS_1.TX-")
		(layer "B.Cu")
		(name "$teardrop_padvia$")
		(hatch none 0.1)
		(priority 30964)
		(attr
			(teardrop
				(type padvia)
			)
		)
		(connect_pads yes
			(clearance 0)
		)
		(min_thickness 0.0254)
		(filled_areas_thickness no)
		(fill yes
			(thermal_gap 0.5)
			(thermal_bridge_width 0.5)
			(island_removal_mode 1)
			(island_area_min 10)
		)
		(polygon
			(pts
				(xy 100.878 104.7175) (xy 100.800085 104.732419) (xy 100.712952 104.750999) (xy 100.664747 104.751904)
				(xy 100.613729 104.742) (xy 100.552 104.867) (xy 100.827289 104.933073) (xy 100.831881 104.904902)
				(xy 100.842942 104.895157) (xy 100.865345 104.89915) (xy 100.878 104.9025)
			)
		)
	)
	(zone
		(net 203)
		(net_name "/Backplane/PCIe_{REF}.CK+")
		(layer "B.Cu")
		(name "$teardrop_padvia$")
		(hatch none 0.1)
		(priority 30995)
		(attr
			(teardrop
				(type padvia)
			)
		)
		(connect_pads yes
			(clearance 0)
		)
		(min_thickness 0.0254)
		(filled_areas_thickness no)
		(fill yes
			(thermal_gap 0.5)
			(thermal_bridge_width 0.5)
			(island_removal_mode 1)
			(island_area_min 10)
		)
		(polygon
			(pts
				(xy 314.812 164.811) (xy 314.832648 164.803802) (xy 314.864984 164.794208) (xy 314.879007 164.801035)
				(xy 314.888995 164.8225) (xy 315.138 164.71) (xy 314.888995 164.5975) (xy 314.879271 164.618676)
				(xy 314.865643 164.625731) (xy 314.832648 164.616198) (xy 314.812 164.609)
			)
		)
	)
	(zone
		(net 123)
		(net_name "/2xUSB3.0+RJ45/P1_D-")
		(layer "B.Cu")
		(name "$teardrop_padvia$")
		(hatch none 0.1)
		(priority 30022)
		(attr
			(teardrop
				(type padvia)
			)
		)
		(connect_pads yes
			(clearance 0)
		)
		(min_thickness 0.0254)
		(filled_areas_thickness no)
		(fill yes
			(thermal_gap 0.5)
			(thermal_bridge_width 0.5)
			(island_removal_mode 1)
			(island_area_min 10)
		)
		(polygon
			(pts
				(xy 105.883483 105.2675) (xy 106.030217 105.262747) (xy 106.151831 105.249479) (xy 106.345333 105.202873)
				(xy 106.487478 105.14928) (xy 106.657198 105.085716) (xy 106.881686 105.02703) (xy 106.751 104.365)
				(xy 106.08797 104.233314) (xy 106.075531 104.384626) (xy 106.092849 104.581765) (xy 106.101844 104.644561)
				(xy 106.122296 104.814799) (xy 106.122682 104.88918) (xy 106.111751 104.954029) (xy 106.085934 105.007565)
				(xy 106.041663 105.048009) (xy 105.975368 105.073581) (xy 105.883483 105.0825)
			)
		)
	)
	(zone
		(net 100)
		(net_name "/OCuLink/PCIe_{x4}.TX0+")
		(layer "B.Cu")
		(name "$teardrop_padvia$")
		(hatch none 0.1)
		(priority 30169)
		(attr
			(teardrop
				(type padvia)
			)
		)
		(connect_pads yes
			(clearance 0)
		)
		(min_thickness 0.0254)
		(filled_areas_thickness no)
		(fill yes
			(thermal_gap 0.5)
			(thermal_bridge_width 0.5)
			(island_removal_mode 1)
			(island_area_min 10)
		)
		(polygon
			(pts
				(xy 108.964136 166.6555) (xy 108.991741 166.668972) (xy 109.012869 166.691194) (xy 109.037335 166.762856)
				(xy 109.039562 166.90593) (xy 109.036 166.951209) (xy 109.332 166.847571) (xy 109.356422 166.527571)
				(xy 109.246399 166.532123) (xy 109.113593 166.5038) (xy 109.029763 166.475592) (xy 108.964136 166.4535)
			)
		)
	)
	(zone
		(net 1)
		(net_name "GND")
		(layer "B.Cu")
		(name "$teardrop_padvia$")
		(hatch none 0.1)
		(priority 30478)
		(attr
			(teardrop
				(type padvia)
			)
		)
		(connect_pads yes
			(clearance 0)
		)
		(min_thickness 0.0254)
		(filled_areas_thickness no)
		(fill yes
			(thermal_gap 0.5)
			(thermal_bridge_width 0.5)
			(island_removal_mode 1)
			(island_area_min 10)
		)
		(polygon
			(pts
				(xy 99.5 85.683323) (xy 99.495287 85.761234) (xy 99.4823 85.820018) (xy 99.440199 85.911048) (xy 99.3975 85.996221)
				(xy 99.6 86.085) (xy 99.8025 85.996221) (xy 99.759801 85.91105) (xy 99.717133 85.818217) (xy 99.704556 85.760078)
				(xy 99.7 85.683323)
			)
		)
	)
	(zone
		(net 1)
		(net_name "GND")
		(layer "B.Cu")
		(name "$teardrop_padvia$")
		(hatch none 0.1)
		(priority 30248)
		(attr
			(teardrop
				(type padvia)
			)
		)
		(connect_pads yes
			(clearance 0)
		)
		(min_thickness 0.0254)
		(filled_areas_thickness no)
		(fill yes
			(thermal_gap 0.5)
			(thermal_bridge_width 0.5)
			(island_removal_mode 1)
			(island_area_min 10)
		)
		(polygon
			(pts
				(xy 176.779323 105.51) (xy 176.9369 105.516932) (xy 177.050434 105.545456) (xy 177.092222 105.5625)
				(xy 177.181 105.36) (xy 177.092222 105.1575) (xy 176.996177 105.191883) (xy 176.894296 105.207101)
				(xy 176.779323 105.21)
			)
		)
	)
	(zone
		(net 123)
		(net_name "/2xUSB3.0+RJ45/P1_D-")
		(layer "B.Cu")
		(name "$teardrop_padvia$")
		(hatch none 0.1)
		(priority 30137)
		(attr
			(teardrop
				(type padvia)
			)
		)
		(connect_pads yes
			(clearance 0)
		)
		(min_thickness 0.0254)
		(filled_areas_thickness no)
		(fill yes
			(thermal_gap 0.5)
			(thermal_bridge_width 0.5)
			(island_removal_mode 1)
			(island_area_min 10)
		)
		(polygon
			(pts
				(xy 105.081555 105.16526) (xy 105.13346 105.120974) (xy 105.199097 105.080393) (xy 105.269077 105.050119)
				(xy 105.349786 105.027918) (xy 105.482838 105.015) (xy 105.401707 104.714293) (xy 105.101 104.633163)
				(xy 105.082961 104.789302) (xy 105.032442 104.922908) (xy 104.956326 105.028748) (xy 104.95074 105.034445)
			)
		)
	)
	(zone
		(net 1)
		(net_name "GND")
		(layer "B.Cu")
		(hatch edge 0.5)
		(priority 6)
		(connect_pads
			(clearance 0.15)
		)
		(min_thickness 0.25)
		(filled_areas_thickness no)
		(fill yes
			(thermal_gap 0.2)
			(thermal_bridge_width 0.5)
		)
		(polygon
			(pts
				(xy 306.95 78.82) (xy 286.18 78.82) (xy 286.18 76.61) (xy 301.144917 76.61) (xy 303.382205 74.41)
				(xy 306.95 74.41)
			)
		)
	)
	(zone
		(net 945)
		(net_name "/GPIO expander/GPIOEX5")
		(layer "B.Cu")
		(name "$teardrop_padvia$")
		(hatch none 0.1)
		(priority 30775)
		(attr
			(teardrop
				(type padvia)
			)
		)
		(connect_pads yes
			(clearance 0)
		)
		(min_thickness 0.0254)
		(filled_areas_thickness no)
		(fill yes
			(thermal_gap 0.5)
			(thermal_bridge_width 0.5)
			(island_removal_mode 1)
			(island_area_min 10)
		)
		(polygon
			(pts
				(xy 197.460873 132.527515) (xy 197.513382 132.481819) (xy 197.559376 132.455231) (xy 197.645824 132.434847)
				(xy 197.66116 132.433011) (xy 197.743895 132.420677) (xy 197.700707 132.199293) (xy 197.479323 132.156105)
				(xy 197.466988 132.238841) (xy 197.446651 132.336119) (xy 197.419943 132.384159) (xy 197.372485 132.439127)
			)
		)
	)
	(zone
		(net 1)
		(net_name "GND")
		(layer "B.Cu")
		(name "$teardrop_padvia$")
		(hatch none 0.1)
		(priority 30253)
		(attr
			(teardrop
				(type padvia)
			)
		)
		(connect_pads yes
			(clearance 0)
		)
		(min_thickness 0.0254)
		(filled_areas_thickness no)
		(fill yes
			(thermal_gap 0.5)
			(thermal_bridge_width 0.5)
			(island_removal_mode 1)
			(island_area_min 10)
		)
		(polygon
			(pts
				(xy 176.779323 111.01) (xy 176.9369 111.016932) (xy 177.050434 111.045456) (xy 177.092222 111.0625)
				(xy 177.181 110.86) (xy 177.092222 110.6575) (xy 176.996177 110.691883) (xy 176.894296 110.707101)
				(xy 176.779323 110.71)
			)
		)
	)
	(zone
		(net 625)
		(net_name "/PCIe redriver/TX_EQ2")
		(layer "B.Cu")
		(name "$teardrop_padvia$")
		(hatch none 0.1)
		(priority 30718)
		(attr
			(teardrop
				(type padvia)
			)
		)
		(connect_pads yes
			(clearance 0)
		)
		(min_thickness 0.0254)
		(filled_areas_thickness no)
		(fill yes
			(thermal_gap 0.5)
			(thermal_bridge_width 0.5)
			(island_removal_mode 1)
			(island_area_min 10)
		)
		(polygon
			(pts
				(xy 112.9625 143.620677) (xy 112.967318 143.551236) (xy 112.98104 143.499912) (xy 113.027755 143.42437)
				(xy 113.037299 143.412229) (xy 113.087081 143.345003) (xy 112.9 143.219) (xy 112.712919 143.345003)
				(xy 112.762701 143.412231) (xy 112.817106 143.495397) (xy 112.83219 143.548251) (xy 112.8375 143.620677)
			)
		)
	)
	(zone
		(net 370)
		(net_name "Net-(J12D-SPKR)")
		(layer "B.Cu")
		(name "$teardrop_padvia$")
		(hatch none 0.1)
		(priority 30686)
		(attr
			(teardrop
				(type padvia)
			)
		)
		(connect_pads yes
			(clearance 0)
		)
		(min_thickness 0.0254)
		(filled_areas_thickness no)
		(fill yes
			(thermal_gap 0.5)
			(thermal_bridge_width 0.5)
			(island_removal_mode 1)
			(island_area_min 10)
		)
		(polygon
			(pts
				(xy 191.4875 163.899323) (xy 191.482682 163.968763) (xy 191.46896 164.020087) (xy 191.422245 164.095628)
				(xy 191.412702 164.107768) (xy 191.362919 164.174997) (xy 191.55 164.301) (xy 191.737081 164.174997)
				(xy 191.687299 164.107769) (xy 191.632894 164.024603) (xy 191.61781 163.971748) (xy 191.6125 163.899323)
			)
		)
	)
	(zone
		(net 50)
		(net_name "Net-(C12-Pad2)")
		(layer "B.Cu")
		(name "$teardrop_padvia$")
		(hatch none 0.1)
		(priority 30018)
		(attr
			(teardrop
				(type padvia)
			)
		)
		(connect_pads yes
			(clearance 0)
		)
		(min_thickness 0.0254)
		(filled_areas_thickness no)
		(fill yes
			(thermal_gap 0.5)
			(thermal_bridge_width 0.5)
			(island_removal_mode 1)
			(island_area_min 10)
		)
		(polygon
			(pts
				(xy 138.391 105.45) (xy 138.446099 105.455385) (xy 138.502362 105.473082) (xy 138.548301 105.499175)
				(xy 138.591056 105.536973) (xy 138.625051 105.581735) (xy 138.653745 105.637901) (xy 138.675121 105.703559)
				(xy 138.689238 105.781528) (xy 138.695 105.884) (xy 139.456 105.2) (xy 138.695 104.516) (xy 138.690202 104.609999)
				(xy 138.676614 104.690331) (xy 138.65584 104.756913) (xy 138.628882 104.812009) (xy 138.596489 104.856947)
				(xy 138.560139 104.891907) (xy 138.475028 104.937214) (xy 138.391 104.95)
			)
		)
	)
	(zone
		(net 2)
		(net_name "+3V3")
		(layer "B.Cu")
		(name "$teardrop_padvia$")
		(hatch none 0.1)
		(priority 30160)
		(attr
			(teardrop
				(type padvia)
			)
		)
		(connect_pads yes
			(clearance 0)
		)
		(min_thickness 0.0254)
		(filled_areas_thickness no)
		(fill yes
			(thermal_gap 0.5)
			(thermal_bridge_width 0.5)
			(island_removal_mode 1)
			(island_area_min 10)
		)
		(polygon
			(pts
				(xy 257.243707 77.885) (xy 257.199062 77.905403) (xy 257.165515 77.924221) (xy 257.133052 77.932795)
				(xy 257.106342 77.918697) (xy 257.090054 77.8695) (xy 256.829707 78.135) (xy 257.090054 78.4005)
				(xy 257.099874 78.362407) (xy 257.115281 78.342642) (xy 257.149607 78.339648) (xy 257.199062 78.364597)
				(xy 257.243707 78.385)
			)
		)
	)
	(zone
		(net 1)
		(net_name "GND")
		(layer "B.Cu")
		(name "$teardrop_padvia$")
		(hatch none 0.1)
		(priority 30279)
		(attr
			(teardrop
				(type padvia)
			)
		)
		(connect_pads yes
			(clearance 0)
		)
		(min_thickness 0.0254)
		(filled_areas_thickness no)
		(fill yes
			(thermal_gap 0.5)
			(thermal_bridge_width 0.5)
			(island_removal_mode 1)
			(island_area_min 10)
		)
		(polygon
			(pts
				(xy 101.95 122.38) (xy 101.94977 122.368272) (xy 101.95069 122.332986) (xy 101.963174 122.297808)
				(xy 101.999014 122.270795) (xy 102.07 122.26) (xy 101.8 121.959) (xy 101.53 122.26) (xy 101.580215 122.264645)
				(xy 101.614212 122.27716) (xy 101.644973 122.314073) (xy 101.65023 122.368272) (xy 101.65 122.38)
			)
		)
	)
	(zone
		(net 878)
		(net_name "/2xSFP+/SFI1.RX+")
		(layer "B.Cu")
		(name "$teardrop_padvia$")
		(hatch none 0.1)
		(priority 30672)
		(attr
			(teardrop
				(type padvia)
			)
		)
		(connect_pads yes
			(clearance 0)
		)
		(min_thickness 0.0254)
		(filled_areas_thickness no)
		(fill yes
			(thermal_gap 0.5)
			(thermal_bridge_width 0.5)
			(island_removal_mode 1)
			(island_area_min 10)
		)
		(polygon
			(pts
				(xy 131.684988 147.95599) (xy 131.681606 147.71224) (xy 131.680677 147.62747) (xy 131.459983 147.629001)
				(xy 131.334997 147.817081) (xy 131.407182 147.84831) (xy 131.42341 147.852918) (xy 131.494228 147.882392)
				(xy 131.516271 147.911529) (xy 131.525012 147.958712)
			)
		)
	)
	(zone
		(net 53)
		(net_name "/2xSFP+/SH")
		(layer "B.Cu")
		(name "$teardrop_padvia$")
		(hatch none 0.1)
		(priority 30016)
		(attr
			(teardrop
				(type padvia)
			)
		)
		(connect_pads yes
			(clearance 0)
		)
		(min_thickness 0.0254)
		(filled_areas_thickness no)
		(fill yes
			(thermal_gap 0.5)
			(thermal_bridge_width 0.5)
			(island_removal_mode 1)
			(island_area_min 10)
		)
		(polygon
			(pts
				(xy 132.6 156.520589) (xy 132.604874 156.396824) (xy 132.618996 156.291865) (xy 132.640089 156.207229)
				(xy 132.668095 156.133643) (xy 132.746201 156.00343) (xy 132.860058 155.868796) (xy 132.962896 155.750401)
				(xy 133.073602 155.601678) (xy 132.45 155.184) (xy 131.826398 155.601678) (xy 131.970593 155.790228)
				(xy 132.039942 155.868797) (xy 132.144416 155.991075) (xy 132.226718 156.122489) (xy 132.257616 156.200049)
				(xy 132.280646 156.290005) (xy 132.295032 156.395728) (xy 132.3 156.520589)
			)
		)
	)
	(zone
		(net 155)
		(net_name "Net-(J1A-LED_D2)")
		(layer "B.Cu")
		(name "$teardrop_padvia$")
		(hatch none 0.1)
		(priority 30332)
		(attr
			(teardrop
				(type padvia)
			)
		)
		(connect_pads yes
			(clearance 0)
		)
		(min_thickness 0.0254)
		(filled_areas_thickness no)
		(fill yes
			(thermal_gap 0.5)
			(thermal_bridge_width 0.5)
			(island_removal_mode 1)
			(island_area_min 10)
		)
		(polygon
			(pts
				(xy 122.8575 100.422) (xy 122.837531 100.484866) (xy 122.811079 100.516844) (xy 122.773668 100.545358)
				(xy 122.726473 100.567882) (xy 122.668833 100.583093) (xy 122.668202 100.583202) (xy 122.92 100.861)
				(xy 123.171798 100.583202) (xy 123.116365 100.568905) (xy 123.07048 100.547825) (xy 123.032799 100.52046)
				(xy 123.005566 100.489552) (xy 122.988528 100.456265) (xy 122.982511 100.423434) (xy 122.9825 100.422)
			)
		)
	)
	(zone
		(net 1)
		(net_name "GND")
		(layer "B.Cu")
		(name "$teardrop_padvia$")
		(hatch none 0.1)
		(priority 30002)
		(attr
			(teardrop
				(type padvia)
			)
		)
		(connect_pads yes
			(clearance 0)
		)
		(min_thickness 0.0254)
		(filled_areas_thickness no)
		(fill yes
			(thermal_gap 0.5)
			(thermal_bridge_width 0.5)
			(island_removal_mode 1)
			(island_area_min 10)
		)
		(polygon
			(pts
				(xy 239.020708 73.221) (xy 239.025849 73.168476) (xy 239.041839 73.115561) (xy 239.067539 73.066933)
				(xy 239.104293 73.020842) (xy 239.14979 72.980901) (xy 239.206371 72.945645) (xy 239.272503 72.917002)
				(xy 239.350198 72.894967) (xy 239.439501 72.880672) (xy 239.541323 72.875045) (xy 239.551769 72.875)
				(xy 238.780707 71.859) (xy 237.994727 72.875) (xy 238.097611 72.879817) (xy 238.187798 72.893539)
				(xy 238.265289 72.914877) (xy 238.331374 72.942833) (xy 238.386903 72.976556) (xy 238.431993 73.014806)
				(xy 238.494352 73.103227) (xy 238.520042 73.202027) (xy 238.520708 73.221)
			)
		)
	)
	(zone
		(net 61)
		(net_name "/OCuLink/5V_CONN0")
		(layer "B.Cu")
		(name "$teardrop_padvia$")
		(hatch none 0.1)
		(priority 30079)
		(attr
			(teardrop
				(type padvia)
			)
		)
		(connect_pads yes
			(clearance 0)
		)
		(min_thickness 0.0254)
		(filled_areas_thickness no)
		(fill yes
			(thermal_gap 0.5)
			(thermal_bridge_width 0.5)
			(island_removal_mode 1)
			(island_area_min 10)
		)
		(polygon
			(pts
				(xy 103.79 153.8) (xy 103.782241 153.865906) (xy 103.747929 153.934345) (xy 103.716722 153.963454)
				(xy 103.67344 153.987231) (xy 103.596863 154.006863) (xy 103.95 154.461) (xy 104.303137 154.006863)
				(xy 104.241216 153.994106) (xy 104.192249 153.974586) (xy 104.154836 153.9498) (xy 104.127482 153.921187)
				(xy 104.095688 153.852117) (xy 104.09 153.8)
			)
		)
	)
	(zone
		(net 293)
		(net_name "/2xUSB3.0+RJ45/GbE.MDI1+")
		(layer "B.Cu")
		(name "$teardrop_padvia$")
		(hatch none 0.1)
		(priority 30651)
		(attr
			(teardrop
				(type padvia)
			)
		)
		(connect_pads yes
			(clearance 0)
		)
		(min_thickness 0.0254)
		(filled_areas_thickness no)
		(fill yes
			(thermal_gap 0.5)
			(thermal_bridge_width 0.5)
			(island_removal_mode 1)
			(island_area_min 10)
		)
		(polygon
			(pts
				(xy 170.35 163.657916) (xy 170.345244 163.697838) (xy 170.33195 163.726255) (xy 170.287871 163.758671)
				(xy 170.242738 163.773949) (xy 170.196459 163.789244) (xy 170.149997 163.812919) (xy 170.275 164.001)
				(xy 170.495677 164.001757) (xy 170.497797 163.863281) (xy 170.5 163.657916)
			)
		)
	)
	(zone
		(net 680)
		(net_name "Net-(U45C-PRTAD3)")
		(layer "B.Cu")
		(name "$teardrop_padvia$")
		(hatch none 0.1)
		(priority 30410)
		(attr
			(teardrop
				(type padvia)
			)
		)
		(connect_pads yes
			(clearance 0)
		)
		(min_thickness 0.0254)
		(filled_areas_thickness no)
		(fill yes
			(thermal_gap 0.5)
			(thermal_bridge_width 0.5)
			(island_removal_mode 1)
			(island_area_min 10)
		)
		(polygon
			(pts
				(xy 129.683 135.9975) (xy 129.623588 135.977727) (xy 129.567503 135.914453) (xy 129.545801 135.865828)
				(xy 129.531127 135.806468) (xy 129.529347 135.7945) (xy 129.269 136.06) (xy 129.529347 136.3255)
				(xy 129.542197 136.265361) (xy 129.562131 136.215477) (xy 129.588056 136.175358) (xy 129.617876 136.146345)
				(xy 129.649294 136.128854) (xy 129.681105 136.122521) (xy 129.683 136.1225)
			)
		)
	)
	(zone
		(net 1)
		(net_name "GND")
		(layer "B.Cu")
		(name "$teardrop_padvia$")
		(hatch none 0.1)
		(priority 30855)
		(attr
			(teardrop
				(type padvia)
			)
		)
		(connect_pads yes
			(clearance 0)
		)
		(min_thickness 0.0254)
		(filled_areas_thickness no)
		(fill yes
			(thermal_gap 0.5)
			(thermal_bridge_width 0.5)
			(island_removal_mode 1)
			(island_area_min 10)
		)
		(polygon
			(pts
				(xy 315.492 160.81) (xy 315.481885 160.810153) (xy 315.451169 160.80954) (xy 315.41868 160.801218)
				(xy 315.389526 160.777325) (xy 315.368809 160.73) (xy 315.136 160.91) (xy 315.368809 161.09) (xy 315.382168 161.054099)
				(xy 315.400399 161.030801) (xy 315.445725 161.011101) (xy 315.481885 161.009847) (xy 315.492 161.01)
			)
		)
	)
	(zone
		(net 380)
		(net_name "Net-(J12G-USB0_HOST_PRSNT)")
		(layer "B.Cu")
		(name "$teardrop_padvia$")
		(hatch none 0.1)
		(priority 30094)
		(attr
			(teardrop
				(type padvia)
			)
		)
		(connect_pads yes
			(clearance 0)
		)
		(min_thickness 0.0254)
		(filled_areas_thickness no)
		(fill yes
			(thermal_gap 0.5)
			(thermal_bridge_width 0.5)
			(island_removal_mode 1)
			(island_area_min 10)
		)
		(polygon
			(pts
				(xy 194.1875 162.657206) (xy 194.182685 162.739266) (xy 194.168981 162.804611) (xy 194.122424 162.897879)
				(xy 194.054214 162.976341) (xy 193.998058 163.037841) (xy 193.938199 163.116661) (xy 194.25 163.326)
				(xy 194.561801 163.116661) (xy 194.464781 162.996482) (xy 194.445786 162.976341) (xy 194.392634 162.917458)
				(xy 194.350408 162.853375) (xy 194.32255 162.770992) (xy 194.3125 162.657206)
			)
		)
	)
	(zone
		(net 2)
		(net_name "+3V3")
		(layer "B.Cu")
		(name "$teardrop_padvia$")
		(hatch none 0.1)
		(priority 30794)
		(attr
			(teardrop
				(type padvia)
			)
		)
		(connect_pads yes
			(clearance 0)
		)
		(min_thickness 0.0254)
		(filled_areas_thickness no)
		(fill yes
			(thermal_gap 0.5)
			(thermal_bridge_width 0.5)
			(island_removal_mode 1)
			(island_area_min 10)
		)
		(polygon
			(pts
				(xy 120.3375 149.500323) (xy 120.332687 149.569322) (xy 120.318999 149.620376) (xy 120.272394 149.695477)
				(xy 120.262545 149.70792) (xy 120.211919 149.775997) (xy 120.399 149.902) (xy 120.586081 149.775997)
				(xy 120.537154 149.709644) (xy 120.482791 149.626) (xy 120.467776 149.572982) (xy 120.4625 149.500323)
			)
		)
	)
	(zone
		(net 2)
		(net_name "+3V3")
		(layer "B.Cu")
		(name "$teardrop_padvia$")
		(hatch none 0.1)
		(priority 30801)
		(attr
			(teardrop
				(type padvia)
			)
		)
		(connect_pads yes
			(clearance 0)
		)
		(min_thickness 0.0254)
		(filled_areas_thickness no)
		(fill yes
			(thermal_gap 0.5)
			(thermal_bridge_width 0.5)
			(island_removal_mode 1)
			(island_area_min 10)
		)
		(polygon
			(pts
				(xy 196.120346 136.440657) (xy 196.165733 136.49285) (xy 196.192154 136.53863) (xy 196.212304 136.624689)
				(xy 196.214139 136.640453) (xy 196.226477 136.724386) (xy 196.447861 136.681198) (xy 196.491049 136.459814)
				(xy 196.409535 136.447492) (xy 196.311949 136.426788) (xy 196.263842 136.399916) (xy 196.208734 136.352269)
			)
		)
	)
	(zone
		(net 172)
		(net_name "/2xSFP+/SFI0.TX+")
		(layer "B.Cu")
		(name "$teardrop_padvia$")
		(hatch none 0.1)
		(priority 30065)
		(attr
			(teardrop
				(type padvia)
			)
		)
		(connect_pads yes
			(clearance 0)
		)
		(min_thickness 0.0254)
		(filled_areas_thickness no)
		(fill yes
			(thermal_gap 0.5)
			(thermal_bridge_width 0.5)
			(island_removal_mode 1)
			(island_area_min 10)
		)
		(polygon
			(pts
				(xy 148.491973 159.60511) (xy 148.548621 159.668573) (xy 148.587722 159.727093) (xy 148.625254 159.831212)
				(xy 148.63245 159.971683) (xy 148.633515 160.073695) (xy 148.648262 160.193889) (xy 149.070707 160.110707)
				(xy 149.153889 159.688262) (xy 148.980345 159.664451) (xy 148.885892 159.65309) (xy 148.798509 159.629692)
				(xy 148.708235 159.580554) (xy 148.60511 159.491973)
			)
		)
	)
	(zone
		(net 227)
		(net_name "/Com Express 7 Interfaces/PCIe_{B1x4}.TX0+")
		(layer "B.Cu")
		(name "$teardrop_padvia$")
		(hatch none 0.1)
		(priority 30527)
		(attr
			(teardrop
				(type padvia)
			)
		)
		(connect_pads yes
			(clearance 0)
		)
		(min_thickness 0.0254)
		(filled_areas_thickness no)
		(fill yes
			(thermal_gap 0.5)
			(thermal_bridge_width 0.5)
			(island_removal_mode 1)
			(island_area_min 10)
		)
		(polygon
			(pts
				(xy 210.682504 170.8705) (xy 210.72929 170.875235) (xy 210.764742 170.888379) (xy 210.812939 170.933387)
				(xy 210.837116 170.971608) (xy 210.864485 171.014773) (xy 210.901147 171.056731) (xy 211.051 170.8935)
				(xy 211.03014 170.672823) (xy 210.929466 170.677452) (xy 210.846096 170.674019) (xy 210.844035 170.673895)
				(xy 210.682504 170.6685)
			)
		)
	)
	(zone
		(net 2)
		(net_name "+3V3")
		(layer "B.Cu")
		(name "$teardrop_padvia$")
		(hatch none 0.1)
		(priority 30218)
		(attr
			(teardrop
				(type padvia)
			)
		)
		(connect_pads yes
			(clearance 0)
		)
		(min_thickness 0.0254)
		(filled_areas_thickness no)
		(fill yes
			(thermal_gap 0.5)
			(thermal_bridge_width 0.5)
			(island_removal_mode 1)
			(island_area_min 10)
		)
		(polygon
			(pts
				(xy 198.603475 136.062754) (xy 198.693752 136.082527) (xy 198.799509 136.148516) (xy 198.852886 136.200177)
				(xy 198.903115 136.263489) (xy 198.904685 136.265754) (xy 199.092733 136.000254) (xy 198.94004 135.734754)
				(xy 198.881421 135.798377) (xy 198.820811 135.850384) (xy 198.758886 135.891045) (xy 198.698232 135.919224)
				(xy 198.603475 135.937754)
			)
		)
	)
	(zone
		(net 2)
		(net_name "+3V3")
		(layer "B.Cu")
		(hatch edge 0.5)
		(priority 37)
		(connect_pads yes
			(clearance 0.15)
		)
		(min_thickness 0.25)
		(filled_areas_thickness no)
		(fill yes
			(thermal_gap 0.2)
			(thermal_bridge_width 0.5)
			(smoothing fillet)
			(radius 0.2)
		)
		(polygon
			(pts
				(xy 149.25 163.11) (xy 150 162.36) (xy 150.95 162.36) (xy 151.6 161.71) (xy 151.6 160.36) (xy 150.05 160.36)
				(xy 149.25 161.16) (xy 148.2 161.16) (xy 147.1 162.26) (xy 147.1 163.11)
			)
		)
	)
	(zone
		(net 974)
		(net_name "/PCIe redriver/RX_FG1")
		(layer "B.Cu")
		(name "$teardrop_padvia$")
		(hatch none 0.1)
		(priority 30613)
		(attr
			(teardrop
				(type padvia)
			)
		)
		(connect_pads yes
			(clearance 0)
		)
		(min_thickness 0.0254)
		(filled_areas_thickness no)
		(fill yes
			(thermal_gap 0.5)
			(thermal_bridge_width 0.5)
			(island_removal_mode 1)
			(island_area_min 10)
		)
		(polygon
			(pts
				(xy 191.964529 140.978374) (xy 191.958242 141.058117) (xy 191.934232 141.150097) (xy 191.906546 141.206957)
				(xy 191.866844 141.258131) (xy 191.866522 141.258457) (xy 192.200271 141.341325) (xy 192.217949 140.966551)
				(xy 192.164574 140.997345) (xy 192.126887 141.008653) (xy 192.105672 141.006218) (xy 192.093601 140.995549)
				(xy 192.089529 140.978374)
			)
		)
	)
	(zone
		(net 2)
		(net_name "+3V3")
		(layer "B.Cu")
		(name "$teardrop_padvia$")
		(hatch none 0.1)
		(priority 30287)
		(attr
			(teardrop
				(type padvia)
			)
		)
		(connect_pads yes
			(clearance 0)
		)
		(min_thickness 0.0254)
		(filled_areas_thickness no)
		(fill yes
			(thermal_gap 0.5)
			(thermal_bridge_width 0.5)
			(island_removal_mode 1)
			(island_area_min 10)
		)
		(polygon
			(pts
				(xy 218.7 129.958089) (xy 218.6953 130.008815) (xy 218.682402 130.04871) (xy 218.63697 130.109368)
				(xy 218.609375 130.134131) (xy 218.563371 130.177544) (xy 218.727 130.327) (xy 218.947677 130.305351)
				(xy 218.95484 130.20664) (xy 218.968552 130.155988) (xy 218.989812 130.071758) (xy 219 129.958089)
			)
		)
	)
	(zone
		(net 161)
		(net_name "/2xUSB3.0+RJ45/USBSS_2.RX+")
		(layer "B.Cu")
		(name "$teardrop_padvia$")
		(hatch none 0.1)
		(priority 31020)
		(attr
			(teardrop
				(type padvia)
			)
		)
		(connect_pads yes
			(clearance 0)
		)
		(min_thickness 0.0254)
		(filled_areas_thickness no)
		(fill yes
			(thermal_gap 0.5)
			(thermal_bridge_width 0.5)
			(island_removal_mode 1)
			(island_area_min 10)
		)
		(polygon
			(pts
				(xy 123.338 104.7075) (xy 123.319153 104.7124) (xy 123.285892 104.718518) (xy 123.271353 104.710159)
				(xy 123.261005 104.6875) (xy 123.012 104.8) (xy 123.261005 104.9125) (xy 123.270976 104.890283)
				(xy 123.284951 104.881669) (xy 123.319153 104.8876) (xy 123.338 104.8925)
			)
		)
	)
	(zone
		(net 229)
		(net_name "/M.2 key M #1/PCIE_{REF}.CK-")
		(layer "B.Cu")
		(name "$teardrop_padvia$")
		(hatch none 0.1)
		(priority 30299)
		(attr
			(teardrop
				(type padvia)
			)
		)
		(connect_pads yes
			(clearance 0)
		)
		(min_thickness 0.0254)
		(filled_areas_thickness no)
		(fill yes
			(thermal_gap 0.5)
			(thermal_bridge_width 0.5)
			(island_removal_mode 1)
			(island_area_min 10)
		)
		(polygon
			(pts
				(xy 175.39 105.961) (xy 175.404678 105.957463) (xy 175.434685 105.954192) (xy 175.445673 105.966143)
				(xy 175.45 105.995) (xy 176.201 105.86) (xy 175.45 105.725) (xy 175.445525 105.754204) (xy 175.434203 105.765997)
				(xy 175.404678 105.762537) (xy 175.39 105.759)
			)
		)
	)
	(zone
		(net 354)
		(net_name "Net-(J12D-~{LPC_DRQ1}{slash}~{ESPI_ALERT1})")
		(layer "B.Cu")
		(name "$teardrop_padvia$")
		(hatch none 0.1)
		(priority 30682)
		(attr
			(teardrop
				(type padvia)
			)
		)
		(connect_pads yes
			(clearance 0)
		)
		(min_thickness 0.0254)
		(filled_areas_thickness no)
		(fill yes
			(thermal_gap 0.5)
			(thermal_bridge_width 0.5)
			(island_removal_mode 1)
			(island_area_min 10)
		)
		(polygon
			(pts
				(xy 179.5375 165.299323) (xy 179.532682 165.368763) (xy 179.51896 165.420087) (xy 179.472245 165.495628)
				(xy 179.462702 165.507768) (xy 179.412919 165.574997) (xy 179.6 165.701) (xy 179.787081 165.574997)
				(xy 179.737299 165.507769) (xy 179.682894 165.424603) (xy 179.66781 165.371748) (xy 179.6625 165.299323)
			)
		)
	)
	(zone
		(net 57)
		(net_name "/USB-C console/FTDI_VCCIO")
		(layer "B.Cu")
		(name "$teardrop_padvia$")
		(hatch none 0.1)
		(priority 30208)
		(attr
			(teardrop
				(type padvia)
			)
		)
		(connect_pads yes
			(clearance 0)
		)
		(min_thickness 0.0254)
		(filled_areas_thickness no)
		(fill yes
			(thermal_gap 0.5)
			(thermal_bridge_width 0.5)
			(island_removal_mode 1)
			(island_area_min 10)
		)
		(polygon
			(pts
				(xy 111.962 70.49) (xy 111.97887 70.489662) (xy 112.023826 70.490241) (xy 112.071169 70.502059)
				(xy 112.113573 70.536638) (xy 112.143708 70.6055) (xy 112.401 70.34) (xy 112.143708 70.0745) (xy 112.128151 70.119269)
				(xy 112.107435 70.150885) (xy 112.056299 70.183619) (xy 111.97887 70.190338) (xy 111.962 70.19)
			)
		)
	)
	(zone
		(net 210)
		(net_name "/Com Express 7 Interfaces/PCIe_{B1x4}.RX3+")
		(layer "B.Cu")
		(name "$teardrop_padvia$")
		(hatch none 0.1)
		(priority 30497)
		(attr
			(teardrop
				(type padvia)
			)
		)
		(connect_pads yes
			(clearance 0)
		)
		(min_thickness 0.0254)
		(filled_areas_thickness no)
		(fill yes
			(thermal_gap 0.5)
			(thermal_bridge_width 0.5)
			(island_removal_mode 1)
			(island_area_min 10)
		)
		(polygon
			(pts
				(xy 204.4795 161.032504) (xy 204.474765 161.07929) (xy 204.461621 161.114742) (xy 204.416613 161.162939)
				(xy 204.378393 161.187115) (xy 204.335226 161.214484) (xy 204.293268 161.251147) (xy 204.4565 161.401)
				(xy 204.677177 161.38014) (xy 204.672548 161.279469) (xy 204.67598 161.196102) (xy 204.676105 161.194035)
				(xy 204.6815 161.032504)
			)
		)
	)
	(zone
		(net 189)
		(net_name "/OCuLink/PCIe_{x4}.RX1-")
		(layer "B.Cu")
		(name "$teardrop_padvia$")
		(hatch none 0.1)
		(priority 30509)
		(attr
			(teardrop
				(type padvia)
			)
		)
		(connect_pads yes
			(clearance 0)
		)
		(min_thickness 0.0254)
		(filled_areas_thickness no)
		(fill yes
			(thermal_gap 0.5)
			(thermal_bridge_width 0.5)
			(island_removal_mode 1)
			(island_area_min 10)
		)
		(polygon
			(pts
				(xy 99.397496 164.0595) (xy 99.35071 164.054765) (xy 99.315258 164.041621) (xy 99.26706 163.996613)
				(xy 99.242884 163.958392) (xy 99.215514 163.915225) (xy 99.178852 163.873268) (xy 99.029 164.0365)
				(xy 99.04986 164.257177) (xy 99.150531 164.252548) (xy 99.233897 164.25598) (xy 99.235964 164.256105)
				(xy 99.397496 164.2615)
			)
		)
	)
	(zone
		(net 195)
		(net_name "/OCuLink/PCIe_{x4}.RX2-")
		(layer "B.Cu")
		(name "$teardrop_padvia$")
		(hatch none 0.1)
		(priority 30508)
		(attr
			(teardrop
				(type padvia)
			)
		)
		(connect_pads yes
			(clearance 0)
		)
		(min_thickness 0.0254)
		(filled_areas_thickness no)
		(fill yes
			(thermal_gap 0.5)
			(thermal_bridge_width 0.5)
			(island_removal_mode 1)
			(island_area_min 10)
		)
		(polygon
			(pts
				(xy 99.392496 159.5545) (xy 99.34571 159.549765) (xy 99.310258 159.536621) (xy 99.26206 159.491613)
				(xy 99.237884 159.453392) (xy 99.210514 159.410225) (xy 99.173852 159.368268) (xy 99.024 159.5315)
				(xy 99.04486 159.752177) (xy 99.145531 159.747548) (xy 99.228897 159.75098) (xy 99.230964 159.751105)
				(xy 99.392496 159.7565)
			)
		)
	)
	(zone
		(net 357)
		(net_name "/Com Express 7 MGMT/SMBus.SCL")
		(layer "B.Cu")
		(name "$teardrop_padvia$")
		(hatch none 0.1)
		(priority 30759)
		(attr
			(teardrop
				(type padvia)
			)
		)
		(connect_pads yes
			(clearance 0)
		)
		(min_thickness 0.0254)
		(filled_areas_thickness no)
		(fill yes
			(thermal_gap 0.5)
			(thermal_bridge_width 0.5)
			(island_removal_mode 1)
			(island_area_min 10)
		)
		(polygon
			(pts
				(xy 109.632485 163.290873) (xy 109.678181 163.343382) (xy 109.704768 163.389376) (xy 109.725152 163.475825)
				(xy 109.726988 163.491158) (xy 109.739323 163.573895) (xy 109.960707 163.530707) (xy 110.003895 163.309323)
				(xy 109.921158 163.296988) (xy 109.82388 163.276651) (xy 109.77584 163.249943) (xy 109.720873 163.202485)
			)
		)
	)
	(zone
		(net 96)
		(net_name "/OCuLink/PCIe_{x4}.TX1-")
		(layer "B.Cu")
		(name "$teardrop_padvia$")
		(hatch none 0.1)
		(priority 31011)
		(attr
			(teardrop
				(type padvia)
			)
		)
		(connect_pads yes
			(clearance 0)
		)
		(min_thickness 0.0254)
		(filled_areas_thickness no)
		(fill yes
			(thermal_gap 0.5)
			(thermal_bridge_width 0.5)
			(island_removal_mode 1)
			(island_area_min 10)
		)
		(polygon
			(pts
				(xy 104.708 164.511) (xy 104.687352 164.518199) (xy 104.655017 164.527792) (xy 104.640994 164.520965)
				(xy 104.631005 164.4995) (xy 104.382 164.612) (xy 104.631005 164.7245) (xy 104.64073 164.703324)
				(xy 104.654358 164.696269) (xy 104.687352 164.705801) (xy 104.708 164.713)
			)
		)
	)
	(zone
		(net 969)
		(net_name "/M.2 key M #1/M2_3V3")
		(layer "B.Cu")
		(name "$teardrop_padvia$")
		(hatch none 0.1)
		(priority 30269)
		(attr
			(teardrop
				(type padvia)
			)
		)
		(connect_pads yes
			(clearance 0)
		)
		(min_thickness 0.0254)
		(filled_areas_thickness no)
		(fill yes
			(thermal_gap 0.5)
			(thermal_bridge_width 0.5)
			(island_removal_mode 1)
			(island_area_min 10)
		)
		(polygon
			(pts
				(xy 178.260677 92.96) (xy 178.103106 92.953069) (xy 177.989578 92.924549) (xy 177.947778 92.9075)
				(xy 177.859 93.11) (xy 177.947778 93.3125) (xy 178.043817 93.278118) (xy 178.145689 93.2629) (xy 178.260677 93.26)
			)
		)
	)
	(zone
		(net 273)
		(net_name "/M.2 key M #2/PCIE_{REF}.CK+")
		(layer "B.Cu")
		(name "$teardrop_padvia$")
		(hatch none 0.1)
		(priority 30500)
		(attr
			(teardrop
				(type padvia)
			)
		)
		(connect_pads yes
			(clearance 0)
		)
		(min_thickness 0.0254)
		(filled_areas_thickness no)
		(fill yes
			(thermal_gap 0.5)
			(thermal_bridge_width 0.5)
			(island_removal_mode 1)
			(island_area_min 10)
		)
		(polygon
			(pts
				(xy 260.6045 136.632504) (xy 260.599765 136.67929) (xy 260.586621 136.714742) (xy 260.541613 136.762939)
				(xy 260.503393 136.787115) (xy 260.460226 136.814484) (xy 260.418268 136.851147) (xy 260.5815 137.001)
				(xy 260.802177 136.98014) (xy 260.797548 136.879469) (xy 260.80098 136.796102) (xy 260.801105 136.794035)
				(xy 260.8065 136.632504)
			)
		)
	)
	(zone
		(net 2)
		(net_name "+3V3")
		(layer "B.Cu")
		(name "$teardrop_padvia$")
		(hatch none 0.1)
		(priority 30926)
		(attr
			(teardrop
				(type padvia)
			)
		)
		(connect_pads yes
			(clearance 0)
		)
		(min_thickness 0.0254)
		(filled_areas_thickness no)
		(fill yes
			(thermal_gap 0.5)
			(thermal_bridge_width 0.5)
			(island_removal_mode 1)
			(island_area_min 10)
		)
		(polygon
			(pts
				(xy 193.069306 133.389616) (xy 193.073946 133.394115) (xy 193.098265 133.426284) (xy 193.100835 133.449908)
				(xy 193.089395 133.480191) (xy 193.459628 133.690137) (xy 193.246708 133.319313) (xy 193.219872 133.330846)
				(xy 193.198332 133.330724) (xy 193.161999 133.305666) (xy 193.157693 133.301229)
			)
		)
	)
	(zone
		(net 1)
		(net_name "GND")
		(layer "B.Cu")
		(name "$teardrop_padvia$")
		(hatch none 0.1)
		(priority 30785)
		(attr
			(teardrop
				(type padvia)
			)
		)
		(connect_pads yes
			(clearance 0)
		)
		(min_thickness 0.0254)
		(filled_areas_thickness no)
		(fill yes
			(thermal_gap 0.5)
			(thermal_bridge_width 0.5)
			(island_removal_mode 1)
			(island_area_min 10)
		)
		(polygon
			(pts
				(xy 124.207515 96.099127) (xy 124.161819 96.046618) (xy 124.135231 96.000623) (xy 124.114847 95.914175)
				(xy 124.113011 95.89884) (xy 124.100677 95.816105) (xy 123.879293 95.859293) (xy 123.836105 96.080677)
				(xy 123.91884 96.093011) (xy 124.016119 96.113349) (xy 124.064159 96.140057) (xy 124.119127 96.187515)
			)
		)
	)
	(zone
		(net 262)
		(net_name "/Com Express 7 Interfaces/PCIe_{B2Bx4}.RX0-")
		(layer "B.Cu")
		(name "$teardrop_padvia$")
		(hatch none 0.1)
		(priority 30305)
		(attr
			(teardrop
				(type padvia)
			)
		)
		(connect_pads yes
			(clearance 0)
		)
		(min_thickness 0.0254)
		(filled_areas_thickness no)
		(fill yes
			(thermal_gap 0.5)
			(thermal_bridge_width 0.5)
			(island_removal_mode 1)
			(island_area_min 10)
		)
		(polygon
			(pts
				(xy 175.39 103.461) (xy 175.404678 103.457463) (xy 175.434685 103.454192) (xy 175.445673 103.466143)
				(xy 175.45 103.495) (xy 176.201 103.36) (xy 175.45 103.225) (xy 175.445525 103.254204) (xy 175.434203 103.265997)
				(xy 175.404678 103.262537) (xy 175.39 103.259)
			)
		)
	)
	(zone
		(net 102)
		(net_name "/OCuLink/PCIe_{x4}.TX1+")
		(layer "B.Cu")
		(name "$teardrop_padvia$")
		(hatch none 0.1)
		(priority 31015)
		(attr
			(teardrop
				(type padvia)
			)
		)
		(connect_pads yes
			(clearance 0)
		)
		(min_thickness 0.0254)
		(filled_areas_thickness no)
		(fill yes
			(thermal_gap 0.5)
			(thermal_bridge_width 0.5)
			(island_removal_mode 1)
			(island_area_min 10)
		)
		(polygon
			(pts
				(xy 104.708 165.011) (xy 104.687352 165.018199) (xy 104.655017 165.027792) (xy 104.640994 165.020965)
				(xy 104.631005 164.9995) (xy 104.382 165.112) (xy 104.631005 165.2245) (xy 104.64073 165.203324)
				(xy 104.654358 165.196269) (xy 104.687352 165.205801) (xy 104.708 165.213)
			)
		)
	)
	(zone
		(net 78)
		(net_name "+1V8")
		(layer "B.Cu")
		(name "$teardrop_padvia$")
		(hatch none 0.1)
		(priority 30361)
		(attr
			(teardrop
				(type padvia)
			)
		)
		(connect_pads yes
			(clearance 0)
		)
		(min_thickness 0.0254)
		(filled_areas_thickness no)
		(fill yes
			(thermal_gap 0.5)
			(thermal_bridge_width 0.5)
			(island_removal_mode 1)
			(island_area_min 10)
		)
		(polygon
			(pts
				(xy 158.3175 139.922) (xy 158.297531 139.984866) (xy 158.271079 140.016844) (xy 158.233668 140.045358)
				(xy 158.186473 140.067882) (xy 158.128833 140.083093) (xy 158.128202 140.083202) (xy 158.38 140.361)
				(xy 158.631798 140.083202) (xy 158.576365 140.068905) (xy 158.53048 140.047825) (xy 158.492799 140.02046)
				(xy 158.465566 139.989552) (xy 158.448528 139.956265) (xy 158.442511 139.923434) (xy 158.4425 139.922)
			)
		)
	)
	(zone
		(net 78)
		(net_name "+1V8")
		(layer "B.Cu")
		(name "$teardrop_padvia$")
		(hatch none 0.1)
		(priority 30704)
		(attr
			(teardrop
				(type padvia)
			)
		)
		(connect_pads yes
			(clearance 0)
		)
		(min_thickness 0.0254)
		(filled_areas_thickness no)
		(fill yes
			(thermal_gap 0.5)
			(thermal_bridge_width 0.5)
			(island_removal_mode 1)
			(island_area_min 10)
		)
		(polygon
			(pts
				(xy 140.1575 139.959323) (xy 140.152682 140.028763) (xy 140.13896 140.080087) (xy 140.092245 140.155628)
				(xy 140.082702 140.167768) (xy 140.032919 140.234997) (xy 140.22 140.361) (xy 140.407081 140.234997)
				(xy 140.357299 140.167769) (xy 140.302894 140.084603) (xy 140.28781 140.031748) (xy 140.2825 139.959323)
			)
		)
	)
	(zone
		(net 713)
		(net_name "Net-(U39-SCL)")
		(layer "B.Cu")
		(name "$teardrop_padvia$")
		(hatch none 0.1)
		(priority 30084)
		(attr
			(teardrop
				(type padvia)
			)
		)
		(connect_pads yes
			(clearance 0)
		)
		(min_thickness 0.0254)
		(filled_areas_thickness no)
		(fill yes
			(thermal_gap 0.5)
			(thermal_bridge_width 0.5)
			(island_removal_mode 1)
			(island_area_min 10)
		)
		(polygon
			(pts
				(xy 122.825546 146.922842) (xy 122.866092 146.88913) (xy 122.90357 146.871208) (xy 122.935095 146.866848)
				(xy 122.965173 146.871989) (xy 123.029979 146.910464) (xy 123.096123 146.973084) (xy 123.191535 147.060648)
				(xy 123.246919 147.096448) (xy 123.309446 147.120589) (xy 123.400707 146.759293) (xy 123.182161 146.457698)
				(xy 123.166716 146.468826) (xy 122.954858 146.62847) (xy 122.737158 146.834454)
			)
		)
	)
	(zone
		(net 379)
		(net_name "Net-(J12D-~{ESPI_EN})")
		(layer "B.Cu")
		(name "$teardrop_padvia$")
		(hatch none 0.1)
		(priority 30717)
		(attr
			(teardrop
				(type padvia)
			)
		)
		(connect_pads yes
			(clearance 0)
		)
		(min_thickness 0.0254)
		(filled_areas_thickness no)
		(fill yes
			(thermal_gap 0.5)
			(thermal_bridge_width 0.5)
			(island_removal_mode 1)
			(island_area_min 10)
		)
		(polygon
			(pts
				(xy 198.1125 161.900677) (xy 198.117318 161.831236) (xy 198.13104 161.779912) (xy 198.177755 161.70437)
				(xy 198.187299 161.692229) (xy 198.237081 161.625003) (xy 198.05 161.499) (xy 197.862919 161.625003)
				(xy 197.912701 161.692231) (xy 197.967106 161.775397) (xy 197.98219 161.828251) (xy 197.9875 161.900677)
			)
		)
	)
	(zone
		(net 194)
		(net_name "/OCuLink/PCIe_{x4}.RX2+")
		(layer "B.Cu")
		(name "$teardrop_padvia$")
		(hatch none 0.1)
		(priority 30835)
		(attr
			(teardrop
				(type padvia)
			)
		)
		(connect_pads yes
			(clearance 0)
		)
		(min_thickness 0.0254)
		(filled_areas_thickness no)
		(fill yes
			(thermal_gap 0.5)
			(thermal_bridge_width 0.5)
			(island_removal_mode 1)
			(island_area_min 10)
		)
		(polygon
			(pts
				(xy 191.314266 135.144655) (xy 191.328491 135.150455) (xy 191.350969 135.161827) (xy 191.351279 135.173767)
				(xy 191.337076 135.192816) (xy 191.691861 135.457904) (xy 191.706958 135.296225) (xy 191.610467 135.212858)
				(xy 191.524258 135.093627) (xy 191.457101 135.00182)
			)
		)
	)
	(zone
		(net 314)
		(net_name "/2xUSB3.0+RJ45/FLG_1")
		(layer "B.Cu")
		(name "$teardrop_padvia$")
		(hatch none 0.1)
		(priority 30765)
		(attr
			(teardrop
				(type padvia)
			)
		)
		(connect_pads yes
			(clearance 0)
		)
		(min_thickness 0.0254)
		(filled_areas_thickness no)
		(fill yes
			(thermal_gap 0.5)
			(thermal_bridge_width 0.5)
			(island_removal_mode 1)
			(island_area_min 10)
		)
		(polygon
			(pts
				(xy 122.290873 88.387515) (xy 122.343382 88.341819) (xy 122.389376 88.315231) (xy 122.475824 88.294847)
				(xy 122.49116 88.293011) (xy 122.573895 88.280677) (xy 122.530707 88.059293) (xy 122.309323 88.016105)
				(xy 122.296988 88.098841) (xy 122.276651 88.196119) (xy 122.249943 88.244159) (xy 122.202485 88.299127)
			)
		)
	)
	(zone
		(net 271)
		(net_name "/M.2 key M #2/PCIE_{REF}.CK-")
		(layer "B.Cu")
		(name "$teardrop_padvia$")
		(hatch none 0.1)
		(priority 30502)
		(attr
			(teardrop
				(type padvia)
			)
		)
		(connect_pads yes
			(clearance 0)
		)
		(min_thickness 0.0254)
		(filled_areas_thickness no)
		(fill yes
			(thermal_gap 0.5)
			(thermal_bridge_width 0.5)
			(island_removal_mode 1)
			(island_area_min 10)
		)
		(polygon
			(pts
				(xy 299.153 75.127139) (xy 299.148265 75.173925) (xy 299.135121 75.209377) (xy 299.090113 75.257574)
				(xy 299.051893 75.28175) (xy 299.008726 75.309119) (xy 298.966768 75.345782) (xy 299.13 75.495635)
				(xy 299.350677 75.474775) (xy 299.346048 75.374104) (xy 299.34948 75.290737) (xy 299.349605 75.28867)
				(xy 299.355 75.127139)
			)
		)
	)
	(zone
		(net 254)
		(net_name "/Com Express 7 Interfaces/PCIe_{B2Bx4}.RX1+")
		(layer "B.Cu")
		(name "$teardrop_padvia$")
		(hatch none 0.1)
		(priority 30301)
		(attr
			(teardrop
				(type padvia)
			)
		)
		(connect_pads yes
			(clearance 0)
		)
		(min_thickness 0.0254)
		(filled_areas_thickness no)
		(fill yes
			(thermal_gap 0.5)
			(thermal_bridge_width 0.5)
			(island_removal_mode 1)
			(island_area_min 10)
		)
		(polygon
			(pts
				(xy 175.39 99.961) (xy 175.404678 99.957463) (xy 175.434685 99.954192) (xy 175.445673 99.966143)
				(xy 175.45 99.995) (xy 176.201 99.86) (xy 175.45 99.725) (xy 175.445525 99.754204) (xy 175.434203 99.765997)
				(xy 175.404678 99.762537) (xy 175.39 99.759)
			)
		)
	)
	(zone
		(net 380)
		(net_name "Net-(J12G-USB0_HOST_PRSNT)")
		(layer "B.Cu")
		(name "$teardrop_padvia$")
		(hatch none 0.1)
		(priority 30636)
		(attr
			(teardrop
				(type padvia)
			)
		)
		(connect_pads yes
			(clearance 0)
		)
		(min_thickness 0.0254)
		(filled_areas_thickness no)
		(fill yes
			(thermal_gap 0.5)
			(thermal_bridge_width 0.5)
			(island_removal_mode 1)
			(island_area_min 10)
		)
		(polygon
			(pts
				(xy 195.948373 160.140015) (xy 195.999759 160.095242) (xy 196.045587 160.06742) (xy 196.1413 160.038751)
				(xy 196.198391 160.025547) (xy 196.265074 160.001548) (xy 196.175707 159.799293) (xy 195.954323 159.756105)
				(xy 195.943185 159.856886) (xy 195.929012 159.950961) (xy 195.904876 159.998357) (xy 195.859985 160.051627)
			)
		)
	)
	(zone
		(net 1)
		(net_name "GND")
		(layer "B.Cu")
		(name "$teardrop_padvia$")
		(hatch none 0.1)
		(priority 30150)
		(attr
			(teardrop
				(type padvia)
			)
		)
		(connect_pads yes
			(clearance 0)
		)
		(min_thickness 0.0254)
		(filled_areas_thickness no)
		(fill yes
			(thermal_gap 0.5)
			(thermal_bridge_width 0.5)
			(island_removal_mode 1)
			(island_area_min 10)
		)
		(polygon
			(pts
				(xy 114.333223 76.298224) (xy 114.316523 76.340161) (xy 114.307104 76.37302) (xy 114.287719 76.400445)
				(xy 114.249108 76.413938) (xy 114.182008 76.405) (xy 114.214292 76.725707) (xy 114.509999 76.823078)
				(xy 114.512526 76.775389) (xy 114.523799 76.740199) (xy 114.563212 76.699173) (xy 114.626648 76.676839)
				(xy 114.660897 76.666988) (xy 114.686775 76.651776)
			)
		)
	)
	(zone
		(net 1)
		(net_name "GND")
		(layer "B.Cu")
		(name "$teardrop_padvia$")
		(hatch none 0.1)
		(priority 30251)
		(attr
			(teardrop
				(type padvia)
			)
		)
		(connect_pads yes
			(clearance 0)
		)
		(min_thickness 0.0254)
		(filled_areas_thickness no)
		(fill yes
			(thermal_gap 0.5)
			(thermal_bridge_width 0.5)
			(island_removal_mode 1)
			(island_area_min 10)
		)
		(polygon
			(pts
				(xy 176.779323 111.51) (xy 176.9369 111.516932) (xy 177.050434 111.545456) (xy 177.092222 111.5625)
				(xy 177.181 111.36) (xy 177.092222 111.1575) (xy 176.996177 111.191883) (xy 176.894296 111.207101)
				(xy 176.779323 111.21)
			)
		)
	)
	(zone
		(net 81)
		(net_name "/Misc/FAN_12V")
		(layer "B.Cu")
		(name "$teardrop_padvia$")
		(hatch none 0.1)
		(priority 30007)
		(attr
			(teardrop
				(type padvia)
			)
		)
		(connect_pads yes
			(clearance 0)
		)
		(min_thickness 0.0254)
		(filled_areas_thickness no)
		(fill yes
			(thermal_gap 0.5)
			(thermal_bridge_width 0.5)
			(island_removal_mode 1)
			(island_area_min 10)
		)
		(polygon
			(pts
				(xy 236.490707 73.204379) (xy 236.49597 73.121131) (xy 236.512813 73.031151) (xy 236.539953 72.944539)
				(xy 236.579507 72.856529) (xy 236.626623 72.778013) (xy 236.685642 72.70154) (xy 236.750732 72.634728)
				(xy 236.82719 72.572019) (xy 236.959928 72.490568) (xy 236.240707 71.859) (xy 235.521486 72.490568)
				(xy 235.683574 72.594426) (xy 235.811033 72.71958) (xy 235.905385 72.863236) (xy 235.965949 73.02086)
				(xy 235.990312 73.181986) (xy 235.990707 73.204379)
			)
		)
	)
	(zone
		(net 285)
		(net_name "/2xUSB3.0+RJ45/GbE.MDI3-")
		(layer "B.Cu")
		(name "$teardrop_padvia$")
		(hatch none 0.1)
		(priority 30647)
		(attr
			(teardrop
				(type padvia)
			)
		)
		(connect_pads yes
			(clearance 0)
		)
		(min_thickness 0.0254)
		(filled_areas_thickness no)
		(fill yes
			(thermal_gap 0.5)
			(thermal_bridge_width 0.5)
			(island_removal_mode 1)
			(island_area_min 10)
		)
		(polygon
			(pts
				(xy 172.65 161.542084) (xy 172.654756 161.502162) (xy 172.66805 161.473745) (xy 172.712129 161.441329)
				(xy 172.757262 161.42605) (xy 172.803541 161.410756) (xy 172.850003 161.387081) (xy 172.725 161.199)
				(xy 172.504323 161.198242) (xy 172.502203 161.336699) (xy 172.5 161.542084)
			)
		)
	)
	(zone
		(net 78)
		(net_name "+1V8")
		(layer "B.Cu")
		(name "$teardrop_padvia$")
		(hatch none 0.1)
		(priority 30366)
		(attr
			(teardrop
				(type padvia)
			)
		)
		(connect_pads yes
			(clearance 0)
		)
		(min_thickness 0.0254)
		(filled_areas_thickness no)
		(fill yes
			(thermal_gap 0.5)
			(thermal_bridge_width 0.5)
			(island_removal_mode 1)
			(island_area_min 10)
		)
		(polygon
			(pts
				(xy 158.4425 139.798) (xy 158.462469 139.735134) (xy 158.488921 139.703156) (xy 158.526332 139.674642)
				(xy 158.573527 139.652118) (xy 158.631167 139.636907) (xy 158.631798 139.636798) (xy 158.38 139.359)
				(xy 158.128202 139.636798) (xy 158.183635 139.651095) (xy 158.22952 139.672175) (xy 158.267201 139.69954)
				(xy 158.294434 139.730448) (xy 158.311472 139.763735) (xy 158.317489 139.796566) (xy 158.3175 139.798)
			)
		)
	)
	(zone
		(net 866)
		(net_name "/Backplane/PCIe_{x2}.TX0+")
		(layer "B.Cu")
		(name "$teardrop_padvia$")
		(hatch none 0.1)
		(priority 31013)
		(attr
			(teardrop
				(type padvia)
			)
		)
		(connect_pads yes
			(clearance 0)
		)
		(min_thickness 0.0254)
		(filled_areas_thickness no)
		(fill yes
			(thermal_gap 0.5)
			(thermal_bridge_width 0.5)
			(island_removal_mode 1)
			(island_area_min 10)
		)
		(polygon
			(pts
				(xy 314.69 159.809) (xy 314.669352 159.816199) (xy 314.637017 159.825792) (xy 314.622994 159.818965)
				(xy 314.613005 159.7975) (xy 314.364 159.91) (xy 314.613005 160.0225) (xy 314.62273 160.001324)
				(xy 314.636358 159.994269) (xy 314.669352 160.003801) (xy 314.69 160.011)
			)
		)
	)
	(zone
		(net 2)
		(net_name "+3V3")
		(layer "B.Cu")
		(name "$teardrop_padvia$")
		(hatch none 0.1)
		(priority 30790)
		(attr
			(teardrop
				(type padvia)
			)
		)
		(connect_pads yes
			(clearance 0)
		)
		(min_thickness 0.0254)
		(filled_areas_thickness no)
		(fill yes
			(thermal_gap 0.5)
			(thermal_bridge_width 0.5)
			(island_removal_mode 1)
			(island_area_min 10)
		)
		(polygon
			(pts
				(xy 114.3385 149.500323) (xy 114.333687 149.569322) (xy 114.319999 149.620376) (xy 114.273394 149.695477)
				(xy 114.263545 149.70792) (xy 114.212919 149.775997) (xy 114.4 149.902) (xy 114.587081 149.775997)
				(xy 114.538154 149.709644) (xy 114.483791 149.626) (xy 114.468776 149.572982) (xy 114.4635 149.500323)
			)
		)
	)
	(zone
		(net 578)
		(net_name "/Power/PG_{1V0}")
		(layer "B.Cu")
		(name "$teardrop_padvia$")
		(hatch none 0.1)
		(priority 30322)
		(attr
			(teardrop
				(type padvia)
			)
		)
		(connect_pads yes
			(clearance 0)
		)
		(min_thickness 0.0254)
		(filled_areas_thickness no)
		(fill yes
			(thermal_gap 0.5)
			(thermal_bridge_width 0.5)
			(island_removal_mode 1)
			(island_area_min 10)
		)
		(polygon
			(pts
				(xy 310.938 118.5975) (xy 310.877868 118.577798) (xy 310.820088 118.514492) (xy 310.796617 118.465147)
				(xy 310.779778 118.404932) (xy 310.776798 118.388202) (xy 310.499 118.64) (xy 310.776798 118.891798)
				(xy 310.811395 118.802087) (xy 310.869685 118.743812) (xy 310.904369 118.727849) (xy 310.937557 118.722501)
				(xy 310.938 118.7225)
			)
		)
	)
	(zone
		(net 290)
		(net_name "/2xUSB3.0+RJ45/GbE.MDI2+")
		(layer "B.Cu")
		(name "$teardrop_padvia$")
		(hatch none 0.1)
		(priority 30657)
		(attr
			(teardrop
				(type padvia)
			)
		)
		(connect_pads yes
			(clearance 0)
		)
		(min_thickness 0.0254)
		(filled_areas_thickness no)
		(fill yes
			(thermal_gap 0.5)
			(thermal_bridge_width 0.5)
			(island_removal_mode 1)
			(island_area_min 10)
		)
		(polygon
			(pts
				(xy 166.3 150.142084) (xy 166.297797 149.936718) (xy 166.295677 149.798242) (xy 166.075 149.799)
				(xy 165.949997 149.987081) (xy 166.026138 150.020995) (xy 166.042738 150.02605) (xy 166.084281 150.039844)
				(xy 166.118398 150.059262) (xy 166.141501 150.091083) (xy 166.15 150.142084)
			)
		)
	)
	(zone
		(net 2)
		(net_name "+3V3")
		(layer "B.Cu")
		(name "$teardrop_padvia$")
		(hatch none 0.1)
		(priority 30078)
		(attr
			(teardrop
				(type padvia)
			)
		)
		(connect_pads yes
			(clearance 0)
		)
		(min_thickness 0.0254)
		(filled_areas_thickness no)
		(fill yes
			(thermal_gap 0.5)
			(thermal_bridge_width 0.5)
			(island_removal_mode 1)
			(island_area_min 10)
		)
		(polygon
			(pts
				(xy 218.7 128.19) (xy 218.693061 128.249722) (xy 218.664485 128.312046) (xy 218.634966 128.343432)
				(xy 218.593175 128.369916) (xy 218.496863 128.396863) (xy 218.85 128.851) (xy 219.203137 128.396863)
				(xy 219.143671 128.384207) (xy 219.09684 128.364812) (xy 219.035198 128.311607) (xy 219.005191 128.242171)
				(xy 219 128.19)
			)
		)
	)
	(zone
		(net 969)
		(net_name "/M.2 key M #1/M2_3V3")
		(layer "B.Cu")
		(name "$teardrop_padvia$")
		(hatch none 0.1)
		(priority 30274)
		(attr
			(teardrop
				(type padvia)
			)
		)
		(connect_pads yes
			(clearance 0)
		)
		(min_thickness 0.0254)
		(filled_areas_thickness no)
		(fill yes
			(thermal_gap 0.5)
			(thermal_bridge_width 0.5)
			(island_removal_mode 1)
			(island_area_min 10)
		)
		(polygon
			(pts
				(xy 178.260677 93.46) (xy 178.103106 93.453069) (xy 177.989578 93.424549) (xy 177.947778 93.4075)
				(xy 177.859 93.61) (xy 177.947778 93.8125) (xy 178.043817 93.778118) (xy 178.145689 93.7629) (xy 178.260677 93.76)
			)
		)
	)
	(zone
		(net 978)
		(net_name "/PCIe redriver/RX_EQ0")
		(layer "B.Cu")
		(name "$teardrop_padvia$")
		(hatch none 0.1)
		(priority 30931)
		(attr
			(teardrop
				(type padvia)
			)
		)
		(connect_pads yes
			(clearance 0)
		)
		(min_thickness 0.0254)
		(filled_areas_thickness no)
		(fill yes
			(thermal_gap 0.5)
			(thermal_bridge_width 0.5)
			(island_removal_mode 1)
			(island_area_min 10)
		)
		(polygon
			(pts
				(xy 190.682111 139.99965) (xy 190.687111 139.994372) (xy 190.715518 139.972625) (xy 190.736355 139.971405)
				(xy 190.763076 139.984015) (xy 190.984754 139.611449) (xy 190.614814 139.81992) (xy 190.62544 139.847087)
				(xy 190.624781 139.868977) (xy 190.598469 139.906663) (xy 190.593724 139.911263)
			)
		)
	)
	(zone
		(net 354)
		(net_name "Net-(J12D-~{LPC_DRQ1}{slash}~{ESPI_ALERT1})")
		(layer "B.Cu")
		(name "$teardrop_padvia$")
		(hatch none 0.1)
		(priority 30110)
		(attr
			(teardrop
				(type padvia)
			)
		)
		(connect_pads yes
			(clearance 0)
		)
		(min_thickness 0.0254)
		(filled_areas_thickness no)
		(fill yes
			(thermal_gap 0.5)
			(thermal_bridge_width 0.5)
			(island_removal_mode 1)
			(island_area_min 10)
		)
		(polygon
			(pts
				(xy 178.017794 162.4875) (xy 177.935734 162.482685) (xy 177.870388 162.468981) (xy 177.777121 162.422424)
				(xy 177.698658 162.354214) (xy 177.637159 162.298058) (xy 177.558339 162.238199) (xy 177.349 162.55)
				(xy 177.558339 162.861801) (xy 177.678517 162.76478) (xy 177.698657 162.745787) (xy 177.757541 162.692634)
				(xy 177.821624 162.650409) (xy 177.904008 162.622551) (xy 178.017794 162.6125)
			)
		)
	)
	(zone
		(net 713)
		(net_name "Net-(U39-SCL)")
		(layer "B.Cu")
		(name "$teardrop_padvia$")
		(hatch none 0.1)
		(priority 30920)
		(attr
			(teardrop
				(type padvia)
			)
		)
		(connect_pads yes
			(clearance 0)
		)
		(min_thickness 0.0254)
		(filled_areas_thickness no)
		(fill yes
			(thermal_gap 0.5)
			(thermal_bridge_width 0.5)
			(island_removal_mode 1)
			(island_area_min 10)
		)
		(polygon
			(pts
				(xy 122.3255 147.0485) (xy 122.319178 147.048596) (xy 122.279675 147.043011) (xy 122.261453 147.028078)
				(xy 122.248505 146.9985) (xy 121.837 147.111) (xy 122.248505 147.2235) (xy 122.259621 147.196506)
				(xy 122.275148 147.181405) (xy 122.319178 147.173404) (xy 122.3255 147.1735)
			)
		)
	)
	(zone
		(net 96)
		(net_name "/OCuLink/PCIe_{x4}.TX1-")
		(layer "B.Cu")
		(name "$teardrop_padvia$")
		(hatch none 0.1)
		(priority 30988)
		(attr
			(teardrop
				(type padvia)
			)
		)
		(connect_pads yes
			(clearance 0)
		)
		(min_thickness 0.0254)
		(filled_areas_thickness no)
		(fill yes
			(thermal_gap 0.5)
			(thermal_bridge_width 0.5)
			(island_removal_mode 1)
			(island_area_min 10)
		)
		(polygon
			(pts
				(xy 104.058 164.713) (xy 104.078648 164.705802) (xy 104.110984 164.696208) (xy 104.125007 164.703035)
				(xy 104.134995 164.7245) (xy 104.384 164.612) (xy 104.134995 164.4995) (xy 104.125271 164.520676)
				(xy 104.111643 164.527731) (xy 104.078648 164.518198) (xy 104.058 164.511)
			)
		)
	)
	(zone
		(net 627)
		(net_name "/PCIe redriver/TX_FG1")
		(layer "B.Cu")
		(name "$teardrop_padvia$")
		(hatch none 0.1)
		(priority 30692)
		(attr
			(teardrop
				(type padvia)
			)
		)
		(connect_pads yes
			(clearance 0)
		)
		(min_thickness 0.0254)
		(filled_areas_thickness no)
		(fill yes
			(thermal_gap 0.5)
			(thermal_bridge_width 0.5)
			(island_removal_mode 1)
			(island_area_min 10)
		)
		(polygon
			(pts
				(xy 112.8375 151.109323) (xy 112.832682 151.178763) (xy 112.81896 151.230087) (xy 112.772245 151.305628)
				(xy 112.762702 151.317768) (xy 112.712919 151.384997) (xy 112.9 151.511) (xy 113.087081 151.384997)
				(xy 113.037299 151.317769) (xy 112.982894 151.234603) (xy 112.96781 151.181748) (xy 112.9625 151.109323)
			)
		)
	)
	(zone
		(net 2)
		(net_name "+3V3")
		(layer "B.Cu")
		(name "$teardrop_padvia$")
		(hatch none 0.1)
		(priority 30161)
		(attr
			(teardrop
				(type padvia)
			)
		)
		(connect_pads yes
			(clearance 0)
		)
		(min_thickness 0.0254)
		(filled_areas_thickness no)
		(fill yes
			(thermal_gap 0.5)
			(thermal_bridge_width 0.5)
			(island_removal_mode 1)
			(island_area_min 10)
		)
		(polygon
			(pts
				(xy 243.513708 77.885) (xy 243.469063 77.905403) (xy 243.435516 77.924221) (xy 243.403053 77.932795)
				(xy 243.376343 77.918697) (xy 243.360055 77.8695) (xy 243.099708 78.135) (xy 243.360055 78.4005)
				(xy 243.369875 78.362407) (xy 243.385282 78.342642) (xy 243.419608 78.339648) (xy 243.469063 78.364597)
				(xy 243.513708 78.385)
			)
		)
	)
	(zone
		(net 574)
		(net_name "Net-(U19-EN)")
		(layer "B.Cu")
		(name "$teardrop_padvia$")
		(hatch none 0.1)
		(priority 30324)
		(attr
			(teardrop
				(type padvia)
			)
		)
		(connect_pads yes
			(clearance 0)
		)
		(min_thickness 0.0254)
		(filled_areas_thickness no)
		(fill yes
			(thermal_gap 0.5)
			(thermal_bridge_width 0.5)
			(island_removal_mode 1)
			(island_area_min 10)
		)
		(polygon
			(pts
				(xy 305.994 100.5975) (xy 305.941123 100.577779) (xy 305.896531 100.515836) (xy 305.881531 100.467362)
				(xy 305.874373 100.408175) (xy 305.874 100.39) (xy 305.573 100.66) (xy 305.874 100.93) (xy 305.878722 100.86779)
				(xy 305.891774 100.816261) (xy 305.911499 100.775671) (xy 305.936219 100.746328) (xy 305.963124 100.728989)
				(xy 305.991614 100.722538) (xy 305.994 100.7225)
			)
		)
	)
	(zone
		(net 105)
		(net_name "/PCIe redriver/PCIe_{I}_C.RX2-")
		(layer "B.Cu")
		(name "$teardrop_padvia$")
		(hatch none 0.1)
		(priority 30887)
		(attr
			(teardrop
				(type padvia)
			)
		)
		(connect_pads yes
			(clearance 0)
		)
		(min_thickness 0.0254)
		(filled_areas_thickness no)
		(fill yes
			(thermal_gap 0.5)
			(thermal_bridge_width 0.5)
			(island_removal_mode 1)
			(island_area_min 10)
		)
		(polygon
			(pts
				(xy 194.847325 137.763426) (xy 194.827634 137.753915) (xy 194.797986 137.737834) (xy 194.792898 137.723091)
				(xy 194.801013 137.700849) (xy 194.430486 137.489422) (xy 194.641913 137.859949) (xy 194.663764 137.851852)
				(xy 194.678389 137.8565) (xy 194.694979 137.88657) (xy 194.70449 137.906261)
			)
		)
	)
	(zone
		(net 220)
		(net_name "/Com Express 7 Interfaces/PCIe_{B1x4}.TX1+")
		(layer "B.Cu")
		(name "$teardrop_padvia$")
		(hatch none 0.1)
		(priority 30503)
		(attr
			(teardrop
				(type padvia)
			)
		)
		(connect_pads yes
			(clearance 0)
		)
		(min_thickness 0.0254)
		(filled_areas_thickness no)
		(fill yes
			(thermal_gap 0.5)
			(thermal_bridge_width 0.5)
			(island_removal_mode 1)
			(island_area_min 10)
		)
		(polygon
			(pts
				(xy 207.449092 165.968809) (xy 207.485522 165.939074) (xy 207.519885 165.9233) (xy 207.585791 165.921045)
				(xy 207.629912 165.930976) (xy 207.679788 165.942147) (xy 207.735381 165.945891) (xy 207.725921 165.724507)
				(xy 207.555129 165.583214) (xy 207.487215 165.657674) (xy 207.425836 165.714198) (xy 207.424294 165.715565)
				(xy 207.306256 165.825973)
			)
		)
	)
	(zone
		(net 225)
		(net_name "/Com Express 7 Interfaces/PCIe_{B1x4}.TX0-")
		(layer "B.Cu")
		(name "$teardrop_padvia$")
		(hatch none 0.1)
		(priority 30841)
		(attr
			(teardrop
				(type padvia)
			)
		)
		(connect_pads yes
			(clearance 0)
		)
		(min_thickness 0.0254)
		(filled_areas_thickness no)
		(fill yes
			(thermal_gap 0.5)
			(thermal_bridge_width 0.5)
			(island_removal_mode 1)
			(island_area_min 10)
		)
		(polygon
			(pts
				(xy 119.3545 145.1855) (xy 119.360476 145.199706) (xy 119.36836 145.223694) (xy 119.360161 145.232391)
				(xy 119.336683 145.235861) (xy 119.401 145.674) (xy 119.526 145.568212) (xy 119.516326 145.441693)
				(xy 119.539344 145.296816) (xy 119.5565 145.1855)
			)
		)
	)
	(zone
		(net 2)
		(net_name "+3V3")
		(layer "B.Cu")
		(name "$teardrop_padvia$")
		(hatch none 0.1)
		(priority 30282)
		(attr
			(teardrop
				(type padvia)
			)
		)
		(connect_pads yes
			(clearance 0)
		)
		(min_thickness 0.0254)
		(filled_areas_thickness no)
		(fill yes
			(thermal_gap 0.5)
			(thermal_bridge_width 0.5)
			(island_removal_mode 1)
			(island_area_min 10)
		)
		(polygon
			(pts
				(xy 142.580613 138.452745) (xy 142.662026 138.541767) (xy 142.711018 138.615736) (xy 142.751463 138.713204)
				(xy 142.960707 138.640707) (xy 143.048354 138.437738) (xy 142.971556 138.398184) (xy 142.906006 138.349331)
				(xy 142.792745 138.240613)
			)
		)
	)
	(zone
		(net 976)
		(net_name "/PCIe redriver/RX_EQ2")
		(layer "B.Cu")
		(name "$teardrop_padvia$")
		(hatch none 0.1)
		(priority 30905)
		(attr
			(teardrop
				(type padvia)
			)
		)
		(connect_pads yes
			(clearance 0)
		)
		(min_thickness 0.0254)
		(filled_areas_thickness no)
		(fill yes
			(thermal_gap 0.5)
			(thermal_bridge_width 0.5)
			(island_removal_mode 1)
			(island_area_min 10)
		)
		(polygon
			(pts
				(xy 189.180926 137.277996) (xy 189.185463 137.282398) (xy 189.209447 137.31428) (xy 189.211773 137.337725)
				(xy 189.200013 137.367796) (xy 189.570541 137.579224) (xy 189.359113 137.208696) (xy 189.332165 137.219923)
				(xy 189.310507 137.219623) (xy 189.273715 137.194146) (xy 189.269313 137.189609)
			)
		)
	)
	(zone
		(net 78)
		(net_name "+1V8")
		(layer "B.Cu")
		(name "$teardrop_padvia$")
		(hatch none 0.1)
		(priority 30441)
		(attr
			(teardrop
				(type padvia)
			)
		)
		(connect_pads yes
			(clearance 0)
		)
		(min_thickness 0.0254)
		(filled_areas_thickness no)
		(fill yes
			(thermal_gap 0.5)
			(thermal_bridge_width 0.5)
			(island_removal_mode 1)
			(island_area_min 10)
		)
		(polygon
			(pts
				(xy 147.967 133.9325) (xy 148.026412 133.952273) (xy 148.082497 134.015547) (xy 148.104199 134.064172)
				(xy 148.118873 134.123531) (xy 148.120653 134.1355) (xy 148.381 133.87) (xy 148.120653 133.6045)
				(xy 148.107804 133.664638) (xy 148.08787 133.714522) (xy 148.061945 133.754641) (xy 148.032125 133.783654)
				(xy 148.000707 133.801146) (xy 147.968896 133.807479) (xy 147.967 133.8075)
			)
		)
	)
	(zone
		(net 2)
		(net_name "+3V3")
		(layer "B.Cu")
		(name "$teardrop_padvia$")
		(hatch none 0.1)
		(priority 30738)
		(attr
			(teardrop
				(type padvia)
			)
		)
		(connect_pads yes
			(clearance 0)
		)
		(min_thickness 0.0254)
		(filled_areas_thickness no)
		(fill yes
			(thermal_gap 0.5)
			(thermal_bridge_width 0.5)
			(island_removal_mode 1)
			(island_area_min 10)
		)
		(polygon
			(pts
				(xy 197.908491 135.557331) (xy 197.83905 135.552513) (xy 197.787727 135.538791) (xy 197.712185 135.492077)
				(xy 197.700045 135.482532) (xy 197.632817 135.43275) (xy 197.506814 135.619831) (xy 197.632817 135.806912)
				(xy 197.700043 135.75713) (xy 197.78321 135.702725) (xy 197.836065 135.687641) (xy 197.908491 135.682331)
			)
		)
	)
	(zone
		(net 310)
		(net_name "/Com Express 7 MGMT/~{BIOS_DIS0}")
		(layer "B.Cu")
		(name "$teardrop_padvia$")
		(hatch none 0.1)
		(priority 30780)
		(attr
			(teardrop
				(type padvia)
			)
		)
		(connect_pads yes
			(clearance 0)
		)
		(min_thickness 0.0254)
		(filled_areas_thickness no)
		(fill yes
			(thermal_gap 0.5)
			(thermal_bridge_width 0.5)
			(island_removal_mode 1)
			(island_area_min 10)
		)
		(polygon
			(pts
				(xy 189.277515 158.689127) (xy 189.231819 158.636618) (xy 189.205231 158.590623) (xy 189.184847 158.504175)
				(xy 189.183011 158.48884) (xy 189.170677 158.406105) (xy 188.949293 158.449293) (xy 188.906105 158.670677)
				(xy 188.98884 158.683011) (xy 189.086119 158.703349) (xy 189.134159 158.730057) (xy 189.189127 158.777515)
			)
		)
	)
	(zone
		(net 867)
		(net_name "/Backplane/PCIe_{x2}.TX0-")
		(layer "B.Cu")
		(name "$teardrop_padvia$")
		(hatch none 0.1)
		(priority 30983)
		(attr
			(teardrop
				(type padvia)
			)
		)
		(connect_pads yes
			(clearance 0)
		)
		(min_thickness 0.0254)
		(filled_areas_thickness no)
		(fill yes
			(thermal_gap 0.5)
			(thermal_bridge_width 0.5)
			(island_removal_mode 1)
			(island_area_min 10)
		)
		(polygon
			(pts
				(xy 314.812 160.511) (xy 314.832648 160.503802) (xy 314.864984 160.494208) (xy 314.879007 160.501035)
				(xy 314.888995 160.5225) (xy 315.138 160.41) (xy 314.888995 160.2975) (xy 314.879271 160.318676)
				(xy 314.865643 160.325731) (xy 314.832648 160.316198) (xy 314.812 160.309)
			)
		)
	)
	(zone
		(net 97)
		(net_name "/OCuLink/PCIe_{x4}.TX2-")
		(layer "B.Cu")
		(name "$teardrop_padvia$")
		(hatch none 0.1)
		(priority 30985)
		(attr
			(teardrop
				(type padvia)
			)
		)
		(connect_pads yes
			(clearance 0)
		)
		(min_thickness 0.0254)
		(filled_areas_thickness no)
		(fill yes
			(thermal_gap 0.5)
			(thermal_bridge_width 0.5)
			(island_removal_mode 1)
			(island_area_min 10)
		)
		(polygon
			(pts
				(xy 104.83 160.211) (xy 104.850648 160.203802) (xy 104.882984 160.194208) (xy 104.897007 160.201035)
				(xy 104.906995 160.2225) (xy 105.156 160.11) (xy 104.906995 159.9975) (xy 104.897271 160.018676)
				(xy 104.883643 160.025731) (xy 104.850648 160.016198) (xy 104.83 160.009)
			)
		)
	)
	(zone
		(net 1)
		(net_name "GND")
		(layer "B.Cu")
		(name "$teardrop_padvia$")
		(hatch none 0.1)
		(priority 30345)
		(attr
			(teardrop
				(type padvia)
			)
		)
		(connect_pads yes
			(clearance 0)
		)
		(min_thickness 0.0254)
		(filled_areas_thickness no)
		(fill yes
			(thermal_gap 0.5)
			(thermal_bridge_width 0.5)
			(island_removal_mode 1)
			(island_area_min 10)
		)
		(polygon
			(pts
				(xy 137.612 169.7025) (xy 137.674866 169.722469) (xy 137.706844 169.748921) (xy 137.735358 169.786332)
				(xy 137.757882 169.833527) (xy 137.773093 169.891167) (xy 137.773202 169.891798) (xy 138.051 169.64)
				(xy 137.773202 169.388202) (xy 137.758905 169.443635) (xy 137.737825 169.48952) (xy 137.71046 169.527201)
				(xy 137.679552 169.554434) (xy 137.646265 169.571472) (xy 137.613434 169.577489) (xy 137.612 169.5775)
			)
		)
	)
	(zone
		(net 160)
		(net_name "/2xUSB3.0+RJ45/USBSS_2.RX-")
		(layer "B.Cu")
		(name "$teardrop_padvia$")
		(hatch none 0.1)
		(priority 30965)
		(attr
			(teardrop
				(type padvia)
			)
		)
		(connect_pads yes
			(clearance 0)
		)
		(min_thickness 0.0254)
		(filled_areas_thickness no)
		(fill yes
			(thermal_gap 0.5)
			(thermal_bridge_width 0.5)
			(island_removal_mode 1)
			(island_area_min 10)
		)
		(polygon
			(pts
				(xy 122.712701 105.336602) (xy 122.720525 105.332572) (xy 122.733134 105.33012) (xy 122.739368 105.369377)
				(xy 123.013965 105.299742) (xy 122.947139 105.175) (xy 122.861292 105.184635) (xy 122.763624 105.169324)
				(xy 122.710738 105.159309) (xy 122.664824 105.157906)
			)
		)
	)
	(zone
		(net 655)
		(net_name "Net-(U43C-PRTAD0)")
		(layer "B.Cu")
		(name "$teardrop_padvia$")
		(hatch none 0.1)
		(priority 30447)
		(attr
			(teardrop
				(type padvia)
			)
		)
		(connect_pads yes
			(clearance 0)
		)
		(min_thickness 0.0254)
		(filled_areas_thickness no)
		(fill yes
			(thermal_gap 0.5)
			(thermal_bridge_width 0.5)
			(island_removal_mode 1)
			(island_area_min 10)
		)
		(polygon
			(pts
				(xy 157.007 141.4225) (xy 157.066412 141.442273) (xy 157.122497 141.505547) (xy 157.144199 141.554172)
				(xy 157.158873 141.613531) (xy 157.160653 141.6255) (xy 157.421 141.36) (xy 157.160653 141.0945)
				(xy 157.147804 141.154638) (xy 157.12787 141.204522) (xy 157.101945 141.244641) (xy 157.072125 141.273654)
				(xy 157.040707 141.291146) (xy 157.008896 141.297479) (xy 157.007 141.2975)
			)
		)
	)
	(zone
		(net 868)
		(net_name "/Backplane/PCIe_{x2}.TX1+")
		(layer "B.Cu")
		(name "$teardrop_padvia$")
		(hatch none 0.1)
		(priority 30950)
		(attr
			(teardrop
				(type padvia)
			)
		)
		(connect_pads yes
			(clearance 0)
		)
		(min_thickness 0.0254)
		(filled_areas_thickness no)
		(fill yes
			(thermal_gap 0.5)
			(thermal_bridge_width 0.5)
			(island_removal_mode 1)
			(island_area_min 10)
		)
		(polygon
			(pts
				(xy 315.458808 161.362528) (xy 315.445602 161.368004) (xy 315.42286 161.374909) (xy 315.414581 161.365963)
				(xy 315.4112 161.341482) (xy 315.136001 161.407977) (xy 315.198604 161.533) (xy 315.281203 161.523726)
				(xy 315.377862 161.546911) (xy 315.454108 161.564472)
			)
		)
	)
	(zone
		(net 189)
		(net_name "/OCuLink/PCIe_{x4}.RX1-")
		(layer "B.Cu")
		(name "$teardrop_padvia$")
		(hatch none 0.1)
		(priority 30525)
		(attr
			(teardrop
				(type padvia)
			)
		)
		(connect_pads yes
			(clearance 0)
		)
		(min_thickness 0.0254)
		(filled_areas_thickness no)
		(fill yes
			(thermal_gap 0.5)
			(thermal_bridge_width 0.5)
			(island_removal_mode 1)
			(island_area_min 10)
		)
		(polygon
			(pts
				(xy 99.232504 149.5955) (xy 99.27929 149.600235) (xy 99.314742 149.613379) (xy 99.362939 149.658387)
				(xy 99.387116 149.696608) (xy 99.414485 149.739773) (xy 99.451147 149.781731) (xy 99.601 149.6185)
				(xy 99.58014 149.397823) (xy 99.479466 149.402452) (xy 99.396096 149.399019) (xy 99.394035 149.398895)
				(xy 99.232504 149.3935)
			)
		)
	)
	(zone
		(net 44)
		(net_name "/2xUSB3.0+RJ45/USBSS_1.TX+")
		(layer "B.Cu")
		(name "$teardrop_padvia$")
		(hatch none 0.1)
		(priority 30952)
		(attr
			(teardrop
				(type padvia)
			)
		)
		(connect_pads yes
			(clearance 0)
		)
		(min_thickness 0.0254)
		(filled_areas_thickness no)
		(fill yes
			(thermal_gap 0.5)
			(thermal_bridge_width 0.5)
			(island_removal_mode 1)
			(island_area_min 10)
		)
		(polygon
			(pts
				(xy 100.228 104.5195) (xy 100.308309 104.503748) (xy 100.396167 104.484329) (xy 100.444805 104.482846)
				(xy 100.496351 104.492) (xy 100.554 104.367) (xy 100.278225 104.303366) (xy 100.273746 104.3318)
				(xy 100.262735 104.341653) (xy 100.240525 104.33778) (xy 100.228 104.3345)
			)
		)
	)
	(zone
		(net 98)
		(net_name "/OCuLink/PCIe_{x4}.TX3-")
		(layer "B.Cu")
		(name "$teardrop_padvia$")
		(hatch none 0.1)
		(priority 31004)
		(attr
			(teardrop
				(type padvia)
			)
		)
		(connect_pads yes
			(clearance 0)
		)
		(min_thickness 0.0254)
		(filled_areas_thickness no)
		(fill yes
			(thermal_gap 0.5)
			(thermal_bridge_width 0.5)
			(island_removal_mode 1)
			(island_area_min 10)
		)
		(polygon
			(pts
				(xy 105.48 158.511) (xy 105.459352 158.518199) (xy 105.427017 158.527792) (xy 105.412994 158.520965)
				(xy 105.403005 158.4995) (xy 105.154 158.612) (xy 105.403005 158.7245) (xy 105.41273 158.703324)
				(xy 105.426358 158.696269) (xy 105.459352 158.705801) (xy 105.48 158.713)
			)
		)
	)
	(zone
		(net 426)
		(net_name "Net-(J12K-10G_SDP0)")
		(layer "B.Cu")
		(name "$teardrop_padvia$")
		(hatch none 0.1)
		(priority 30693)
		(attr
			(teardrop
				(type padvia)
			)
		)
		(connect_pads yes
			(clearance 0)
		)
		(min_thickness 0.0254)
		(filled_areas_thickness no)
		(fill yes
			(thermal_gap 0.5)
			(thermal_bridge_width 0.5)
			(island_removal_mode 1)
			(island_area_min 10)
		)
		(polygon
			(pts
				(xy 197.0125 158.049323) (xy 197.007682 158.118763) (xy 196.99396 158.170087) (xy 196.947245 158.245628)
				(xy 196.937702 158.257768) (xy 196.887919 158.324997) (xy 197.075 158.451) (xy 197.262081 158.324997)
				(xy 197.212299 158.257769) (xy 197.157894 158.174603) (xy 197.14281 158.121748) (xy 197.1375 158.049323)
			)
		)
	)
	(zone
		(net 225)
		(net_name "/Com Express 7 Interfaces/PCIe_{B1x4}.TX0-")
		(layer "B.Cu")
		(name "$teardrop_padvia$")
		(hatch none 0.1)
		(priority 30534)
		(attr
			(teardrop
				(type padvia)
			)
		)
		(connect_pads yes
			(clearance 0)
		)
		(min_thickness 0.0254)
		(filled_areas_thickness no)
		(fill yes
			(thermal_gap 0.5)
			(thermal_bridge_width 0.5)
			(island_removal_mode 1)
			(island_area_min 10)
		)
		(polygon
			(pts
				(xy 210.682504 170.4815) (xy 210.844035 170.476105) (xy 210.928445 170.472554) (xy 211.03014 170.477177)
				(xy 211.051 170.2565) (xy 210.901147 170.093268) (xy 210.847007 170.161935) (xy 210.837115 170.178393)
				(xy 210.812615 170.217065) (xy 210.783109 170.249279) (xy 210.741953 170.271327) (xy 210.682504 170.2795)
			)
		)
	)
	(zone
		(net 2)
		(net_name "+3V3")
		(layer "B.Cu")
		(name "$teardrop_padvia$")
		(hatch none 0.1)
		(priority 30400)
		(attr
			(teardrop
				(type padvia)
			)
		)
		(connect_pads yes
			(clearance 0)
		)
		(min_thickness 0.0254)
		(filled_areas_thickness no)
		(fill yes
			(thermal_gap 0.5)
			(thermal_bridge_width 0.5)
			(island_removal_mode 1)
			(island_area_min 10)
		)
		(polygon
			(pts
				(xy 193.0625 166.793) (xy 193.082273 166.733588) (xy 193.145547 166.677503) (xy 193.194172 166.655801)
				(xy 193.253532 166.641127) (xy 193.2655 166.639347) (xy 193 166.379) (xy 192.7345 166.639347) (xy 192.794639 166.652197)
				(xy 192.844523 166.672131) (xy 192.884642 166.698056) (xy 192.913655 166.727876) (xy 192.931146 166.759294)
				(xy 192.937479 166.791105) (xy 192.9375 166.793)
			)
		)
	)
	(zone
		(net 49)
		(net_name "/2xUSB3.0+RJ45/USBSS_2.TX-")
		(layer "B.Cu")
		(name "$teardrop_padvia$")
		(hatch none 0.1)
		(priority 31026)
		(attr
			(teardrop
				(type padvia)
			)
		)
		(connect_pads yes
			(clearance 0)
		)
		(min_thickness 0.0254)
		(filled_areas_thickness no)
		(fill yes
			(thermal_gap 0.5)
			(thermal_bridge_width 0.5)
			(island_removal_mode 1)
			(island_area_min 10)
		)
		(polygon
			(pts
				(xy 123.46 103.8945) (xy 123.478847 103.8896) (xy 123.512108 103.883482) (xy 123.526647 103.891841)
				(xy 123.536995 103.9145) (xy 123.786 103.802) (xy 123.536995 103.6895) (xy 123.527025 103.711717)
				(xy 123.51305 103.720331) (xy 123.478847 103.7144) (xy 123.46 103.7095)
			)
		)
	)
	(zone
		(net 679)
		(net_name "Net-(U45C-PRTAD2)")
		(layer "B.Cu")
		(name "$teardrop_padvia$")
		(hatch none 0.1)
		(priority 30412)
		(attr
			(teardrop
				(type padvia)
			)
		)
		(connect_pads yes
			(clearance 0)
		)
		(min_thickness 0.0254)
		(filled_areas_thickness no)
		(fill yes
			(thermal_gap 0.5)
			(thermal_bridge_width 0.5)
			(island_removal_mode 1)
			(island_area_min 10)
		)
		(polygon
			(pts
				(xy 126.983 138.9975) (xy 126.923588 138.977727) (xy 126.867503 138.914453) (xy 126.845801 138.865828)
				(xy 126.831127 138.806468) (xy 126.829347 138.7945) (xy 126.569 139.06) (xy 126.829347 139.3255)
				(xy 126.842197 139.265361) (xy 126.862131 139.215477) (xy 126.888056 139.175358) (xy 126.917876 139.146345)
				(xy 126.949294 139.128854) (xy 126.981105 139.122521) (xy 126.983 139.1225)
			)
		)
	)
	(zone
		(net 935)
		(net_name "Net-(D13-C)")
		(layer "B.Cu")
		(name "$teardrop_padvia$")
		(hatch none 0.1)
		(priority 30319)
		(attr
			(teardrop
				(type padvia)
			)
		)
		(connect_pads yes
			(clearance 0)
		)
		(min_thickness 0.0254)
		(filled_areas_thickness no)
		(fill yes
			(thermal_gap 0.5)
			(thermal_bridge_width 0.5)
			(island_removal_mode 1)
			(island_area_min 10)
		)
		(polygon
			(pts
				(xy 178.03 95.1725) (xy 178.068823 95.183438) (xy 178.083933 95.205195) (xy 178.09 95.245) (xy 178.841 95.11)
				(xy 178.09 94.975) (xy 178.085483 95.010281) (xy 178.073862 95.031797) (xy 178.041039 95.046995)
				(xy 178.03 95.0475)
			)
		)
	)
	(zone
		(net 1)
		(net_name "GND")
		(layer "B.Cu")
		(name "$teardrop_padvia$")
		(hatch none 0.1)
		(priority 30481)
		(attr
			(teardrop
				(type padvia)
			)
		)
		(connect_pads yes
			(clearance 0)
		)
		(min_thickness 0.0254)
		(filled_areas_thickness no)
		(fill yes
			(thermal_gap 0.5)
			(thermal_bridge_width 0.5)
			(island_removal_mode 1)
			(island_area_min 10)
		)
		(polygon
			(pts
				(xy 101.704031 165.31261) (xy 101.652272 165.254186) (xy 101.619889 165.203436) (xy 101.58529 165.109297)
				(xy 101.555257 165.018879) (xy 101.349293 165.099293) (xy 101.268879 165.305257) (xy 101.359297 165.33529)
				(xy 101.455111 165.370762) (xy 101.505114 165.402979) (xy 101.56261 165.454031)
			)
		)
	)
	(zone
		(net 49)
		(net_name "/2xUSB3.0+RJ45/USBSS_2.TX-")
		(layer "B.Cu")
		(name "$teardrop_padvia$")
		(hatch none 0.1)
		(priority 30021)
		(attr
			(teardrop
				(type padvia)
			)
		)
		(connect_pads yes
			(clearance 0)
		)
		(min_thickness 0.0254)
		(filled_areas_thickness no)
		(fill yes
			(thermal_gap 0.5)
			(thermal_bridge_width 0.5)
			(island_removal_mode 1)
			(island_area_min 10)
		)
		(polygon
			(pts
				(xy 112.316517 102.4625) (xy 112.169782 102.467253) (xy 112.048168 102.480521) (xy 111.854665 102.527127)
				(xy 111.71252 102.58072) (xy 111.542801 102.644284) (xy 111.318314 102.70297) (xy 111.449 103.365)
				(xy 112.11203 103.496686) (xy 112.124469 103.345373) (xy 112.10715 103.148234) (xy 112.098156 103.08544)
				(xy 112.077704 102.915201) (xy 112.077317 102.84082) (xy 112.088249 102.775971) (xy 112.114066 102.722435)
				(xy 112.158337 102.681991) (xy 112.224631 102.656419) (xy 112.316517 102.6475)
			)
		)
	)
	(zone
		(net 195)
		(net_name "/OCuLink/PCIe_{x4}.RX2-")
		(layer "B.Cu")
		(name "$teardrop_padvia$")
		(hatch none 0.1)
		(priority 30501)
		(attr
			(teardrop
				(type padvia)
			)
		)
		(connect_pads yes
			(clearance 0)
		)
		(min_thickness 0.0254)
		(filled_areas_thickness no)
		(fill yes
			(thermal_gap 0.5)
			(thermal_bridge_width 0.5)
			(island_removal_mode 1)
			(island_area_min 10)
		)
		(polygon
			(pts
				(xy 108.8045 148.432504) (xy 108.799765 148.47929) (xy 108.786621 148.514742) (xy 108.741613 148.562939)
				(xy 108.703393 148.587115) (xy 108.660226 148.614484) (xy 108.618268 148.651147) (xy 108.7815 148.801)
				(xy 109.002177 148.78014) (xy 108.997548 148.679469) (xy 109.00098 148.596102) (xy 109.001105 148.594035)
				(xy 109.0065 148.432504)
			)
		)
	)
	(zone
		(net 315)
		(net_name "Net-(J12H-VCC_RTC)")
		(layer "B.Cu")
		(name "$teardrop_padvia$")
		(hatch none 0.1)
		(priority 30754)
		(attr
			(teardrop
				(type padvia)
			)
		)
		(connect_pads yes
			(clearance 0)
		)
		(min_thickness 0.0254)
		(filled_areas_thickness no)
		(fill yes
			(thermal_gap 0.5)
			(thermal_bridge_width 0.5)
			(island_removal_mode 1)
			(island_area_min 10)
		)
		(polygon
			(pts
				(xy 218.939127 146.072485) (xy 218.886618 146.118181) (xy 218.840623 146.144768) (xy 218.754174 146.165152)
				(xy 218.738841 146.166988) (xy 218.656105 146.179323) (xy 218.699293 146.400707) (xy 218.920677 146.443895)
				(xy 218.933011 146.36116) (xy 218.953349 146.263881) (xy 218.980057 146.215841) (xy 219.027515 146.160873)
			)
		)
	)
	(zone
		(net 96)
		(net_name "/OCuLink/PCIe_{x4}.TX1-")
		(layer "B.Cu")
		(name "$teardrop_padvia$")
		(hatch none 0.1)
		(priority 30993)
		(attr
			(teardrop
				(type padvia)
			)
		)
		(connect_pads yes
			(clearance 0)
		)
		(min_thickness 0.0254)
		(filled_areas_thickness no)
		(fill yes
			(thermal_gap 0.5)
			(thermal_bridge_width 0.5)
			(island_removal_mode 1)
			(island_area_min 10)
		)
		(polygon
			(pts
				(xy 104.83 164.713) (xy 104.850648 164.705802) (xy 104.882984 164.696208) (xy 104.897007 164.703035)
				(xy 104.906995 164.7245) (xy 105.156 164.612) (xy 104.906995 164.4995) (xy 104.897271 164.520676)
				(xy 104.883643 164.527731) (xy 104.850648 164.518198) (xy 104.83 164.511)
			)
		)
	)
	(zone
		(net 876)
		(net_name "Net-(J2B-TX_{FAULT})")
		(layer "B.Cu")
		(name "$teardrop_padvia$")
		(hatch none 0.1)
		(priority 30085)
		(attr
			(teardrop
				(type padvia)
			)
		)
		(connect_pads yes
			(clearance 0)
		)
		(min_thickness 0.0254)
		(filled_areas_thickness no)
		(fill yes
			(thermal_gap 0.5)
			(thermal_bridge_width 0.5)
			(island_removal_mode 1)
			(island_area_min 10)
		)
		(polygon
			(pts
				(xy 141.962842 167.784454) (xy 141.92913 167.743908) (xy 141.911208 167.706429) (xy 141.906848 167.674904)
				(xy 141.911989 167.644827) (xy 141.950464 167.58002) (xy 142.013085 167.513875) (xy 142.100648 167.418463)
				(xy 142.136448 167.36308) (xy 142.160589 167.300553) (xy 141.799293 167.209293) (xy 141.497698 167.427838)
				(xy 141.508832 167.443291) (xy 141.668472 167.655143) (xy 141.874454 167.872842)
			)
		)
	)
	(zone
		(net 1)
		(net_name "GND")
		(layer "B.Cu")
		(name "$teardrop_padvia$")
		(hatch none 0.1)
		(priority 30369)
		(attr
			(teardrop
				(type padvia)
			)
		)
		(connect_pads yes
			(clearance 0)
		)
		(min_thickness 0.0254)
		(filled_areas_thickness no)
		(fill yes
			(thermal_gap 0.5)
			(thermal_bridge_width 0.5)
			(island_removal_mode 1)
			(island_area_min 10)
		)
		(polygon
			(pts
				(xy 143.8325 138.498) (xy 143.852469 138.435134) (xy 143.878921 138.403156) (xy 143.916332 138.374642)
				(xy 143.963527 138.352118) (xy 144.021167 138.336907) (xy 144.021798 138.336798) (xy 143.77 138.059)
				(xy 143.518202 138.336798) (xy 143.573635 138.351095) (xy 143.61952 138.372175) (xy 143.657201 138.39954)
				(xy 143.684434 138.430448) (xy 143.701472 138.463735) (xy 143.707489 138.496566) (xy 143.7075 138.498)
			)
		)
	)
	(zone
		(net 291)
		(net_name "/2xUSB3.0+RJ45/~{GBE0_LINK}")
		(layer "B.Cu")
		(name "$teardrop_padvia$")
		(hatch none 0.1)
		(priority 30709)
		(attr
			(teardrop
				(type padvia)
			)
		)
		(connect_pads yes
			(clearance 0)
		)
		(min_thickness 0.0254)
		(filled_areas_thickness no)
		(fill yes
			(thermal_gap 0.5)
			(thermal_bridge_width 0.5)
			(island_removal_mode 1)
			(island_area_min 10)
		)
		(polygon
			(pts
				(xy 126.699323 111.7625) (xy 126.768764 111.767318) (xy 126.820088 111.78104) (xy 126.895629 111.827755)
				(xy 126.907769 111.837299) (xy 126.974997 111.887081) (xy 127.101 111.7) (xy 126.974997 111.512919)
				(xy 126.907768 111.562702) (xy 126.824602 111.617106) (xy 126.771748 111.63219) (xy 126.699323 111.6375)
			)
		)
	)
	(zone
		(net 194)
		(net_name "/OCuLink/PCIe_{x4}.RX2+")
		(layer "B.Cu")
		(name "$teardrop_padvia$")
		(hatch none 0.1)
		(priority 30567)
		(attr
			(teardrop
				(type padvia)
			)
		)
		(connect_pads yes
			(clearance 0)
		)
		(min_thickness 0.0254)
		(filled_areas_thickness no)
		(fill yes
			(thermal_gap 0.5)
			(thermal_bridge_width 0.5)
			(island_removal_mode 1)
			(island_area_min 10)
		)
		(polygon
			(pts
				(xy 99.392496 159.9435) (xy 99.230964 159.948895) (xy 99.146554 159.952445) (xy 99.04486 159.947823)
				(xy 99.024 160.1685) (xy 99.173852 160.331731) (xy 99.227992 160.263062) (xy 99.237883 160.246608)
				(xy 99.262383 160.207935) (xy 99.29189 160.175721) (xy 99.333046 160.153673) (xy 99.392496 160.1455)
			)
		)
	)
	(zone
		(net 186)
		(net_name "/OCuLink/PCIe_{x4}.RX0+")
		(layer "B.Cu")
		(name "$teardrop_padvia$")
		(hatch none 0.1)
		(priority 30839)
		(attr
			(teardrop
				(type padvia)
			)
		)
		(connect_pads yes
			(clearance 0)
		)
		(min_thickness 0.0254)
		(filled_areas_thickness no)
		(fill yes
			(thermal_gap 0.5)
			(thermal_bridge_width 0.5)
			(island_removal_mode 1)
			(island_area_min 10)
		)
		(polygon
			(pts
				(xy 193.435586 133.023335) (xy 193.449811 133.029135) (xy 193.472289 133.040507) (xy 193.472599 133.052447)
				(xy 193.458396 133.071496) (xy 193.813181 133.336583) (xy 193.828277 133.174903) (xy 193.731786 133.091537)
				(xy 193.645578 132.972307) (xy 193.578421 132.8805)
			)
		)
	)
	(zone
		(net 113)
		(net_name "/2xSFP+/10GKR_SFP0.TX-")
		(layer "B.Cu")
		(name "$teardrop_padvia$")
		(hatch none 0.1)
		(priority 30828)
		(attr
			(teardrop
				(type padvia)
			)
		)
		(connect_pads yes
			(clearance 0)
		)
		(min_thickness 0.0254)
		(filled_areas_thickness no)
		(fill yes
			(thermal_gap 0.5)
			(thermal_bridge_width 0.5)
			(island_removal_mode 1)
			(island_area_min 10)
		)
		(polygon
			(pts
				(xy 197.536428 154.052617) (xy 197.51111 154.003541) (xy 197.483564 153.969024) (xy 197.42164 153.92286)
				(xy 197.372922 153.889243) (xy 197.3252 153.835878) (xy 197.137737 153.959958) (xy 197.182014 154.181558)
				(xy 197.240091 154.153885) (xy 197.280308 154.122194) (xy 197.34212 154.080951) (xy 197.367471 154.084141)
				(xy 197.388614 154.113859)
			)
		)
	)
	(zone
		(net 537)
		(net_name "/Backplane/PCIe_{x2}.RX0-")
		(layer "B.Cu")
		(name "$teardrop_padvia$")
		(hatch none 0.1)
		(priority 30528)
		(attr
			(teardrop
				(type padvia)
			)
		)
		(connect_pads yes
			(clearance 0)
		)
		(min_thickness 0.0254)
		(filled_areas_thickness no)
		(fill yes
			(thermal_gap 0.5)
			(thermal_bridge_width 0.5)
			(island_removal_mode 1)
			(island_area_min 10)
		)
		(polygon
			(pts
				(xy 270.432504 158.4955) (xy 270.47929 158.500235) (xy 270.514742 158.513379) (xy 270.562939 158.558387)
				(xy 270.587116 158.596608) (xy 270.614485 158.639773) (xy 270.651147 158.681731) (xy 270.801 158.5185)
				(xy 270.78014 158.297823) (xy 270.679466 158.302452) (xy 270.596096 158.299019) (xy 270.594035 158.298895)
				(xy 270.432504 158.2935)
			)
		)
	)
	(zone
		(net 86)
		(net_name "/Com Express 7 Interfaces/PCIe_{B2Ax4}.RX0-")
		(layer "B.Cu")
		(name "$teardrop_padvia$")
		(hatch none 0.1)
		(priority 30555)
		(attr
			(teardrop
				(type padvia)
			)
		)
		(connect_pads yes
			(clearance 0)
		)
		(min_thickness 0.0254)
		(filled_areas_thickness no)
		(fill yes
			(thermal_gap 0.5)
			(thermal_bridge_width 0.5)
			(island_removal_mode 1)
			(island_area_min 10)
		)
		(polygon
			(pts
				(xy 296.542 75.019852) (xy 296.547395 75.181383) (xy 296.550945 75.265794) (xy 296.546323 75.367488)
				(xy 296.767 75.388348) (xy 296.930231 75.238495) (xy 296.861562 75.184355) (xy 296.845108 75.174464)
				(xy 296.806435 75.149964) (xy 296.774221 75.120457) (xy 296.752173 75.079301) (xy 296.744 75.019852)
			)
		)
	)
	(zone
		(net 187)
		(net_name "/OCuLink/PCIe_{x4}.RX0-")
		(layer "B.Cu")
		(name "$teardrop_padvia$")
		(hatch none 0.1)
		(priority 30848)
		(attr
			(teardrop
				(type padvia)
			)
		)
		(connect_pads yes
			(clearance 0)
		)
		(min_thickness 0.0254)
		(filled_areas_thickness no)
		(fill yes
			(thermal_gap 0.5)
			(thermal_bridge_width 0.5)
			(island_removal_mode 1)
			(island_area_min 10)
		)
		(polygon
			(pts
				(xy 193.710651 132.74827) (xy 193.802458 132.815427) (xy 193.905433 132.887639) (xy 193.956964 132.9364)
				(xy 194.005056 132.998127) (xy 194.166735 132.98303) (xy 193.901647 132.628245) (xy 193.880387 132.6432)
				(xy 193.868109 132.64) (xy 193.859286 132.61966) (xy 193.853486 132.605435)
			)
		)
	)
	(zone
		(net 81)
		(net_name "/Misc/FAN_12V")
		(layer "B.Cu")
		(name "$teardrop_padvia$")
		(hatch none 0.1)
		(priority 30005)
		(attr
			(teardrop
				(type padvia)
			)
		)
		(connect_pads yes
			(clearance 0)
		)
		(min_thickness 0.0254)
		(filled_areas_thickness no)
		(fill yes
			(thermal_gap 0.5)
			(thermal_bridge_width 0.5)
			(island_removal_mode 1)
			(island_area_min 10)
		)
		(polygon
			(pts
				(xy 250.220709 73.204379) (xy 250.225972 73.121131) (xy 250.242815 73.031151) (xy 250.269955 72.944539)
				(xy 250.309509 72.856529) (xy 250.356625 72.778013) (xy 250.415644 72.70154) (xy 250.480734 72.634728)
				(xy 250.557192 72.572019) (xy 250.68993 72.490568) (xy 249.970709 71.859) (xy 249.251488 72.490568)
				(xy 249.413576 72.594426) (xy 249.541035 72.71958) (xy 249.635387 72.863236) (xy 249.695951 73.02086)
				(xy 249.720314 73.181986) (xy 249.720709 73.204379)
			)
		)
	)
	(zone
		(net 2)
		(net_name "+3V3")
		(layer "B.Cu")
		(name "$teardrop_padvia$")
		(hatch none 0.1)
		(priority 30367)
		(attr
			(teardrop
				(type padvia)
			)
		)
		(connect_pads yes
			(clearance 0)
		)
		(min_thickness 0.0254)
		(filled_areas_thickness no)
		(fill yes
			(thermal_gap 0.5)
			(thermal_bridge_width 0.5)
			(island_removal_mode 1)
			(island_area_min 10)
		)
		(polygon
			(pts
				(xy 123.9425 108.248) (xy 123.962469 108.185134) (xy 123.988921 108.153156) (xy 124.026332 108.124642)
				(xy 124.073527 108.102118) (xy 124.131167 108.086907) (xy 124.131798 108.086798) (xy 123.88 107.809)
				(xy 123.628202 108.086798) (xy 123.683635 108.101095) (xy 123.72952 108.122175) (xy 123.767201 108.14954)
				(xy 123.794434 108.180448) (xy 123.811472 108.213735) (xy 123.817489 108.246566) (xy 123.8175 108.248)
			)
		)
	)
	(zone
		(net 1)
		(net_name "GND")
		(layer "B.Cu")
		(name "$teardrop_padvia$")
		(hatch none 0.1)
		(priority 30862)
		(attr
			(teardrop
				(type padvia)
			)
		)
		(connect_pads yes
			(clearance 0)
		)
		(min_thickness 0.0254)
		(filled_areas_thickness no)
		(fill yes
			(thermal_gap 0.5)
			(thermal_bridge_width 0.5)
			(island_removal_mode 1)
			(island_area_min 10)
		)
		(polygon
			(pts
				(xy 315.492 165.61) (xy 315.481885 165.610153) (xy 315.451169 165.60954) (xy 315.41868 165.601218)
				(xy 315.389526 165.577325) (xy 315.368809 165.53) (xy 315.136 165.71) (xy 315.368809 165.89) (xy 315.382168 165.854099)
				(xy 315.400399 165.830801) (xy 315.445725 165.811101) (xy 315.481885 165.809847) (xy 315.492 165.81)
			)
		)
	)
	(zone
		(net 926)
		(net_name "Net-(J5-SUSCLK)")
		(layer "B.Cu")
		(name "$teardrop_padvia$")
		(hatch none 0.1)
		(priority 30316)
		(attr
			(teardrop
				(type padvia)
			)
		)
		(connect_pads yes
			(clearance 0)
		)
		(min_thickness 0.0254)
		(filled_areas_thickness no)
		(fill yes
			(thermal_gap 0.5)
			(thermal_bridge_width 0.5)
			(island_removal_mode 1)
			(island_area_min 10)
		)
		(polygon
			(pts
				(xy 178.03 109.6725) (xy 178.068823 109.683438) (xy 178.083933 109.705195) (xy 178.09 109.745) (xy 178.841 109.61)
				(xy 178.09 109.475) (xy 178.085483 109.510281) (xy 178.073862 109.531797) (xy 178.041039 109.546995)
				(xy 178.03 109.5475)
			)
		)
	)
	(zone
		(net 1)
		(net_name "GND")
		(layer "B.Cu")
		(name "$teardrop_padvia$")
		(hatch none 0.1)
		(priority 30868)
		(attr
			(teardrop
				(type padvia)
			)
		)
		(connect_pads yes
			(clearance 0)
		)
		(min_thickness 0.0254)
		(filled_areas_thickness no)
		(fill yes
			(thermal_gap 0.5)
			(thermal_bridge_width 0.5)
			(island_removal_mode 1)
			(island_area_min 10)
		)
		(polygon
			(pts
				(xy 104.028 159.71) (xy 104.038115 159.709847) (xy 104.068832 159.71046) (xy 104.10132 159.718782)
				(xy 104.130475 159.742675) (xy 104.151191 159.79) (xy 104.384 159.61) (xy 104.151191 159.43) (xy 104.137833 159.465901)
				(xy 104.119601 159.489199) (xy 104.074276 159.508899) (xy 104.038115 159.510153) (xy 104.028 159.51)
			)
		)
	)
	(zone
		(net 95)
		(net_name "/OCuLink/PCIe_{x4}.TX0-")
		(layer "B.Cu")
		(name "$teardrop_padvia$")
		(hatch none 0.1)
		(priority 30182)
		(attr
			(teardrop
				(type padvia)
			)
		)
		(connect_pads yes
			(clearance 0)
		)
		(min_thickness 0.0254)
		(filled_areas_thickness no)
		(fill yes
			(thermal_gap 0.5)
			(thermal_bridge_width 0.5)
			(island_removal_mode 1)
			(island_area_min 10)
		)
		(polygon
			(pts
				(xy 108.965556 166.2665) (xy 109.020074 166.246776) (xy 109.179598 166.19577) (xy 109.268436 166.182974)
				(xy 109.358602 166.189) (xy 109.332 165.869) (xy 109.036 165.766977) (xy 109.042099 165.895154)
				(xy 109.031354 165.986378) (xy 109.0157 166.024205) (xy 108.992319 166.050566) (xy 108.965556 166.0645)
			)
		)
	)
	(zone
		(net 969)
		(net_name "/M.2 key M #1/M2_3V3")
		(layer "B.Cu")
		(name "$teardrop_padvia$")
		(hatch none 0.1)
		(priority 30273)
		(attr
			(teardrop
				(type padvia)
			)
		)
		(connect_pads yes
			(clearance 0)
		)
		(min_thickness 0.0254)
		(filled_areas_thickness no)
		(fill yes
			(thermal_gap 0.5)
			(thermal_bridge_width 0.5)
			(island_removal_mode 1)
			(island_area_min 10)
		)
		(polygon
			(pts
				(xy 178.260677 96.46) (xy 178.103106 96.453069) (xy 177.989578 96.424549) (xy 177.947778 96.4075)
				(xy 177.859 96.61) (xy 177.947778 96.8125) (xy 178.043817 96.778118) (xy 178.145689 96.7629) (xy 178.260677 96.76)
			)
		)
	)
	(zone
		(net 197)
		(net_name "/OCuLink/PCIe_{x4}.RX3-")
		(layer "B.Cu")
		(name "$teardrop_padvia$")
		(hatch none 0.1)
		(priority 30519)
		(attr
			(teardrop
				(type padvia)
			)
		)
		(connect_pads yes
			(clearance 0)
		)
		(min_thickness 0.0254)
		(filled_areas_thickness no)
		(fill yes
			(thermal_gap 0.5)
			(thermal_bridge_width 0.5)
			(island_removal_mode 1)
			(island_area_min 10)
		)
		(polygon
			(pts
				(xy 99.392496 158.0545) (xy 99.34571 158.049765) (xy 99.310258 158.036621) (xy 99.26206 157.991613)
				(xy 99.237884 157.953392) (xy 99.210514 157.910225) (xy 99.173852 157.868268) (xy 99.024 158.0315)
				(xy 99.04486 158.252177) (xy 99.145531 158.247548) (xy 99.228897 158.25098) (xy 99.230964 158.251105)
				(xy 99.392496 158.2565)
			)
		)
	)
	(zone
		(net 222)
		(net_name "/Com Express 7 Interfaces/PCIe_{B1x4}.RX0+")
		(layer "B.Cu")
		(name "$teardrop_padvia$")
		(hatch none 0.1)
		(priority 30494)
		(attr
			(teardrop
				(type padvia)
			)
		)
		(connect_pads yes
			(clearance 0)
		)
		(min_thickness 0.0254)
		(filled_areas_thickness no)
		(fill yes
			(thermal_gap 0.5)
			(thermal_bridge_width 0.5)
			(island_removal_mode 1)
			(island_area_min 10)
		)
		(polygon
			(pts
				(xy 209.4795 158.882504) (xy 209.474765 158.92929) (xy 209.461621 158.964742) (xy 209.416613 159.012939)
				(xy 209.378393 159.037115) (xy 209.335226 159.064484) (xy 209.293268 159.101147) (xy 209.4565 159.251)
				(xy 209.677177 159.23014) (xy 209.672548 159.129469) (xy 209.67598 159.046102) (xy 209.676105 159.044035)
				(xy 209.6815 158.882504)
			)
		)
	)
	(zone
		(net 625)
		(net_name "/PCIe redriver/TX_EQ2")
		(layer "B.Cu")
		(name "$teardrop_padvia$")
		(hatch none 0.1)
		(priority 30915)
		(attr
			(teardrop
				(type padvia)
			)
		)
		(connect_pads yes
			(clearance 0)
		)
		(min_thickness 0.0254)
		(filled_areas_thickness no)
		(fill yes
			(thermal_gap 0.5)
			(thermal_bridge_width 0.5)
			(island_removal_mode 1)
			(island_area_min 10)
		)
		(polygon
			(pts
				(xy 113.3385 145.1855) (xy 113.338596 145.191822) (xy 113.333011 145.231325) (xy 113.318078 145.249547)
				(xy 113.2885 145.262495) (xy 113.401 145.674) (xy 113.5135 145.262495) (xy 113.486507 145.251379)
				(xy 113.471405 145.235852) (xy 113.463404 145.191822) (xy 113.4635 145.1855)
			)
		)
	)
	(zone
		(net 2)
		(net_name "+3V3")
		(layer "B.Cu")
		(name "$teardrop_padvia$")
		(hatch none 0.1)
		(priority 30908)
		(attr
			(teardrop
				(type padvia)
			)
		)
		(connect_pads yes
			(clearance 0)
		)
		(min_thickness 0.0254)
		(filled_areas_thickness no)
		(fill yes
			(thermal_gap 0.5)
			(thermal_bridge_width 0.5)
			(island_removal_mode 1)
			(island_area_min 10)
		)
		(polygon
			(pts
				(xy 193.052334 139.558417) (xy 193.047797 139.554015) (xy 193.023813 139.522133) (xy 193.021487 139.498688)
				(xy 193.033246 139.468617) (xy 192.662719 139.257188) (xy 192.874146 139.627715) (xy 192.901094 139.616488)
				(xy 192.922752 139.616789) (xy 192.959545 139.642267) (xy 192.963947 139.646804)
			)
		)
	)
	(zone
		(net 247)
		(net_name "/Com Express 7 Interfaces/PCIe_{B2Bx4}.TX2-")
		(layer "B.Cu")
		(name "$teardrop_padvia$")
		(hatch none 0.1)
		(priority 30569)
		(attr
			(teardrop
				(type padvia)
			)
		)
		(connect_pads yes
			(clearance 0)
		)
		(min_thickness 0.0254)
		(filled_areas_thickness no)
		(fill yes
			(thermal_gap 0.5)
			(thermal_bridge_width 0.5)
			(island_removal_mode 1)
			(island_area_min 10)
		)
		(polygon
			(pts
				(xy 174.667496 98.7035) (xy 174.505964 98.708895) (xy 174.421554 98.712445) (xy 174.31986 98.707823)
				(xy 174.299 98.9285) (xy 174.448852 99.091731) (xy 174.502992 99.023062) (xy 174.512883 99.006608)
				(xy 174.537383 98.967935) (xy 174.56689 98.935721) (xy 174.608046 98.913673) (xy 174.667496 98.9055)
			)
		)
	)
	(zone
		(net 717)
		(net_name "Net-(U40-SCL)")
		(layer "B.Cu")
		(name "$teardrop_padvia$")
		(hatch none 0.1)
		(priority 30898)
		(attr
			(teardrop
				(type padvia)
			)
		)
		(connect_pads yes
			(clearance 0)
		)
		(min_thickness 0.0254)
		(filled_areas_thickness no)
		(fill yes
			(thermal_gap 0.5)
			(thermal_bridge_width 0.5)
			(island_removal_mode 1)
			(island_area_min 10)
		)
		(polygon
			(pts
				(xy 196.853034 132.240568) (xy 196.848632 132.245105) (xy 196.816749 132.26909) (xy 196.793304 132.271416)
				(xy 196.763233 132.259656) (xy 196.551806 132.630184) (xy 196.922333 132.418756) (xy 196.911106 132.391808)
				(xy 196.911407 132.37015) (xy 196.936884 132.333356) (xy 196.941421 132.328955)
			)
		)
	)
	(zone
		(net 704)
		(net_name "Net-(U24-GPIO2)")
		(layer "B.Cu")
		(name "$teardrop_padvia$")
		(hatch none 0.1)
		(priority 30640)
		(attr
			(teardrop
				(type padvia)
			)
		)
		(connect_pads yes
			(clearance 0)
		)
		(min_thickness 0.0254)
		(filled_areas_thickness no)
		(fill yes
			(thermal_gap 0.5)
			(thermal_bridge_width 0.5)
			(island_removal_mode 1)
			(island_area_min 10)
		)
		(polygon
			(pts
				(xy 260.439323 85.7725) (xy 260.501751 85.777259) (xy 260.548692 85.790573) (xy 260.616857 85.835971)
				(xy 260.634673 85.852061) (xy 260.714997 85.91708) (xy 260.841 85.729999) (xy 260.762287 85.523329)
				(xy 260.658525 85.57688) (xy 260.64805 85.583627) (xy 260.564807 85.628528) (xy 260.51075 85.642381)
				(xy 260.439323 85.6475)
			)
		)
	)
	(zone
		(net 155)
		(net_name "Net-(J1A-LED_D2)")
		(layer "B.Cu")
		(name "$teardrop_padvia$")
		(hatch none 0.1)
		(priority 30027)
		(attr
			(teardrop
				(type padvia)
			)
		)
		(connect_pads yes
			(clearance 0)
		)
		(min_thickness 0.0254)
		(filled_areas_thickness no)
		(fill yes
			(thermal_gap 0.5)
			(thermal_bridge_width 0.5)
			(island_removal_mode 1)
			(island_area_min 10)
		)
		(polygon
			(pts
				(xy 121.714091 99.7975) (xy 121.569393 99.802252) (xy 121.449615 99.815517) (xy 121.259415 99.862068)
				(xy 121.120806 99.915139) (xy 120.952358 99.979072) (xy 120.728314 100.03797) (xy 120.859 100.7)
				(xy 121.52203 100.831686) (xy 121.53444 100.679433) (xy 121.515844 100.485296) (xy 121.498131 100.379562)
				(xy 121.47165 100.201431) (xy 121.469068 100.123784) (xy 121.478637 100.056174) (xy 121.50414 100.000421)
				(xy 121.549361 99.958344) (xy 121.618083 99.931764) (xy 121.714091 99.9225)
			)
		)
	)
	(zone
		(net 104)
		(net_name "/OCuLink/PCIe_{x4}.TX2+")
		(layer "B.Cu")
		(name "$teardrop_padvia$")
		(hatch none 0.1)
		(priority 30984)
		(attr
			(teardrop
				(type padvia)
			)
		)
		(connect_pads yes
			(clearance 0)
		)
		(min_thickness 0.0254)
		(filled_areas_thickness no)
		(fill yes
			(thermal_gap 0.5)
			(thermal_bridge_width 0.5)
			(island_removal_mode 1)
			(island_area_min 10)
		)
		(polygon
			(pts
				(xy 104.83 160.711) (xy 104.850648 160.703802) (xy 104.882984 160.694208) (xy 104.897007 160.701035)
				(xy 104.906995 160.7225) (xy 105.156 160.61) (xy 104.906995 160.4975) (xy 104.897271 160.518676)
				(xy 104.883643 160.525731) (xy 104.850648 160.516198) (xy 104.83 160.509)
			)
		)
	)
	(zone
		(net 352)
		(net_name "Net-(J12D-LPC_AD3{slash}ESPI_IO_3)")
		(layer "B.Cu")
		(name "$teardrop_padvia$")
		(hatch none 0.1)
		(priority 30763)
		(attr
			(teardrop
				(type padvia)
			)
		)
		(connect_pads yes
			(clearance 0)
		)
		(min_thickness 0.0254)
		(filled_areas_thickness no)
		(fill yes
			(thermal_gap 0.5)
			(thermal_bridge_width 0.5)
			(island_removal_mode 1)
			(island_area_min 10)
		)
		(polygon
			(pts
				(xy 178.672485 164.360873) (xy 178.718181 164.413382) (xy 178.744768 164.459376) (xy 178.765152 164.545825)
				(xy 178.766988 164.561158) (xy 178.779323 164.643895) (xy 179.000707 164.600707) (xy 179.043895 164.379323)
				(xy 178.961158 164.366988) (xy 178.86388 164.346651) (xy 178.81584 164.319943) (xy 178.760873 164.272485)
			)
		)
	)
	(zone
		(net 176)
		(net_name "Net-(J3-CC_{1})")
		(layer "B.Cu")
		(name "$teardrop_padvia$")
		(hatch none 0.1)
		(priority 30292)
		(attr
			(teardrop
				(type padvia)
			)
		)
		(connect_pads yes
			(clearance 0)
		)
		(min_thickness 0.0254)
		(filled_areas_thickness no)
		(fill yes
			(thermal_gap 0.5)
			(thermal_bridge_width 0.5)
			(island_removal_mode 1)
			(island_area_min 10)
		)
		(polygon
			(pts
				(xy 100.68 85.898) (xy 100.68621 85.851789) (xy 100.709677 85.80339) (xy 100.737584 85.775034) (xy 100.77781 85.751988)
				(xy 100.831798 85.736798) (xy 100.58 85.459) (xy 100.328202 85.736798) (xy 100.377054 85.749931)
				(xy 100.414564 85.769335) (xy 100.461987 85.821945) (xy 100.479743 85.888446) (xy 100.48 85.898)
			)
		)
	)
	(zone
		(net 868)
		(net_name "/Backplane/PCIe_{x2}.TX1+")
		(layer "B.Cu")
		(name "$teardrop_padvia$")
		(hatch none 0.1)
		(priority 30939)
		(attr
			(teardrop
				(type padvia)
			)
		)
		(connect_pads yes
			(clearance 0)
		)
		(min_thickness 0.0254)
		(filled_areas_thickness no)
		(fill yes
			(thermal_gap 0.5)
			(thermal_bridge_width 0.5)
			(island_removal_mode 1)
			(island_area_min 10)
		)
		(polygon
			(pts
				(xy 314.04 161.5645) (xy 314.119272 161.546854) (xy 314.204896 161.525263) (xy 314.252145 161.523372)
				(xy 314.302083 161.533) (xy 314.366 161.408) (xy 314.090953 161.340707) (xy 314.08632 161.36751)
				(xy 314.075289 161.375052) (xy 314.053941 161.367832) (xy 314.04 161.3625)
			)
		)
	)
	(zone
		(net 126)
		(net_name "/2xUSB3.0+RJ45/P2_D+")
		(layer "B.Cu")
		(name "$teardrop_padvia$")
		(hatch none 0.1)
		(priority 30577)
		(attr
			(teardrop
				(type padvia)
			)
		)
		(connect_pads yes
			(clearance 0)
		)
		(min_thickness 0.0254)
		(filled_areas_thickness no)
		(fill yes
			(thermal_gap 0.5)
			(thermal_bridge_width 0.5)
			(island_removal_mode 1)
			(island_area_min 10)
		)
		(polygon
			(pts
				(xy 113.3475 106.740416) (xy 113.34276 106.785027) (xy 113.329582 106.818424) (xy 113.284799 106.862019)
				(xy 113.24218 106.884851) (xy 113.194337 106.910508) (xy 113.148311 106.947104) (xy 113.3075 107.101)
				(xy 113.528177 107.087562) (xy 113.528316 106.904857) (xy 113.5325 106.740416)
			)
		)
	)
	(zone
		(net 2)
		(net_name "+3V3")
		(layer "B.Cu")
		(name "$teardrop_padvia$")
		(hatch none 0.1)
		(priority 30393)
		(attr
			(teardrop
				(type padvia)
			)
		)
		(connect_pads yes
			(clearance 0)
		)
		(min_thickness 0.0254)
		(filled_areas_thickness no)
		(fill yes
			(thermal_gap 0.5)
			(thermal_bridge_width 0.5)
			(island_removal_mode 1)
			(island_area_min 10)
		)
		(polygon
			(pts
				(xy 193.144611 141.665241) (xy 193.086038 141.695573) (xy 193.044722 141.69948) (xy 192.998106 141.693189)
				(xy 192.948807 141.675744) (xy 192.897294 141.645742) (xy 192.896771 141.645373) (xy 192.878386 142.019854)
				(xy 193.252867 142.001469) (xy 193.223779 141.952163) (xy 193.20624 141.904812) (xy 193.198945 141.858817)
				(xy 193.201544 141.817705) (xy 193.213033 141.78212) (xy 193.231993 141.754651) (xy 193.232999 141.753629)
			)
		)
	)
	(zone
		(net 1)
		(net_name "GND")
		(layer "B.Cu")
		(name "$teardrop_padvia$")
		(hatch none 0.1)
		(priority 30087)
		(attr
			(teardrop
				(type padvia)
			)
		)
		(connect_pads yes
			(clearance 0)
		)
		(min_thickness 0.0254)
		(filled_areas_thickness no)
		(fill yes
			(thermal_gap 0.5)
			(thermal_bridge_width 0.5)
			(island_removal_mode 1)
			(island_area_min 10)
		)
		(polygon
			(pts
				(xy 129.54 131.86) (xy 129.520818 131.803409) (xy 129.503059 131.762146) (xy 129.495846 131.718423)
				(xy 129.511664 131.67384) (xy 129.563 131.63) (xy 129.063 131.389) (xy 128.856634 131.79) (xy 128.98671 131.795162)
				(xy 129.035545 131.811295) (xy 129.041026 131.842715) (xy 129.04 131.86)
			)
		)
	)
	(zone
		(net 2)
		(net_name "+3V3")
		(layer "B.Cu")
		(name "$teardrop_padvia$")
		(hatch none 0.1)
		(priority 30805)
		(attr
			(teardrop
				(type padvia)
			)
		)
		(connect_pads yes
			(clearance 0)
		)
		(min_thickness 0.0254)
		(filled_areas_thickness no)
		(fill yes
			(thermal_gap 0.5)
			(thermal_bridge_width 0.5)
			(island_removal_mode 1)
			(island_area_min 10)
		)
		(polygon
			(pts
				(xy 191.061953 135.446714) (xy 191.016566 135.39452) (xy 190.990144 135.34874) (xy 190.969995 135.262681)
				(xy 190.96816 135.246917) (xy 190.955822 135.162985) (xy 190.734438 135.206173) (xy 190.69125 135.427557)
				(xy 190.772763 135.439878) (xy 190.870349 135.460582) (xy 190.918456 135.487455) (xy 190.973565 135.535102)
			)
		)
	)
	(zone
		(net 877)
		(net_name "/2xSFP+/SFI1.RX-")
		(layer "B.Cu")
		(name "$teardrop_padvia$")
		(hatch none 0.1)
		(priority 30059)
		(attr
			(teardrop
				(type padvia)
			)
		)
		(connect_pads yes
			(clearance 0)
		)
		(min_thickness 0.0254)
		(filled_areas_thickness no)
		(fill yes
			(thermal_gap 0.5)
			(thermal_bridge_width 0.5)
			(island_removal_mode 1)
			(island_area_min 10)
		)
		(polygon
			(pts
				(xy 138.265578 160.209717) (xy 138.500364 160.199055) (xy 138.665213 160.179967) (xy 138.792478 160.158486)
				(xy 138.948984 160.131738) (xy 138.880999 159.709976) (xy 138.51401 159.491523) (xy 138.473202 159.593738)
				(xy 138.456424 159.726195) (xy 138.454534 159.780873) (xy 138.448759 159.883268) (xy 138.426118 159.967877)
				(xy 138.403121 160.000857) (xy 138.369486 160.026206) (xy 138.32307 160.042862) (xy 138.261734 160.049764)
			)
		)
	)
	(zone
		(net 2)
		(net_name "+3V3")
		(layer "B.Cu")
		(name "$teardrop_padvia$")
		(hatch none 0.1)
		(priority 30575)
		(attr
			(teardrop
				(type padvia)
			)
		)
		(connect_pads yes
			(clearance 0)
		)
		(min_thickness 0.0254)
		(filled_areas_thickness no)
		(fill yes
			(thermal_gap 0.5)
			(thermal_bridge_width 0.5)
			(island_removal_mode 1)
			(island_area_min 10)
		)
		(polygon
			(pts
				(xy 120.787723 151.286111) (xy 120.831092 151.313136) (xy 120.875651 151.353058) (xy 120.914494 151.402056)
				(xy 120.944782 151.460276) (xy 120.961517 151.524311) (xy 121.250707 151.290707) (xy 120.973202 151.038202)
				(xy 120.953664 151.122843) (xy 120.929522 151.177176) (xy 120.910194 151.196939) (xy 120.888961 151.201719)
				(xy 120.876111 151.197723)
			)
		)
	)
	(zone
		(net 78)
		(net_name "+1V8")
		(layer "B.Cu")
		(name "$teardrop_padvia$")
		(hatch none 0.1)
		(priority 30385)
		(attr
			(teardrop
				(type padvia)
			)
		)
		(connect_pads yes
			(clearance 0)
		)
		(min_thickness 0.0254)
		(filled_areas_thickness no)
		(fill yes
			(thermal_gap 0.5)
			(thermal_bridge_width 0.5)
			(island_removal_mode 1)
			(island_area_min 10)
		)
		(polygon
			(pts
				(xy 125.6725 136.498) (xy 125.692469 136.435134) (xy 125.718921 136.403156) (xy 125.756332 136.374642)
				(xy 125.803527 136.352118) (xy 125.861167 136.336907) (xy 125.861798 136.336798) (xy 125.61 136.059)
				(xy 125.358202 136.336798) (xy 125.413635 136.351095) (xy 125.45952 136.372175) (xy 125.497201 136.39954)
				(xy 125.524434 136.430448) (xy 125.541472 136.463735) (xy 125.547489 136.496566) (xy 125.5475 136.498)
			)
		)
	)
	(zone
		(net 53)
		(net_name "/2xSFP+/SH")
		(layer "B.Cu")
		(name "$teardrop_padvia$")
		(hatch none 0.1)
		(priority 30013)
		(attr
			(teardrop
				(type padvia)
			)
		)
		(connect_pads yes
			(clearance 0)
		)
		(min_thickness 0.0254)
		(filled_areas_thickness no)
		(fill yes
			(thermal_gap 0.5)
			(thermal_bridge_width 0.5)
			(island_removal_mode 1)
			(island_area_min 10)
		)
		(polygon
			(pts
				(xy 109.785589 169.285) (xy 109.661824 169.280126) (xy 109.556865 169.266004) (xy 109.472229 169.244911)
				(xy 109.398644 169.216905) (xy 109.268431 169.138799) (xy 109.133797 169.024942) (xy 109.015402 168.922104)
				(xy 108.866678 168.811398) (xy 108.449 169.435) (xy 108.866678 170.058602) (xy 109.055228 169.914406)
				(xy 109.133796 169.845058) (xy 109.256074 169.740584) (xy 109.387489 169.658282) (xy 109.465048 169.627384)
				(xy 109.555005 169.604354) (xy 109.660728 169.589968) (xy 109.785589 169.585)
			)
		)
	)
	(zone
		(net 1)
		(net_name "GND")
		(layer "B.Cu")
		(name "$teardrop_padvia$")
		(hatch none 0.1)
		(priority 30119)
		(attr
			(teardrop
				(type padvia)
			)
		)
		(connect_pads yes
			(clearance 0)
		)
		(min_thickness 0.0254)
		(filled_areas_thickness no)
		(fill yes
			(thermal_gap 0.5)
			(thermal_bridge_width 0.5)
			(island_removal_mode 1)
			(island_area_min 10)
		)
		(polygon
			(pts
				(xy 147.7 131.86) (xy 147.689687 131.822995) (xy 147.678605 131.789412) (xy 147.680064 131.75524)
				(xy 147.707967 131.723346) (xy 147.776214 131.696598) (xy 147.3 131.377) (xy 147.047573 131.778)
				(xy 147.143188 131.782695) (xy 147.190256 131.795558) (xy 147.202668 131.807975) (xy 147.205133 131.822727)
				(xy 147.202763 131.838488) (xy 147.2 131.86)
			)
		)
	)
	(zone
		(net 652)
		(net_name "/2xSFP+/KR to SFI #1/PRBSEN")
		(layer "B.Cu")
		(name "$teardrop_padvia$")
		(hatch none 0.1)
		(priority 30756)
		(attr
			(teardrop
				(type padvia)
			)
		)
		(connect_pads yes
			(clearance 0)
		)
		(min_thickness 0.0254)
		(filled_areas_thickness no)
		(fill yes
			(thermal_gap 0.5)
			(thermal_bridge_width 0.5)
			(island_removal_mode 1)
			(island_area_min 10)
		)
		(polygon
			(pts
				(xy 155.689127 139.532485) (xy 155.636618 139.578181) (xy 155.590623 139.604768) (xy 155.504174 139.625152)
				(xy 155.488841 139.626988) (xy 155.406105 139.639323) (xy 155.449293 139.860707) (xy 155.670677 139.903895)
				(xy 155.683011 139.82116) (xy 155.703349 139.723881) (xy 155.730057 139.675841) (xy 155.777515 139.620873)
			)
		)
	)
	(zone
		(net 2)
		(net_name "+3V3")
		(layer "B.Cu")
		(name "$teardrop_padvia$")
		(hatch none 0.1)
		(priority 30910)
		(attr
			(teardrop
				(type padvia)
			)
		)
		(connect_pads yes
			(clearance 0)
		)
		(min_thickness 0.0254)
		(filled_areas_thickness no)
		(fill yes
			(thermal_gap 0.5)
			(thermal_bridge_width 0.5)
			(island_removal_mode 1)
			(island_area_min 10)
		)
		(polygon
			(pts
				(xy 115.9635 149.5355) (xy 115.963404 149.529178) (xy 115.968989 149.489675) (xy 115.983922 149.471452)
				(xy 116.0135 149.458504) (xy 115.901 149.047) (xy 115.7885 149.458504) (xy 115.815493 149.46962)
				(xy 115.830595 149.485147) (xy 115.838596 149.529178) (xy 115.8385 149.5355)
			)
		)
	)
	(zone
		(net 293)
		(net_name "/2xUSB3.0+RJ45/GbE.MDI1+")
		(layer "B.Cu")
		(name "$teardrop_padvia$")
		(hatch none 0.1)
		(priority 30663)
		(attr
			(teardrop
				(type padvia)
			)
		)
		(connect_pads yes
			(clearance 0)
		)
		(min_thickness 0.0254)
		(filled_areas_thickness no)
		(fill yes
			(thermal_gap 0.5)
			(thermal_bridge_width 0.5)
			(island_removal_mode 1)
			(island_area_min 10)
		)
		(polygon
			(pts
				(xy 180.375 167.057916) (xy 180.377203 167.2633) (xy 180.379323 167.401757) (xy 180.6 167.401) (xy 180.725003 167.212919)
				(xy 180.648862 167.179004) (xy 180.632261 167.173949) (xy 180.590719 167.160156) (xy 180.556601 167.140737)
				(xy 180.533499 167.108917) (xy 180.525 167.057916)
			)
		)
	)
	(zone
		(net 879)
		(net_name "/2xSFP+/SFI1.TX+")
		(layer "B.Cu")
		(name "$teardrop_padvia$")
		(hatch none 0.1)
		(priority 30067)
		(attr
			(teardrop
				(type padvia)
			)
		)
		(connect_pads yes
			(clearance 0)
		)
		(min_thickness 0.0254)
		(filled_areas_thickness no)
		(fill yes
			(thermal_gap 0.5)
			(thermal_bridge_width 0.5)
			(island_removal_mode 1)
			(island_area_min 10)
		)
		(polygon
			(pts
				(xy 138.3 165.009999) (xy 138.506564 165.004965) (xy 138.652843 164.989727) (xy 138.809533 164.960679)
				(xy 138.958177 164.931738) (xy 138.881 164.51) (xy 138.458262 164.426111) (xy 138.448684 164.551615)
				(xy 138.449874 164.607381) (xy 138.450114 164.701163) (xy 138.435175 164.778355) (xy 138.417344 164.808154)
				(xy 138.390117 164.830714) (xy 138.351624 164.845006) (xy 138.3 164.849999)
			)
		)
	)
	(zone
		(net 53)
		(net_name "/2xSFP+/SH")
		(layer "B.Cu")
		(name "$teardrop_padvia$")
		(hatch none 0.1)
		(priority 30238)
		(attr
			(teardrop
				(type padvia)
			)
		)
		(connect_pads yes
			(clearance 0)
		)
		(min_thickness 0.0254)
		(filled_areas_thickness no)
		(fill yes
			(thermal_gap 0.5)
			(thermal_bridge_width 0.5)
			(island_removal_mode 1)
			(island_area_min 10)
		)
		(polygon
			(pts
				(xy 124.3 156.247) (xy 124.300337 156.26209) (xy 124.29976 156.302326) (xy 124.287946 156.34387)
				(xy 124.253367 156.379164) (xy 124.1845 156.400652) (xy 124.45 156.661) (xy 124.7155 156.400652)
				(xy 124.669062 156.389708) (xy 124.636865 156.372609) (xy 124.605422 156.328144) (xy 124.599663 156.26209)
				(xy 124.6 156.247)
			)
		)
	)
	(zone
		(net 142)
		(net_name "/2xSFP+/PHY0_{RESET}")
		(layer "B.Cu")
		(name "$teardrop_padvia$")
		(hatch none 0.1)
		(priority 30327)
		(attr
			(teardrop
				(type padvia)
			)
		)
		(connect_pads yes
			(clearance 0)
		)
		(min_thickness 0.0254)
		(filled_areas_thickness no)
		(fill yes
			(thermal_gap 0.5)
			(thermal_bridge_width 0.5)
			(island_removal_mode 1)
			(island_area_min 10)
		)
		(polygon
			(pts
				(xy 141.7375 135.3905) (xy 141.717779 135.443377) (xy 141.655836 135.487969) (xy 141.607362 135.502969)
				(xy 141.548175 135.510127) (xy 141.53 135.5105) (xy 141.8 135.8115) (xy 142.07 135.5105) (xy 142.00779 135.505778)
				(xy 141.956261 135.492726) (xy 141.915671 135.473001) (xy 141.886328 135.448281) (xy 141.868989 135.421376)
				(xy 141.862538 135.392886) (xy 141.8625 135.3905)
			)
		)
	)
	(zone
		(net 53)
		(net_name "/2xSFP+/SH")
		(layer "B.Cu")
		(name "$teardrop_padvia$")
		(hatch none 0.1)
		(priority 30214)
		(attr
			(teardrop
				(type padvia)
			)
		)
		(connect_pads yes
			(clearance 0)
		)
		(min_thickness 0.0254)
		(filled_areas_thickness no)
		(fill yes
			(thermal_gap 0.5)
			(thermal_bridge_width 0.5)
			(island_removal_mode 1)
			(island_area_min 10)
		)
		(polygon
			(pts
				(xy 117.85 169.522) (xy 117.850338 169.53887) (xy 117.849759 169.583826) (xy 117.837941 169.631169)
				(xy 117.803362 169.673573) (xy 117.7345 169.703708) (xy 118 169.961) (xy 118.2655 169.703708) (xy 118.220731 169.688151)
				(xy 118.189115 169.667435) (xy 118.156381 169.616299) (xy 118.149662 169.53887) (xy 118.15 169.522)
			)
		)
	)
	(zone
		(net 2)
		(net_name "+3V3")
		(layer "B.Cu")
		(name "$teardrop_padvia$")
		(hatch none 0.1)
		(priority 30786)
		(attr
			(teardrop
				(type padvia)
			)
		)
		(connect_pads yes
			(clearance 0)
		)
		(min_thickness 0.0254)
		(filled_areas_thickness no)
		(fill yes
			(thermal_gap 0.5)
			(thermal_bridge_width 0.5)
			(island_removal_mode 1)
			(island_area_min 10)
		)
		(polygon
			(pts
				(xy 303.377515 102.499127) (xy 303.331819 102.446618) (xy 303.305231 102.400623) (xy 303.284847 102.314175)
				(xy 303.283011 102.29884) (xy 303.270677 102.216105) (xy 303.049293 102.259293) (xy 303.006105 102.480677)
				(xy 303.08884 102.493011) (xy 303.186119 102.513349) (xy 303.234159 102.540057) (xy 303.289127 102.587515)
			)
		)
	)
	(zone
		(net 1)
		(net_name "GND")
		(layer "B.Cu")
		(name "$teardrop_padvia$")
		(hatch none 0.1)
		(priority 30681)
		(attr
			(teardrop
				(type padvia)
			)
		)
		(connect_pads yes
			(clearance 0)
		)
		(min_thickness 0.0254)
		(filled_areas_thickness no)
		(fill yes
			(thermal_gap 0.5)
			(thermal_bridge_width 0.5)
			(island_removal_mode 1)
			(island_area_min 10)
		)
		(polygon
			(pts
				(xy 105.524323 165.6725) (xy 105.598953 165.677387) (xy 105.653392 165.691599) (xy 105.742929 165.746498)
				(xy 105.799997 165.787081) (xy 105.926 165.6) (xy 105.799997 165.412919) (xy 105.725321 165.470692)
				(xy 105.646254 165.526019) (xy 105.594813 165.541845) (xy 105.524323 165.5475)
			)
		)
	)
	(zone
		(net 432)
		(net_name "/2xSFP+/10GKR_SFP0.RX+")
		(layer "B.Cu")
		(name "$teardrop_padvia$")
		(hatch none 0.1)
		(priority 30625)
		(attr
			(teardrop
				(type padvia)
			)
		)
		(connect_pads yes
			(clearance 0)
		)
		(min_thickness 0.0254)
		(filled_areas_thickness no)
		(fill yes
			(thermal_gap 0.5)
			(thermal_bridge_width 0.5)
			(island_removal_mode 1)
			(island_area_min 10)
		)
		(polygon
			(pts
				(xy 153.22 147.977084) (xy 153.224756 147.936299) (xy 153.238046 147.906971) (xy 153.282406 147.872311)
				(xy 153.325219 147.855729) (xy 153.410003 147.817081) (xy 153.285 147.629) (xy 153.064323 147.632143)
				(xy 153.062568 147.797771) (xy 153.06 147.977084)
			)
		)
	)
	(zone
		(net 95)
		(net_name "/OCuLink/PCIe_{x4}.TX0-")
		(layer "B.Cu")
		(name "$teardrop_padvia$")
		(hatch none 0.1)
		(priority 30996)
		(attr
			(teardrop
				(type padvia)
			)
		)
		(connect_pads yes
			(clearance 0)
		)
		(min_thickness 0.0254)
		(filled_areas_thickness no)
		(fill yes
			(thermal_gap 0.5)
			(thermal_bridge_width 0.5)
			(island_removal_mode 1)
			(island_area_min 10)
		)
		(polygon
			(pts
				(xy 104.83 166.211) (xy 104.850648 166.203802) (xy 104.882984 166.194208) (xy 104.897007 166.201035)
				(xy 104.906995 166.2225) (xy 105.156 166.11) (xy 104.906995 165.9975) (xy 104.897271 166.018676)
				(xy 104.883643 166.025731) (xy 104.850648 166.016198) (xy 104.83 166.009)
			)
		)
	)
	(zone
		(net 264)
		(net_name "/Com Express 7 Interfaces/PCIe_{B2Bx4}.RX0+")
		(layer "B.Cu")
		(name "$teardrop_padvia$")
		(hatch none 0.1)
		(priority 30309)
		(attr
			(teardrop
				(type padvia)
			)
		)
		(connect_pads yes
			(clearance 0)
		)
		(min_thickness 0.0254)
		(filled_areas_thickness no)
		(fill yes
			(thermal_gap 0.5)
			(thermal_bridge_width 0.5)
			(island_removal_mode 1)
			(island_area_min 10)
		)
		(polygon
			(pts
				(xy 175.39 102.961) (xy 175.404678 102.957463) (xy 175.434685 102.954192) (xy 175.445673 102.966143)
				(xy 175.45 102.995) (xy 176.201 102.86) (xy 175.45 102.725) (xy 175.445525 102.754204) (xy 175.434203 102.765997)
				(xy 175.404678 102.762537) (xy 175.39 102.759)
			)
		)
	)
	(zone
		(net 624)
		(net_name "/PCIe redriver/TX_EQ1")
		(layer "B.Cu")
		(name "$teardrop_padvia$")
		(hatch none 0.1)
		(priority 30893)
		(attr
			(teardrop
				(type padvia)
			)
		)
		(connect_pads yes
			(clearance 0)
		)
		(min_thickness 0.0254)
		(filled_areas_thickness no)
		(fill yes
			(thermal_gap 0.5)
			(thermal_bridge_width 0.5)
			(island_removal_mode 1)
			(island_area_min 10)
		)
		(polygon
			(pts
				(xy 112.4755 147.6725) (xy 112.481683 147.672407) (xy 112.520744 147.678026) (xy 112.538663 147.693003)
				(xy 112.551231 147.722655) (xy 112.964 147.611) (xy 112.553752 147.497659) (xy 112.542345 147.524517)
				(xy 112.526608 147.539575) (xy 112.481963 147.547599) (xy 112.4755 147.5475)
			)
		)
	)
	(zone
		(net 869)
		(net_name "/Backplane/PCIe_{x2}.TX1-")
		(layer "B.Cu")
		(name "$teardrop_padvia$")
		(hatch none 0.1)
		(priority 30042)
		(attr
			(teardrop
				(type padvia)
			)
		)
		(connect_pads yes
			(clearance 0)
		)
		(min_thickness 0.0254)
		(filled_areas_thickness no)
		(fill yes
			(thermal_gap 0.5)
			(thermal_bridge_width 0.5)
			(island_removal_mode 1)
			(island_area_min 10)
		)
		(polygon
			(pts
				(xy 317.860744 162.4055) (xy 317.893777 162.411457) (xy 317.923712 162.433158) (xy 317.939644 162.460607)
				(xy 317.949306 162.500407) (xy 317.95 162.565591) (xy 319.451 162.51) (xy 319.254117 162.235) (xy 318.774522 162.244225)
				(xy 318.255858 162.220754) (xy 317.860744 162.2035)
			)
		)
	)
	(zone
		(net 974)
		(net_name "/PCIe redriver/RX_FG1")
		(layer "B.Cu")
		(name "$teardrop_padvia$")
		(hatch none 0.1)
		(priority 30698)
		(attr
			(teardrop
				(type padvia)
			)
		)
		(connect_pads yes
			(clearance 0)
		)
		(min_thickness 0.0254)
		(filled_areas_thickness no)
		(fill yes
			(thermal_gap 0.5)
			(thermal_bridge_width 0.5)
			(island_removal_mode 1)
			(island_area_min 10)
		)
		(polygon
			(pts
				(xy 191.964529 140.837117) (xy 191.959711 140.906557) (xy 191.945989 140.957881) (xy 191.899274 141.033422)
				(xy 191.889731 141.045562) (xy 191.839948 141.112791) (xy 192.027029 141.238794) (xy 192.21411 141.112791)
				(xy 192.164328 141.045563) (xy 192.109923 140.962397) (xy 192.094839 140.909542) (xy 192.089529 140.837117)
			)
		)
	)
	(zone
		(net 347)
		(net_name "/2xUSB3.0+RJ45/~{GBE0_ACT}")
		(layer "B.Cu")
		(name "$teardrop_padvia$")
		(hatch none 0.1)
		(priority 30787)
		(attr
			(teardrop
				(type padvia)
			)
		)
		(connect_pads yes
			(clearance 0)
		)
		(min_thickness 0.0254)
		(filled_areas_thickness no)
		(fill yes
			(thermal_gap 0.5)
			(thermal_bridge_width 0.5)
			(island_removal_mode 1)
			(island_area_min 10)
		)
		(polygon
			(pts
				(xy 164.627515 114.839127) (xy 164.581819 114.786618) (xy 164.555231 114.740623) (xy 164.534847 114.654175)
				(xy 164.533011 114.63884) (xy 164.520677 114.556105) (xy 164.299293 114.599293) (xy 164.256105 114.820677)
				(xy 164.33884 114.833011) (xy 164.436119 114.853349) (xy 164.484159 114.880057) (xy 164.539127 114.927515)
			)
		)
	)
	(zone
		(net 262)
		(net_name "/Com Express 7 Interfaces/PCIe_{B2Bx4}.RX0-")
		(layer "B.Cu")
		(name "$teardrop_padvia$")
		(hatch none 0.1)
		(priority 30570)
		(attr
			(teardrop
				(type padvia)
			)
		)
		(connect_pads yes
			(clearance 0)
		)
		(min_thickness 0.0254)
		(filled_areas_thickness no)
		(fill yes
			(thermal_gap 0.5)
			(thermal_bridge_width 0.5)
			(island_removal_mode 1)
			(island_area_min 10)
		)
		(polygon
			(pts
				(xy 173.967496 103.2035) (xy 173.805964 103.208895) (xy 173.721554 103.212445) (xy 173.61986 103.207823)
				(xy 173.599 103.4285) (xy 173.748852 103.591731) (xy 173.802992 103.523062) (xy 173.812883 103.506608)
				(xy 173.837383 103.467935) (xy 173.86689 103.435721) (xy 173.908046 103.413673) (xy 173.967496 103.4055)
			)
		)
	)
	(zone
		(net 531)
		(net_name "/Com Express 7 Interfaces/SD_CD")
		(layer "B.Cu")
		(name "$teardrop_padvia$")
		(hatch none 0.1)
		(priority 30746)
		(attr
			(teardrop
				(type padvia)
			)
		)
		(connect_pads yes
			(clearance 0)
		)
		(min_thickness 0.0254)
		(filled_areas_thickness no)
		(fill yes
			(thermal_gap 0.5)
			(thermal_bridge_width 0.5)
			(island_removal_mode 1)
			(island_area_min 10)
		)
		(polygon
			(pts
				(xy 138.750677 151.9375) (xy 138.681236 151.932682) (xy 138.629913 151.91896) (xy 138.554371 151.872246)
				(xy 138.542231 151.862701) (xy 138.475003 151.812919) (xy 138.349 152) (xy 138.475003 152.187081)
				(xy 138.542229 152.137299) (xy 138.625396 152.082894) (xy 138.678251 152.06781) (xy 138.750677 152.0625)
			)
		)
	)
	(zone
		(net 200)
		(net_name "/OCuLink/~{PERST_D0}")
		(layer "B.Cu")
		(name "$teardrop_padvia$")
		(hatch none 0.1)
		(priority 30375)
		(attr
			(teardrop
				(type padvia)
			)
		)
		(connect_pads yes
			(clearance 0)
		)
		(min_thickness 0.0254)
		(filled_areas_thickness no)
		(fill yes
			(thermal_gap 0.5)
			(thermal_bridge_width 0.5)
			(island_removal_mode 1)
			(island_area_min 10)
		)
		(polygon
			(pts
				(xy 121.2825 162.998) (xy 121.302469 162.935134) (xy 121.328921 162.903156) (xy 121.366332 162.874642)
				(xy 121.413527 162.852118) (xy 121.471167 162.836907) (xy 121.471798 162.836798) (xy 121.22 162.559)
				(xy 120.968202 162.836798) (xy 121.023635 162.851095) (xy 121.06952 162.872175) (xy 121.107201 162.89954)
				(xy 121.134434 162.930448) (xy 121.151472 162.963735) (xy 121.157489 162.996566) (xy 121.1575 162.998)
			)
		)
	)
	(zone
		(net 712)
		(net_name "Net-(U39-SDA)")
		(layer "B.Cu")
		(name "$teardrop_padvia$")
		(hatch none 0.1)
		(priority 30096)
		(attr
			(teardrop
				(type padvia)
			)
		)
		(connect_pads yes
			(clearance 0)
		)
		(min_thickness 0.0254)
		(filled_areas_thickness no)
		(fill yes
			(thermal_gap 0.5)
			(thermal_bridge_width 0.5)
			(island_removal_mode 1)
			(island_area_min 10)
		)
		(polygon
			(pts
				(xy 122.971993 146.226396) (xy 123.033423 146.171775) (xy 123.08932 146.135259) (xy 123.188191 146.102229)
				(xy 123.291905 146.09498) (xy 123.375099 146.091201) (xy 123.473159 146.077794) (xy 123.400707 145.709293)
				(xy 123.032206 145.636841) (xy 123.01583 145.790423) (xy 123.01502 145.818096) (xy 123.010967 145.897317)
				(xy 122.995512 145.972488) (xy 122.956956 146.050441) (xy 122.883604 146.138007)
			)
		)
	)
	(zone
		(net 102)
		(net_name "/OCuLink/PCIe_{x4}.TX1+")
		(layer "B.Cu")
		(name "$teardrop_padvia$")
		(hatch none 0.1)
		(priority 30979)
		(attr
			(teardrop
				(type padvia)
			)
		)
		(connect_pads yes
			(clearance 0)
		)
		(min_thickness 0.0254)
		(filled_areas_thickness no)
		(fill yes
			(thermal_gap 0.5)
			(thermal_bridge_width 0.5)
			(island_removal_mode 1)
			(island_area_min 10)
		)
		(polygon
			(pts
				(xy 104.83 165.213) (xy 104.850648 165.205802) (xy 104.882984 165.196208) (xy 104.897007 165.203035)
				(xy 104.906995 165.2245) (xy 105.156 165.112) (xy 104.906995 164.9995) (xy 104.897271 165.020676)
				(xy 104.883643 165.027731) (xy 104.850648 165.018198) (xy 104.83 165.011)
			)
		)
	)
	(zone
		(net 1)
		(net_name "GND")
		(layer "B.Cu")
		(name "$teardrop_padvia$")
		(hatch none 0.1)
		(priority 30158)
		(attr
			(teardrop
				(type padvia)
			)
		)
		(connect_pads yes
			(clearance 0)
		)
		(min_thickness 0.0254)
		(filled_areas_thickness no)
		(fill yes
			(thermal_gap 0.5)
			(thermal_bridge_width 0.5)
			(island_removal_mode 1)
			(island_area_min 10)
		)
		(polygon
			(pts
				(xy 241.727708 78.385) (xy 241.772354 78.364597) (xy 241.8059 78.345779) (xy 241.838364 78.337205)
				(xy 241.865074 78.351303) (xy 241.881361 78.4005) (xy 242.141708 78.135) (xy 241.881361 77.8695)
				(xy 241.871541 77.907593) (xy 241.856134 77.927358) (xy 241.821809 77.930352) (xy 241.772354 77.905403)
				(xy 241.727708 77.885)
			)
		)
	)
	(zone
		(net 104)
		(net_name "/OCuLink/PCIe_{x4}.TX2+")
		(layer "B.Cu")
		(name "$teardrop_padvia$")
		(hatch none 0.1)
		(priority 31014)
		(attr
			(teardrop
				(type padvia)
			)
		)
		(connect_pads yes
			(clearance 0)
		)
		(min_thickness 0.0254)
		(filled_areas_thickness no)
		(fill yes
			(thermal_gap 0.5)
			(thermal_bridge_width 0.5)
			(island_removal_mode 1)
			(island_area_min 10)
		)
		(polygon
			(pts
				(xy 105.48 160.509) (xy 105.459352 160.516199) (xy 105.427017 160.525792) (xy 105.412994 160.518965)
				(xy 105.403005 160.4975) (xy 105.154 160.61) (xy 105.403005 160.7225) (xy 105.41273 160.701324)
				(xy 105.426358 160.694269) (xy 105.459352 160.703801) (xy 105.48 160.711)
			)
		)
	)
	(zone
		(net 155)
		(net_name "Net-(J1A-LED_D2)")
		(layer "B.Cu")
		(name "$teardrop_padvia$")
		(hatch none 0.1)
		(priority 30381)
		(attr
			(teardrop
				(type padvia)
			)
		)
		(connect_pads yes
			(clearance 0)
		)
		(min_thickness 0.0254)
		(filled_areas_thickness no)
		(fill yes
			(thermal_gap 0.5)
			(thermal_bridge_width 0.5)
			(island_removal_mode 1)
			(island_area_min 10)
		)
		(polygon
			(pts
				(xy 122.9825 100.298) (xy 123.002469 100.235134) (xy 123.028921 100.203156) (xy 123.066332 100.174642)
				(xy 123.113527 100.152118) (xy 123.171167 100.136907) (xy 123.171798 100.136798) (xy 122.92 99.859)
				(xy 122.668202 100.136798) (xy 122.723635 100.151095) (xy 122.76952 100.172175) (xy 122.807201 100.19954)
				(xy 122.834434 100.230448) (xy 122.851472 100.263735) (xy 122.857489 100.296566) (xy 122.8575 100.298)
			)
		)
	)
	(zone
		(net 2)
		(net_name "+3V3")
		(layer "B.Cu")
		(name "$teardrop_padvia$")
		(hatch none 0.1)
		(priority 30076)
		(attr
			(teardrop
				(type padvia)
			)
		)
		(connect_pads yes
			(clearance 0)
		)
		(min_thickness 0.0254)
		(filled_areas_thickness no)
		(fill yes
			(thermal_gap 0.5)
			(thermal_bridge_width 0.5)
			(island_removal_mode 1)
			(island_area_min 10)
		)
		(polygon
			(pts
				(xy 219 129.51) (xy 219.006939 129.450279) (xy 219.035514 129.387956) (xy 219.065032 129.35657)
				(xy 219.106823 129.330086) (xy 219.203137 129.303137) (xy 218.85 128.849) (xy 218.496863 129.303137)
				(xy 218.55633 129.315794) (xy 218.603161 129.335189) (xy 218.664802 129.388393) (xy 218.694809 129.45783)
				(xy 218.7 129.51)
			)
		)
	)
	(zone
		(net 1)
		(net_name "GND")
		(layer "B.Cu")
		(name "$teardrop_padvia$")
		(hatch none 0.1)
		(priority 30289)
		(attr
			(teardrop
				(type padvia)
			)
		)
		(connect_pads yes
			(clearance 0)
		)
		(min_thickness 0.0254)
		(filled_areas_thickness no)
		(fill yes
			(thermal_gap 0.5)
			(thermal_bridge_width 0.5)
			(island_removal_mode 1)
			(island_area_min 10)
		)
		(polygon
			(pts
				(xy 99.7 85.898) (xy 99.705641 85.857701) (xy 99.72513 85.816184) (xy 99.752195 85.786269) (xy 99.79167 85.760795)
				(xy 99.871798 85.736798) (xy 99.62 85.459) (xy 99.368202 85.736798) (xy 99.411653 85.74965) (xy 99.44451 85.768706)
				(xy 99.485304 85.821027) (xy 99.5 85.898)
			)
		)
	)
	(zone
		(net 958)
		(net_name "/PCIe redriver/PCIe_{I}_C.RX1+")
		(layer "B.Cu")
		(name "$teardrop_padvia$")
		(hatch none 0.1)
		(priority 30885)
		(attr
			(teardrop
				(type padvia)
			)
		)
		(connect_pads yes
			(clearance 0)
		)
		(min_thickness 0.0254)
		(filled_areas_thickness no)
		(fill yes
			(thermal_gap 0.5)
			(thermal_bridge_width 0.5)
			(island_removal_mode 1)
			(island_area_min 10)
		)
		(polygon
			(pts
				(xy 195.554432 137.056319) (xy 195.534741 137.046808) (xy 195.505093 137.030727) (xy 195.500005 137.015984)
				(xy 195.50812 136.993742) (xy 195.137593 136.782315) (xy 195.34902 137.152842) (xy 195.370871 137.144745)
				(xy 195.385496 137.149393) (xy 195.402086 137.179463) (xy 195.411597 137.199154)
			)
		)
	)
	(zone
		(net 188)
		(net_name "/OCuLink/PCIe_{x4}.RX1+")
		(layer "B.Cu")
		(name "$teardrop_padvia$")
		(hatch none 0.1)
		(priority 30840)
		(attr
			(teardrop
				(type padvia)
			)
		)
		(connect_pads yes
			(clearance 0)
		)
		(min_thickness 0.0254)
		(filled_areas_thickness no)
		(fill yes
			(thermal_gap 0.5)
			(thermal_bridge_width 0.5)
			(island_removal_mode 1)
			(island_area_min 10)
		)
		(polygon
			(pts
				(xy 192.374926 134.083995) (xy 192.389151 134.089795) (xy 192.411629 134.101167) (xy 192.411939 134.113107)
				(xy 192.397736 134.132156) (xy 192.752521 134.397243) (xy 192.767617 134.235563) (xy 192.671126 134.152197)
				(xy 192.584918 134.032967) (xy 192.517761 133.94116)
			)
		)
	)
	(zone
		(net 681)
		(net_name "Net-(U45B-~{PDTRXB})")
		(layer "B.Cu")
		(name "$teardrop_padvia$")
		(hatch none 0.1)
		(priority 30653)
		(attr
			(teardrop
				(type padvia)
			)
		)
		(connect_pads yes
			(clearance 0)
		)
		(min_thickness 0.0254)
		(filled_areas_thickness no)
		(fill yes
			(thermal_gap 0.5)
			(thermal_bridge_width 0.5)
			(island_removal_mode 1)
			(island_area_min 10)
		)
		(polygon
			(pts
				(xy 130.619924 134.751688) (xy 130.589854 134.775005) (xy 130.562404 134.783475) (xy 130.51631 134.769541)
				(xy 130.463593 134.724224) (xy 130.411088 134.677548) (xy 130.347799 134.645082) (xy 130.289293 134.860707)
				(xy 130.418157 135.043926) (xy 130.527443 134.976673) (xy 130.608371 134.926997) (xy 130.708312 134.840076)
			)
		)
	)
	(zone
		(net 350)
		(net_name "Net-(J12D-LPC_AD1{slash}ESPI_IO_1)")
		(layer "B.Cu")
		(name "$teardrop_padvia$")
		(hatch none 0.1)
		(priority 30114)
		(attr
			(teardrop
				(type padvia)
			)
		)
		(connect_pads yes
			(clearance 0)
		)
		(min_thickness 0.0254)
		(filled_areas_thickness no)
		(fill yes
			(thermal_gap 0.5)
			(thermal_bridge_width 0.5)
			(island_removal_mode 1)
			(island_area_min 10)
		)
		(polygon
			(pts
				(xy 176.766396 164.228007) (xy 176.711775 164.166577) (xy 176.675259 164.11068) (xy 176.642229 164.011809)
				(xy 176.63498 163.908095) (xy 176.631201 163.8249) (xy 176.617794 163.726841) (xy 176.249293 163.799293)
				(xy 176.176841 164.167794) (xy 176.330423 164.184169) (xy 176.358095 164.18498) (xy 176.437316 164.189032)
				(xy 176.512488 164.204488) (xy 176.590441 164.243043) (xy 176.678007 164.316396)
			)
		)
	)
	(zone
		(net 1)
		(net_name "GND")
		(layer "B.Cu")
		(name "$teardrop_padvia$")
		(hatch none 0.1)
		(priority 30463)
		(attr
			(teardrop
				(type padvia)
			)
		)
		(connect_pads yes
			(clearance 0)
		)
		(min_thickness 0.0254)
		(filled_areas_thickness no)
		(fill yes
			(thermal_gap 0.5)
			(thermal_bridge_width 0.5)
			(island_removal_mode 1)
			(island_area_min 10)
		)
		(polygon
			(pts
				(xy 124.44261 149.395969) (xy 124.387888 149.444023) (xy 124.339621 149.473902) (xy 124.240703 149.505439)
				(xy 124.146795 149.531463) (xy 124.219293 149.740707) (xy 124.422261 149.828355) (xy 124.455228 149.743095)
				(xy 124.496451 149.646719) (xy 124.53092 149.596254) (xy 124.584031 149.53739)
			)
		)
	)
	(zone
		(net 575)
		(net_name "Net-(U18-MODE)")
		(layer "B.Cu")
		(name "$teardrop_padvia$")
		(hatch none 0.1)
		(priority 30641)
		(attr
			(teardrop
				(type padvia)
			)
		)
		(connect_pads yes
			(clearance 0)
		)
		(min_thickness 0.0254)
		(filled_areas_thickness no)
		(fill yes
			(thermal_gap 0.5)
			(thermal_bridge_width 0.5)
			(island_removal_mode 1)
			(island_area_min 10)
		)
		(polygon
			(pts
				(xy 309.575872 121.777515) (xy 309.624602 121.73553) (xy 309.668036 121.711031) (xy 309.749841 121.693767)
				(xy 309.771285 121.692237) (xy 309.868894 121.680677) (xy 309.825706 121.459293) (xy 309.622737 121.371645)
				(xy 309.589771 121.481457) (xy 309.586976 121.495947) (xy 309.561758 121.58701) (xy 309.533988 121.635109)
				(xy 309.487484 121.689127)
			)
		)
	)
	(zone
		(net 1)
		(net_name "GND")
		(layer "B.Cu")
		(name "$teardrop_padvia$")
		(hatch none 0.1)
		(priority 30054)
		(attr
			(teardrop
				(type padvia)
			)
		)
		(connect_pads yes
			(clearance 0)
		)
		(min_thickness 0.0254)
		(filled_areas_thickness no)
		(fill yes
			(thermal_gap 0.5)
			(thermal_bridge_width 0.5)
			(island_removal_mode 1)
			(island_area_min 10)
		)
		(polygon
			(pts
				(xy 265.982115 73.380042) (xy 265.940329 73.430147) (xy 265.892226 73.4885) (xy 265.831368 73.53989)
				(xy 265.751557 73.568872) (xy 265.702606 73.570133) (xy 265.646592 73.56) (xy 265.655002 74.060707)
				(xy 266.055709 74.169116) (xy 266.059173 74.103793) (xy 266.071377 74.045697) (xy 266.119843 73.942942)
				(xy 266.201105 73.849913) (xy 266.270017 73.790822) (xy 266.335667 73.733594)
			)
		)
	)
	(zone
		(net 95)
		(net_name "/OCuLink/PCIe_{x4}.TX0-")
		(layer "B.Cu")
		(name "$teardrop_padvia$")
		(hatch none 0.1)
		(priority 30987)
		(attr
			(teardrop
				(type padvia)
			)
		)
		(connect_pads yes
			(clearance 0)
		)
		(min_thickness 0.0254)
		(filled_areas_thickness no)
		(fill yes
			(thermal_gap 0.5)
			(thermal_bridge_width 0.5)
			(island_removal_mode 1)
			(island_area_min 10)
		)
		(polygon
			(pts
				(xy 104.058 166.211) (xy 104.078648 166.203802) (xy 104.110984 166.194208) (xy 104.125007 166.201035)
				(xy 104.134995 166.2225) (xy 104.384 166.11) (xy 104.134995 165.9975) (xy 104.125271 166.018676)
				(xy 104.111643 166.025731) (xy 104.078648 166.016198) (xy 104.058 166.009)
			)
		)
	)
	(zone
		(net 53)
		(net_name "/2xSFP+/SH")
		(layer "B.Cu")
		(name "$teardrop_padvia$")
		(hatch none 0.1)
		(priority 30015)
		(attr
			(teardrop
				(type padvia)
			)
		)
		(connect_pads yes
			(clearance 0)
		)
		(min_thickness 0.0254)
		(filled_areas_thickness no)
		(fill yes
			(thermal_gap 0.5)
			(thermal_bridge_width 0.5)
			(island_removal_mode 1)
			(island_area_min 10)
		)
		(polygon
			(pts
				(xy 152.2 167.645589) (xy 152.204874 167.521824) (xy 152.218996 167.416865) (xy 152.240089 167.332229)
				(xy 152.268095 167.258643) (xy 152.346201 167.12843) (xy 152.460058 166.993796) (xy 152.562896 166.875401)
				(xy 152.673602 166.726678) (xy 152.05 166.309) (xy 151.426398 166.726678) (xy 151.570593 166.915228)
				(xy 151.639942 166.993797) (xy 151.744416 167.116075) (xy 151.826718 167.247489) (xy 151.857616 167.325049)
				(xy 151.880646 167.415005) (xy 151.895032 167.520728) (xy 151.9 167.645589)
			)
		)
	)
	(zone
		(net 193)
		(net_name "/OCuLink/PCIe_{REF0}.CK-")
		(layer "B.Cu")
		(name "$teardrop_padvia$")
		(hatch none 0.1)
		(priority 30520)
		(attr
			(teardrop
				(type padvia)
			)
		)
		(connect_pads yes
			(clearance 0)
		)
		(min_thickness 0.0254)
		(filled_areas_thickness no)
		(fill yes
			(thermal_gap 0.5)
			(thermal_bridge_width 0.5)
			(island_removal_mode 1)
			(island_area_min 10)
		)
		(polygon
			(pts
				(xy 99.396202 161.0545) (xy 99.349416 161.049765) (xy 99.313964 161.036621) (xy 99.265766 160.991613)
				(xy 99.24159 160.953392) (xy 99.21422 160.910225) (xy 99.177558 160.868268) (xy 99.027706 161.0315)
				(xy 99.048566 161.252177) (xy 99.149237 161.247548) (xy 99.232603 161.25098) (xy 99.23467 161.251105)
				(xy 99.396202 161.2565)
			)
		)
	)
	(zone
		(net 156)
		(net_name "Net-(J1A-LED_D3)")
		(layer "B.Cu")
		(name "$teardrop_padvia$")
		(hatch none 0.1)
		(priority 30384)
		(attr
			(teardrop
				(type padvia)
			)
		)
		(connect_pads yes
			(clearance 0)
		)
		(min_thickness 0.0254)
		(filled_areas_thickness no)
		(fill yes
			(thermal_gap 0.5)
			(thermal_bridge_width 0.5)
			(island_removal_mode 1)
			(island_area_min 10)
		)
		(polygon
			(pts
				(xy 122.9825 109.248) (xy 123.002469 109.185134) (xy 123.028921 109.153156) (xy 123.066332 109.124642)
				(xy 123.113527 109.102118) (xy 123.171167 109.086907) (xy 123.171798 109.086798) (xy 122.92 108.809)
				(xy 122.668202 109.086798) (xy 122.723635 109.101095) (xy 122.76952 109.122175) (xy 122.807201 109.14954)
				(xy 122.834434 109.180448) (xy 122.851472 109.213735) (xy 122.857489 109.246566) (xy 122.8575 109.248)
			)
		)
	)
	(zone
		(net 409)
		(net_name "Net-(J12K-10G_SDP2)")
		(layer "B.Cu")
		(name "$teardrop_padvia$")
		(hatch none 0.1)
		(priority 30092)
		(attr
			(teardrop
				(type padvia)
			)
		)
		(connect_pads yes
			(clearance 0)
		)
		(min_thickness 0.0254)
		(filled_areas_thickness no)
		(fill yes
			(thermal_gap 0.5)
			(thermal_bridge_width 0.5)
			(island_removal_mode 1)
			(island_area_min 10)
		)
		(polygon
			(pts
				(xy 180.7375 159.482206) (xy 180.732685 159.564266) (xy 180.718981 159.629611) (xy 180.672424 159.722879)
				(xy 180.604214 159.801341) (xy 180.548058 159.862841) (xy 180.488199 159.941661) (xy 180.8 160.151)
				(xy 181.111801 159.941661) (xy 181.014781 159.821482) (xy 180.995786 159.801341) (xy 180.942634 159.742458)
				(xy 180.900408 159.678375) (xy 180.87255 159.595992) (xy 180.8625 159.482206)
			)
		)
	)
	(zone
		(net 1)
		(net_name "GND")
		(layer "B.Cu")
		(name "$teardrop_padvia$")
		(hatch none 0.1)
		(priority 30867)
		(attr
			(teardrop
				(type padvia)
			)
		)
		(connect_pads yes
			(clearance 0)
		)
		(min_thickness 0.0254)
		(filled_areas_thickness no)
		(fill yes
			(thermal_gap 0.5)
			(thermal_bridge_width 0.5)
			(island_removal_mode 1)
			(island_area_min 10)
		)
		(polygon
			(pts
				(xy 123.43 104.4) (xy 123.440115 104.399847) (xy 123.470832 104.40046) (xy 123.50332 104.408782)
				(xy 123.532475 104.432675) (xy 123.553191 104.48) (xy 123.786 104.3) (xy 123.553191 104.12) (xy 123.539833 104.155901)
				(xy 123.521601 104.179199) (xy 123.476276 104.198899) (xy 123.440115 104.200153) (xy 123.43 104.2)
			)
		)
	)
	(zone
		(net 889)
		(net_name "/Power/PG_{3V3}")
		(layer "B.Cu")
		(name "$teardrop_padvia$")
		(hatch none 0.1)
		(priority 30752)
		(attr
			(teardrop
				(type padvia)
			)
		)
		(connect_pads yes
			(clearance 0)
		)
		(min_thickness 0.0254)
		(filled_areas_thickness no)
		(fill yes
			(thermal_gap 0.5)
			(thermal_bridge_width 0.5)
			(island_removal_mode 1)
			(island_area_min 10)
		)
		(polygon
			(pts
				(xy 312.314626 136.612485) (xy 312.262117 136.658181) (xy 312.216122 136.684768) (xy 312.129673 136.705152)
				(xy 312.11434 136.706988) (xy 312.031604 136.719323) (xy 312.074792 136.940707) (xy 312.296176 136.983895)
				(xy 312.30851 136.90116) (xy 312.328848 136.803881) (xy 312.355556 136.755841) (xy 312.403014 136.700873)
			)
		)
	)
	(zone
		(net 106)
		(net_name "/OCuLink/PCIe_{x4}.TX3+")
		(layer "B.Cu")
		(name "$teardrop_padvia$")
		(hatch none 0.1)
		(priority 30999)
		(attr
			(teardrop
				(type padvia)
			)
		)
		(connect_pads yes
			(clearance 0)
		)
		(min_thickness 0.0254)
		(filled_areas_thickness no)
		(fill yes
			(thermal_gap 0.5)
			(thermal_bridge_width 0.5)
			(island_removal_mode 1)
			(island_area_min 10)
		)
		(polygon
			(pts
				(xy 105.48 159.011) (xy 105.459352 159.018199) (xy 105.427017 159.027792) (xy 105.412994 159.020965)
				(xy 105.403005 158.9995) (xy 105.154 159.112) (xy 105.403005 159.2245) (xy 105.41273 159.203324)
				(xy 105.426358 159.196269) (xy 105.459352 159.205801) (xy 105.48 159.213)
			)
		)
	)
	(zone
		(net 1)
		(net_name "GND")
		(layer "B.Cu")
		(name "$teardrop_padvia$")
		(hatch none 0.1)
		(priority 30596)
		(attr
			(teardrop
				(type padvia)
			)
		)
		(connect_pads yes
			(clearance 0)
		)
		(min_thickness 0.0254)
		(filled_areas_thickness no)
		(fill yes
			(thermal_gap 0.5)
			(thermal_bridge_width 0.5)
			(island_removal_mode 1)
			(island_area_min 10)
		)
		(polygon
			(pts
				(xy 308.828888 121.042723) (xy 308.803692 121.082428) (xy 308.766132 121.122641) (xy 308.719251 121.157421)
				(xy 308.66346 121.183397) (xy 308.596053 121.196228) (xy 308.824292 121.480707) (xy 309.101797 121.228202)
				(xy 308.99461 121.20599) (xy 308.930548 121.17786) (xy 308.915346 121.159712) (xy 308.914222 121.139028)
				(xy 308.917277 121.131112)
			)
		)
	)
	(zone
		(net 2)
		(net_name "+3V3")
		(layer "B.Cu")
		(hatch edge 0.5)
		(priority 6)
		(connect_pads
			(clearance 0.15)
		)
		(min_thickness 0.25)
		(filled_areas_thickness no)
		(fill yes
			(thermal_gap 0.2)
			(thermal_bridge_width 0.5)
		)
		(polygon
			(pts
				(xy 304.85 82.41) (xy 306.95 82.41) (xy 306.95 80.46) (xy 304.85 80.46)
			)
		)
	)
	(zone
		(net 45)
		(net_name "/2xUSB3.0+RJ45/USBSS_2.TX+")
		(layer "B.Cu")
		(name "$teardrop_padvia$")
		(hatch none 0.1)
		(priority 31027)
		(attr
			(teardrop
				(type padvia)
			)
		)
		(connect_pads yes
			(clearance 0)
		)
		(min_thickness 0.0254)
		(filled_areas_thickness no)
		(fill yes
			(thermal_gap 0.5)
			(thermal_bridge_width 0.5)
			(island_removal_mode 1)
			(island_area_min 10)
		)
		(polygon
			(pts
				(xy 123.46 103.3945) (xy 123.478847 103.3896) (xy 123.512108 103.383482) (xy 123.526647 103.391841)
				(xy 123.536995 103.4145) (xy 123.786 103.302) (xy 123.536995 103.1895) (xy 123.527025 103.211717)
				(xy 123.51305 103.220331) (xy 123.478847 103.2144) (xy 123.46 103.2095)
			)
		)
	)
	(zone
		(net 866)
		(net_name "/Backplane/PCIe_{x2}.TX0+")
		(layer "B.Cu")
		(name "$teardrop_padvia$")
		(hatch none 0.1)
		(priority 30046)
		(attr
			(teardrop
				(type padvia)
			)
		)
		(connect_pads yes
			(clearance 0)
		)
		(min_thickness 0.0254)
		(filled_areas_thickness no)
		(fill yes
			(thermal_gap 0.5)
			(thermal_bridge_width 0.5)
			(island_removal_mode 1)
			(island_area_min 10)
		)
		(polygon
			(pts
				(xy 317.860744 159.6165) (xy 318.255858 159.599246) (xy 318.69849 159.577362) (xy 318.959827 159.575348)
				(xy 319.254117 159.585) (xy 319.451 159.31) (xy 317.95 159.254408) (xy 317.950007 159.313332) (xy 317.940774 159.356415)
				(xy 317.925619 159.384485) (xy 317.906098 159.402295) (xy 317.860744 159.4145)
			)
		)
	)
	(zone
		(net 227)
		(net_name "/Com Express 7 Interfaces/PCIe_{B1x4}.TX0+")
		(layer "B.Cu")
		(name "$teardrop_padvia$")
		(hatch none 0.1)
		(priority 30844)
		(attr
			(teardrop
				(type padvia)
			)
		)
		(connect_pads yes
			(clearance 0)
		)
		(min_thickness 0.0254)
		(filled_areas_thickness no)
		(fill yes
			(thermal_gap 0.5)
			(thermal_bridge_width 0.5)
			(island_removal_mode 1)
			(island_area_min 10)
		)
		(polygon
			(pts
				(xy 119.7435 145.1855) (xy 119.761205 145.298973) (xy 119.783243 145.423283) (xy 119.785395 145.494457)
				(xy 119.776 145.572409) (xy 119.901 145.674) (xy 119.963533 145.235506) (xy 119.937868 145.231086)
				(xy 119.931443 145.220158) (xy 119.939561 145.199614) (xy 119.9455 145.1855)
			)
		)
	)
	(zone
		(net 658)
		(net_name "Net-(U43C-PRTAD2)")
		(layer "B.Cu")
		(name "$teardrop_padvia$")
		(hatch none 0.1)
		(priority 30399)
		(attr
			(teardrop
				(type padvia)
			)
		)
		(connect_pads yes
			(clearance 0)
		)
		(min_thickness 0.0254)
		(filled_areas_thickness no)
		(fill yes
			(thermal_gap 0.5)
			(thermal_bridge_width 0.5)
			(island_removal_mode 1)
			(island_area_min 10)
		)
		(polygon
			(pts
				(xy 145.143 138.9975) (xy 145.083588 138.977727) (xy 145.027503 138.914453) (xy 145.005801 138.865828)
				(xy 144.991127 138.806468) (xy 144.989347 138.7945) (xy 144.729 139.06) (xy 144.989347 139.3255)
				(xy 145.002197 139.265361) (xy 145.022131 139.215477) (xy 145.048056 139.175358) (xy 145.077876 139.146345)
				(xy 145.109294 139.128854) (xy 145.141105 139.122521) (xy 145.143 139.1225)
			)
		)
	)
	(zone
		(net 106)
		(net_name "/OCuLink/PCIe_{x4}.TX3+")
		(layer "B.Cu")
		(name "$teardrop_padvia$")
		(hatch none 0.1)
		(priority 30975)
		(attr
			(teardrop
				(type padvia)
			)
		)
		(connect_pads yes
			(clearance 0)
		)
		(min_thickness 0.0254)
		(filled_areas_thickness no)
		(fill yes
			(thermal_gap 0.5)
			(thermal_bridge_width 0.5)
			(island_removal_mode 1)
			(island_area_min 10)
		)
		(polygon
			(pts
				(xy 104.058 159.213) (xy 104.078648 159.205802) (xy 104.110984 159.196208) (xy 104.125007 159.203035)
				(xy 104.134995 159.2245) (xy 104.384 159.112) (xy 104.134995 158.9995) (xy 104.125271 159.020676)
				(xy 104.111643 159.027731) (xy 104.078648 159.018198) (xy 104.058 159.011)
			)
		)
	)
	(zone
		(net 194)
		(net_name "/OCuLink/PCIe_{x4}.RX2+")
		(layer "B.Cu")
		(name "$teardrop_padvia$")
		(hatch none 0.1)
		(priority 30548)
		(attr
			(teardrop
				(type padvia)
			)
		)
		(connect_pads yes
			(clearance 0)
		)
		(min_thickness 0.0254)
		(filled_areas_thickness no)
		(fill yes
			(thermal_gap 0.5)
			(thermal_bridge_width 0.5)
			(island_removal_mode 1)
			(island_area_min 10)
		)
		(polygon
			(pts
				(xy 109.1935 148.432504) (xy 109.198895 148.594035) (xy 109.202445 148.678446) (xy 109.197823 148.78014)
				(xy 109.4185 148.801) (xy 109.581731 148.651147) (xy 109.513062 148.597007) (xy 109.496608 148.587116)
				(xy 109.457935 148.562616) (xy 109.425721 148.533109) (xy 109.403673 148.491953) (xy 109.3955 148.432504)
			)
		)
	)
	(zone
		(net 1)
		(net_name "GND")
		(layer "B.Cu")
		(name "$teardrop_padvia$")
		(hatch none 0.1)
		(priority 30270)
		(attr
			(teardrop
				(type padvia)
			)
		)
		(connect_pads yes
			(clearance 0)
		)
		(min_thickness 0.0254)
		(filled_areas_thickness no)
		(fill yes
			(thermal_gap 0.5)
			(thermal_bridge_width 0.5)
			(island_removal_mode 1)
			(island_area_min 10)
		)
		(polygon
			(pts
				(xy 99.858677 158.95) (xy 99.701106 158.943069) (xy 99.587578 158.914549) (xy 99.545778 158.8975)
				(xy 99.457 159.1) (xy 99.545778 159.3025) (xy 99.641817 159.268118) (xy 99.743689 159.2529) (xy 99.858677 159.25)
			)
		)
	)
	(zone
		(net 772)
		(net_name "/Backplane/PCIe_{x2}.RX1-")
		(layer "B.Cu")
		(name "$teardrop_padvia$")
		(hatch none 0.1)
		(priority 30526)
		(attr
			(teardrop
				(type padvia)
			)
		)
		(connect_pads yes
			(clearance 0)
		)
		(min_thickness 0.0254)
		(filled_areas_thickness no)
		(fill yes
			(thermal_gap 0.5)
			(thermal_bridge_width 0.5)
			(island_removal_mode 1)
			(island_area_min 10)
		)
		(polygon
			(pts
				(xy 269.832504 160.2955) (xy 269.87929 160.300235) (xy 269.914742 160.313379) (xy 269.962939 160.358387)
				(xy 269.987116 160.396608) (xy 270.014485 160.439773) (xy 270.051147 160.481731) (xy 270.201 160.3185)
				(xy 270.18014 160.097823) (xy 270.079466 160.102452) (xy 269.996096 160.099019) (xy 269.994035 160.098895)
				(xy 269.832504 160.0935)
			)
		)
	)
	(zone
		(net 241)
		(net_name "/Com Express 7 Interfaces/PCIe_{B2Bx4}.TX3-")
		(layer "B.Cu")
		(name "$teardrop_padvia$")
		(hatch none 0.1)
		(priority 30559)
		(attr
			(teardrop
				(type padvia)
			)
		)
		(connect_pads yes
			(clearance 0)
		)
		(min_thickness 0.0254)
		(filled_areas_thickness no)
		(fill yes
			(thermal_gap 0.5)
			(thermal_bridge_width 0.5)
			(island_removal_mode 1)
			(island_area_min 10)
		)
		(polygon
			(pts
				(xy 174.667496 95.7035) (xy 174.505964 95.708895) (xy 174.421554 95.712445) (xy 174.31986 95.707823)
				(xy 174.299 95.9285) (xy 174.448852 96.091731) (xy 174.502992 96.023062) (xy 174.512883 96.006608)
				(xy 174.537383 95.967935) (xy 174.56689 95.935721) (xy 174.608046 95.913673) (xy 174.667496 95.9055)
			)
		)
	)
	(zone
		(net 673)
		(net_name "/2xSFP+/KR to SFI #2/PRBSEN")
		(layer "B.Cu")
		(name "$teardrop_padvia$")
		(hatch none 0.1)
		(priority 30755)
		(attr
			(teardrop
				(type padvia)
			)
		)
		(connect_pads yes
			(clearance 0)
		)
		(min_thickness 0.0254)
		(filled_areas_thickness no)
		(fill yes
			(thermal_gap 0.5)
			(thermal_bridge_width 0.5)
			(island_removal_mode 1)
			(island_area_min 10)
		)
		(polygon
			(pts
				(xy 137.529127 139.532485) (xy 137.476618 139.578181) (xy 137.430623 139.604768) (xy 137.344174 139.625152)
				(xy 137.328841 139.626988) (xy 137.246105 139.639323) (xy 137.289293 139.860707) (xy 137.510677 139.903895)
				(xy 137.523011 139.82116) (xy 137.543349 139.723881) (xy 137.570057 139.675841) (xy 137.617515 139.620873)
			)
		)
	)
	(zone
		(net 965)
		(net_name "/PCIe redriver/PCIe_{O}_C.TX1-")
		(layer "B.Cu")
		(name "$teardrop_padvia$")
		(hatch none 0.1)
		(priority 30854)
		(attr
			(teardrop
				(type padvia)
			)
		)
		(connect_pads yes
			(clearance 0)
		)
		(min_thickness 0.0254)
		(filled_areas_thickness no)
		(fill yes
			(thermal_gap 0.5)
			(thermal_bridge_width 0.5)
			(island_removal_mode 1)
			(island_area_min 10)
		)
		(polygon
			(pts
				(xy 118.0555 149.5355) (xy 118.038615 149.42529) (xy 118.017433 149.302357) (xy 118.015862 149.231999)
				(xy 118.026 149.154996) (xy 117.901 149.047) (xy 117.835792 149.484961) (xy 117.861285 149.489498)
				(xy 117.867691 149.500473) (xy 117.859495 149.521248) (xy 117.8535 149.5355)
			)
		)
	)
	(zone
		(net 659)
		(net_name "Net-(U43C-PRTAD3)")
		(layer "B.Cu")
		(name "$teardrop_padvia$")
		(hatch none 0.1)
		(priority 30398)
		(attr
			(teardrop
				(type padvia)
			)
		)
		(connect_pads yes
			(clearance 0)
		)
		(min_thickness 0.0254)
		(filled_areas_thickness no)
		(fill yes
			(thermal_gap 0.5)
			(thermal_bridge_width 0.5)
			(island_removal_mode 1)
			(island_area_min 10)
		)
		(polygon
			(pts
				(xy 147.843 135.9975) (xy 147.783588 135.977727) (xy 147.727503 135.914453) (xy 147.705801 135.865828)
				(xy 147.691127 135.806468) (xy 147.689347 135.7945) (xy 147.429 136.06) (xy 147.689347 136.3255)
				(xy 147.702197 136.265361) (xy 147.722131 136.215477) (xy 147.748056 136.175358) (xy 147.777876 136.146345)
				(xy 147.809294 136.128854) (xy 147.841105 136.122521) (xy 147.843 136.1225)
			)
		)
	)
	(zone
		(net 237)
		(net_name "/Com Express 7 Interfaces/PCIe_{B2Bx4}.RX3-")
		(layer "B.Cu")
		(name "$teardrop_padvia$")
		(hatch none 0.1)
		(priority 30562)
		(attr
			(teardrop
				(type padvia)
			)
		)
		(connect_pads yes
			(clearance 0)
		)
		(min_thickness 0.0254)
		(filled_areas_thickness no)
		(fill yes
			(thermal_gap 0.5)
			(thermal_bridge_width 0.5)
			(island_removal_mode 1)
			(island_area_min 10)
		)
		(polygon
			(pts
				(xy 173.967496 94.2035) (xy 173.805964 94.208895) (xy 173.721554 94.212445) (xy 173.61986 94.207823)
				(xy 173.599 94.4285) (xy 173.748852 94.591731) (xy 173.802992 94.523062) (xy 173.812883 94.506608)
				(xy 173.837383 94.467935) (xy 173.86689 94.435721) (xy 173.908046 94.413673) (xy 173.967496 94.4055)
			)
		)
	)
	(zone
		(net 54)
		(net_name "/USB-C console/SH")
		(layer "B.Cu")
		(name "$teardrop_padvia$")
		(hatch none 0.1)
		(priority 30039)
		(attr
			(teardrop
				(type padvia)
			)
		)
		(connect_pads yes
			(clearance 0)
		)
		(min_thickness 0.0254)
		(filled_areas_thickness no)
		(fill yes
			(thermal_gap 0.5)
			(thermal_bridge_width 0.5)
			(island_removal_mode 1)
			(island_area_min 10)
		)
		(polygon
			(pts
				(xy 97.506802 87.482355) (xy 97.517156 87.492132) (xy 97.540962 87.518276) (xy 97.543739 87.55076)
				(xy 97.503321 87.594882) (xy 97.397542 87.655938) (xy 98.325707 87.947707) (xy 98.461396 87.447)
				(xy 98.301241 87.428704) (xy 98.160581 87.376747) (xy 98.03145 87.292128) (xy 97.892982 87.161981)
				(xy 97.860355 87.128802)
			)
		)
	)
	(zone
		(net 169)
		(net_name "Net-(J2A-RS1)")
		(layer "B.Cu")
		(name "$teardrop_padvia$")
		(hatch none 0.1)
		(priority 30419)
		(attr
			(teardrop
				(type padvia)
			)
		)
		(connect_pads yes
			(clearance 0)
		)
		(min_thickness 0.0254)
		(filled_areas_thickness no)
		(fill yes
			(thermal_gap 0.5)
			(thermal_bridge_width 0.5)
			(island_removal_mode 1)
			(island_area_min 10)
		)
		(polygon
			(pts
				(xy 146.9875 168.267) (xy 146.967727 168.326412) (xy 146.904453 168.382496) (xy 146.855828 168.404198)
				(xy 146.796469 168.418872) (xy 146.7845 168.420652) (xy 147.05 168.681) (xy 147.3155 168.420652)
				(xy 147.255362 168.407803) (xy 147.205478 168.387869) (xy 147.165358 168.361944) (xy 147.136345 168.332124)
				(xy 147.118854 168.300706) (xy 147.112521 168.268895) (xy 147.1125 168.267)
			)
		)
	)
	(zone
		(net 125)
		(net_name "/2xUSB3.0+RJ45/P2_D-")
		(layer "B.Cu")
		(name "$teardrop_padvia$")
		(hatch none 0.1)
		(priority 30592)
		(attr
			(teardrop
				(type padvia)
			)
		)
		(connect_pads yes
			(clearance 0)
		)
		(min_thickness 0.0254)
		(filled_areas_thickness no)
		(fill yes
			(thermal_gap 0.5)
			(thermal_bridge_width 0.5)
			(island_removal_mode 1)
			(island_area_min 10)
		)
		(polygon
			(pts
				(xy 113.7275 106.740416) (xy 113.731684 106.904858) (xy 113.731823 107.087562) (xy 113.9525 107.101)
				(xy 114.111688 106.947104) (xy 114.044162 106.898225) (xy 114.017819 106.884851) (xy 113.977556 106.863476)
				(xy 113.943998 106.836768) (xy 113.92102 106.797992) (xy 113.9125 106.740416)
			)
		)
	)
	(zone
		(net 1)
		(net_name "GND")
		(layer "B.Cu")
		(name "$teardrop_padvia$")
		(hatch none 0.1)
		(priority 30462)
		(attr
			(teardrop
				(type padvia)
			)
		)
		(connect_pads yes
			(clearance 0)
		)
		(min_thickness 0.0254)
		(filled_areas_thickness no)
		(fill yes
			(thermal_gap 0.5)
			(thermal_bridge_width 0.5)
			(island_removal_mode 1)
			(island_area_min 10)
		)
		(polygon
			(pts
				(xy 142.59961 149.393969) (xy 142.544888 149.442023) (xy 142.496621 149.471902) (xy 142.397703 149.503439)
				(xy 142.303795 149.529463) (xy 142.376293 149.738707) (xy 142.579261 149.826355) (xy 142.612228 149.741095)
				(xy 142.653451 149.644719) (xy 142.68792 149.594254) (xy 142.741031 149.53539)
			)
		)
	)
	(zone
		(net 142)
		(net_name "/2xSFP+/PHY0_{RESET}")
		(layer "B.Cu")
		(name "$teardrop_padvia$")
		(hatch none 0.1)
		(priority 30748)
		(attr
			(teardrop
				(type padvia)
			)
		)
		(connect_pads yes
			(clearance 0)
		)
		(min_thickness 0.0254)
		(filled_areas_thickness no)
		(fill yes
			(thermal_gap 0.5)
			(thermal_bridge_width 0.5)
			(island_removal_mode 1)
			(island_area_min 10)
		)
		(polygon
			(pts
				(xy 141.450677 135.748) (xy 141.381458 135.743185) (xy 141.33027 135.729479) (xy 141.25495 135.682821)
				(xy 141.242656 135.673123) (xy 141.175003 135.622919) (xy 141.049 135.81) (xy 141.175003 135.997081)
				(xy 141.241795 135.947726) (xy 141.325199 135.893342) (xy 141.378135 135.878293) (xy 141.450677 135.873)
			)
		)
	)
	(zone
		(net 291)
		(net_name "/2xUSB3.0+RJ45/~{GBE0_LINK}")
		(layer "B.Cu")
		(name "$teardrop_padvia$")
		(hatch none 0.1)
		(priority 30414)
		(attr
			(teardrop
				(type padvia)
			)
		)
		(connect_pads yes
			(clearance 0)
		)
		(min_thickness 0.0254)
		(filled_areas_thickness no)
		(fill yes
			(thermal_gap 0.5)
			(thermal_bridge_width 0.5)
			(island_removal_mode 1)
			(island_area_min 10)
		)
		(polygon
			(pts
				(xy 124.293 110.7475) (xy 124.233588 110.727727) (xy 124.177503 110.664453) (xy 124.155801 110.615828)
				(xy 124.141127 110.556468) (xy 124.139347 110.5445) (xy 123.879 110.81) (xy 124.139347 111.0755)
				(xy 124.152197 111.015361) (xy 124.172131 110.965477) (xy 124.198056 110.925358) (xy 124.227876 110.896345)
				(xy 124.259294 110.878854) (xy 124.291105 110.872521) (xy 124.293 110.8725)
			)
		)
	)
	(zone
		(net 156)
		(net_name "Net-(J1A-LED_D3)")
		(layer "B.Cu")
		(name "$teardrop_padvia$")
		(hatch none 0.1)
		(priority 30028)
		(attr
			(teardrop
				(type padvia)
			)
		)
		(connect_pads yes
			(clearance 0)
		)
		(min_thickness 0.0254)
		(filled_areas_thickness no)
		(fill yes
			(thermal_gap 0.5)
			(thermal_bridge_width 0.5)
			(island_removal_mode 1)
			(island_area_min 10)
		)
		(polygon
			(pts
				(xy 122.049979 110.121591) (xy 121.811045 109.89083) (xy 121.631244 109.739952) (xy 121.342963 109.540609)
				(xy 121.23501 109.468758) (xy 120.859293 110.029293) (xy 121.23501 110.591242) (xy 121.357529 110.489138)
				(xy 121.492104 110.339806) (xy 121.602115 110.216976) (xy 121.656084 110.16916) (xy 121.710895 110.135208)
				(xy 121.767701 110.118716) (xy 121.827651 110.123282) (xy 121.891898 110.152504) (xy 121.961591 110.209979)
			)
		)
	)
	(zone
		(net 158)
		(net_name "/2xUSB3.0+RJ45/USBSS_1.RX-")
		(layer "B.Cu")
		(name "$teardrop_padvia$")
		(hatch none 0.1)
		(priority 30963)
		(attr
			(teardrop
				(type padvia)
			)
		)
		(connect_pads yes
			(clearance 0)
		)
		(min_thickness 0.0254)
		(filled_areas_thickness no)
		(fill yes
			(thermal_gap 0.5)
			(thermal_bridge_width 0.5)
			(island_removal_mode 1)
			(island_area_min 10)
		)
		(polygon
			(pts
				(xy 100.878 106.2155) (xy 100.800085 106.230419) (xy 100.712952 106.248999) (xy 100.664747 106.249904)
				(xy 100.613729 106.24) (xy 100.552 106.365) (xy 100.827289 106.431073) (xy 100.831881 106.402902)
				(xy 100.842942 106.393157) (xy 100.865345 106.39715) (xy 100.878 106.4005)
			)
		)
	)
	(zone
		(net 241)
		(net_name "/Com Express 7 Interfaces/PCIe_{B2Bx4}.TX3-")
		(layer "B.Cu")
		(name "$teardrop_padvia$")
		(hatch none 0.1)
		(priority 30295)
		(attr
			(teardrop
				(type padvia)
			)
		)
		(connect_pads yes
			(clearance 0)
		)
		(min_thickness 0.0254)
		(filled_areas_thickness no)
		(fill yes
			(thermal_gap 0.5)
			(thermal_bridge_width 0.5)
			(island_removal_mode 1)
			(island_area_min 10)
		)
		(polygon
			(pts
				(xy 175.39 95.961) (xy 175.404678 95.957463) (xy 175.434685 95.954192) (xy 175.445673 95.966143)
				(xy 175.45 95.995) (xy 176.201 95.86) (xy 175.45 95.725) (xy 175.445525 95.754204) (xy 175.434203 95.765997)
				(xy 175.404678 95.762537) (xy 175.39 95.759)
			)
		)
	)
	(zone
		(net 880)
		(net_name "/2xSFP+/SFI1.TX-")
		(layer "B.Cu")
		(name "$teardrop_padvia$")
		(hatch none 0.1)
		(priority 30633)
		(attr
			(teardrop
				(type padvia)
			)
		)
		(connect_pads yes
			(clearance 0)
		)
		(min_thickness 0.0254)
		(filled_areas_thickness no)
		(fill yes
			(thermal_gap 0.5)
			(thermal_bridge_width 0.5)
			(island_removal_mode 1)
			(island_area_min 10)
		)
		(polygon
			(pts
				(xy 128.685 147.977084) (xy 128.682432 147.797777) (xy 128.680677 147.632143) (xy 128.46 147.629)
				(xy 128.334997 147.817081) (xy 128.419781 147.855729) (xy 128.460597 147.871388) (xy 128.494058 147.892373)
				(xy 128.516685 147.925376) (xy 128.525 147.977084)
			)
		)
	)
	(zone
		(net 89)
		(net_name "/Com Express 7 Interfaces/PCIe_{B2Ax4}.RX3-")
		(layer "B.Cu")
		(name "$teardrop_padvia$")
		(hatch none 0.1)
		(priority 30826)
		(attr
			(teardrop
				(type padvia)
			)
		)
		(connect_pads yes
			(clearance 0)
		)
		(min_thickness 0.0254)
		(filled_areas_thickness no)
		(fill yes
			(thermal_gap 0.5)
			(thermal_bridge_width 0.5)
			(island_removal_mode 1)
			(island_area_min 10)
		)
		(polygon
			(pts
				(xy 216.627935 164.960034) (xy 216.61772 164.943233) (xy 216.62264 164.930333) (xy 216.669806 164.908086)
				(xy 216.718503 164.887081) (xy 216.592793 164.699293) (xy 216.38184 164.765665) (xy 216.398869 164.869071)
				(xy 216.399921 164.893316) (xy 216.413433 164.993892) (xy 216.438332 165.045996) (xy 216.4851 165.102869)
			)
		)
	)
	(zone
		(net 705)
		(net_name "Net-(U24-GPIO1)")
		(layer "B.Cu")
		(name "$teardrop_padvia$")
		(hatch none 0.1)
		(priority 30101)
		(attr
			(teardrop
				(type padvia)
			)
		)
		(connect_pads yes
			(clearance 0)
		)
		(min_thickness 0.0254)
		(filled_areas_thickness no)
		(fill yes
			(thermal_gap 0.5)
			(thermal_bridge_width 0.5)
			(island_removal_mode 1)
			(island_area_min 10)
		)
		(polygon
			(pts
				(xy 260.617794 86.2975) (xy 260.535734 86.292685) (xy 260.470388 86.278981) (xy 260.377121 86.232424)
				(xy 260.298658 86.164214) (xy 260.237159 86.108058) (xy 260.158339 86.048199) (xy 259.949 86.36)
				(xy 260.158339 86.671801) (xy 260.278517 86.57478) (xy 260.298657 86.555787) (xy 260.357541 86.502634)
				(xy 260.421624 86.460409) (xy 260.504008 86.432551) (xy 260.617794 86.4225)
			)
		)
	)
	(zone
		(net 228)
		(net_name "/M.2 key M #1/~{PERST_D}")
		(layer "B.Cu")
		(name "$teardrop_padvia$")
		(hatch none 0.1)
		(priority 30317)
		(attr
			(teardrop
				(type padvia)
			)
		)
		(connect_pads yes
			(clearance 0)
		)
		(min_thickness 0.0254)
		(filled_areas_thickness no)
		(fill yes
			(thermal_gap 0.5)
			(thermal_bridge_width 0.5)
			(island_removal_mode 1)
			(island_area_min 10)
		)
		(polygon
			(pts
				(xy 178.03 105.1725) (xy 178.068823 105.183438) (xy 178.083933 105.205195) (xy 178.09 105.245) (xy 178.841 105.11)
				(xy 178.09 104.975) (xy 178.085483 105.010281) (xy 178.073862 105.031797) (xy 178.041039 105.046995)
				(xy 178.03 105.0475)
			)
		)
	)
	(zone
		(net 53)
		(net_name "/2xSFP+/SH")
		(layer "B.Cu")
		(name "$teardrop_padvia$")
		(hatch none 0.1)
		(priority 30008)
		(attr
			(teardrop
				(type padvia)
			)
		)
		(connect_pads yes
			(clearance 0)
		)
		(min_thickness 0.0254)
		(filled_areas_thickness no)
		(fill yes
			(thermal_gap 0.5)
			(thermal_bridge_width 0.5)
			(island_removal_mode 1)
			(island_area_min 10)
		)
		(polygon
			(pts
				(xy 108.41 156.502495) (xy 108.414858 156.400602) (xy 108.428866 156.312862) (xy 108.450188 156.240093)
				(xy 108.478435 156.177092) (xy 108.555909 156.070395) (xy 108.672946 155.969149) (xy 108.738075 155.921896)
				(xy 108.906973 155.791137) (xy 108.991073 155.707345) (xy 109.071477 155.603802) (xy 108.45 155.184)
				(xy 107.738438 155.389326) (xy 107.819739 155.611839) (xy 107.924312 155.813082) (xy 107.995174 155.944961)
				(xy 108.054354 156.089634) (xy 108.094936 156.268384) (xy 108.11 156.502495)
			)
		)
	)
	(zone
		(net 1)
		(net_name "GND")
		(layer "B.Cu")
		(name "$teardrop_padvia$")
		(hatch none 0.1)
		(priority 30267)
		(attr
			(teardrop
				(type padvia)
			)
		)
		(connect_pads yes
			(clearance 0)
		)
		(min_thickness 0.0254)
		(filled_areas_thickness no)
		(fill yes
			(thermal_gap 0.5)
			(thermal_bridge_width 0.5)
			(island_removal_mode 1)
			(island_area_min 10)
		)
		(polygon
			(pts
				(xy 99.860677 157.45) (xy 99.703106 157.443069) (xy 99.589578 157.414549) (xy 99.547778 157.3975)
				(xy 99.459 157.6) (xy 99.547778 157.8025) (xy 99.643817 157.768118) (xy 99.745689 157.7529) (xy 99.860677 157.75)
			)
		)
	)
	(zone
		(net 78)
		(net_name "+1V8")
		(layer "B.Cu")
		(name "$teardrop_padvia$")
		(hatch none 0.1)
		(priority 30365)
		(attr
			(teardrop
				(type padvia)
			)
		)
		(connect_pads yes
			(clearance 0)
		)
		(min_thickness 0.0254)
		(filled_areas_thickness no)
		(fill yes
			(thermal_gap 0.5)
			(thermal_bridge_width 0.5)
			(island_removal_mode 1)
			(island_area_min 10)
		)
		(polygon
			(pts
				(xy 158.4425 140.798) (xy 158.462469 140.735134) (xy 158.488921 140.703156) (xy 158.526332 140.674642)
				(xy 158.573527 140.652118) (xy 158.631167 140.636907) (xy 158.631798 140.636798) (xy 158.38 140.359)
				(xy 158.128202 140.636798) (xy 158.183635 140.651095) (xy 158.22952 140.672175) (xy 158.267201 140.69954)
				(xy 158.294434 140.730448) (xy 158.311472 140.763735) (xy 158.317489 140.796566) (xy 158.3175 140.798)
			)
		)
	)
	(zone
		(net 269)
		(net_name "/Com Express 7 Interfaces/PCIe_{B2Bx4}.TX0+")
		(layer "B.Cu")
		(name "$teardrop_padvia$")
		(hatch none 0.1)
		(priority 30522)
		(attr
			(teardrop
				(type padvia)
			)
		)
		(connect_pads yes
			(clearance 0)
		)
		(min_thickness 0.0254)
		(filled_areas_thickness no)
		(fill yes
			(thermal_gap 0.5)
			(thermal_bridge_width 0.5)
			(island_removal_mode 1)
			(island_area_min 10)
		)
		(polygon
			(pts
				(xy 174.607496 104.3145) (xy 174.56071 104.309765) (xy 174.525258 104.296621) (xy 174.47706 104.251613)
				(xy 174.452884 104.213392) (xy 174.425514 104.170225) (xy 174.388852 104.128268) (xy 174.239 104.2915)
				(xy 174.25986 104.512177) (xy 174.360531 104.507548) (xy 174.443897 104.51098) (xy 174.445964 104.511105)
				(xy 174.607496 104.5165)
			)
		)
	)
	(zone
		(net 537)
		(net_name "/Backplane/PCIe_{x2}.RX0-")
		(layer "B.Cu")
		(name "$teardrop_padvia$")
		(hatch none 0.1)
		(priority 30556)
		(attr
			(teardrop
				(type padvia)
			)
		)
		(connect_pads yes
			(clearance 0)
		)
		(min_thickness 0.0254)
		(filled_areas_thickness no)
		(fill yes
			(thermal_gap 0.5)
			(thermal_bridge_width 0.5)
			(island_removal_mode 1)
			(island_area_min 10)
		)
		(polygon
			(pts
				(xy 220.767496 153.4435) (xy 220.605964 153.448895) (xy 220.521554 153.452445) (xy 220.41986 153.447823)
				(xy 220.399 153.6685) (xy 220.548852 153.831731) (xy 220.602992 153.763062) (xy 220.612883 153.746608)
				(xy 220.637383 153.707935) (xy 220.66689 153.675721) (xy 220.708046 153.653673) (xy 220.767496 153.6455)
			)
		)
	)
	(zone
		(net 1)
		(net_name "GND")
		(layer "B.Cu")
		(name "$teardrop_padvia$")
		(hatch none 0.1)
		(priority 30863)
		(attr
			(teardrop
				(type padvia)
			)
		)
		(connect_pads yes
			(clearance 0)
		)
		(min_thickness 0.0254)
		(filled_areas_thickness no)
		(fill yes
			(thermal_gap 0.5)
			(thermal_bridge_width 0.5)
			(island_removal_mode 1)
			(island_area_min 10)
		)
		(polygon
			(pts
				(xy 124.14 104.2) (xy 124.129885 104.200153) (xy 124.099169 104.19954) (xy 124.06668 104.191218)
				(xy 124.037526 104.167325) (xy 124.016809 104.12) (xy 123.784 104.3) (xy 124.016809 104.48) (xy 124.030168 104.444099)
				(xy 124.048399 104.420801) (xy 124.093725 104.401101) (xy 124.129885 104.399847) (xy 124.14 104.4)
			)
		)
	)
	(zone
		(net 656)
		(net_name "Net-(U43C-PRTAD1)")
		(layer "B.Cu")
		(name "$teardrop_padvia$")
		(hatch none 0.1)
		(priority 30411)
		(attr
			(teardrop
				(type padvia)
			)
		)
		(connect_pads yes
			(clearance 0)
		)
		(min_thickness 0.0254)
		(filled_areas_thickness no)
		(fill yes
			(thermal_gap 0.5)
			(thermal_bridge_width 0.5)
			(island_removal_mode 1)
			(island_area_min 10)
		)
		(polygon
			(pts
				(xy 145.143 137.9975) (xy 145.083588 137.977727) (xy 145.027503 137.914453) (xy 145.005801 137.865828)
				(xy 144.991127 137.806468) (xy 144.989347 137.7945) (xy 144.729 138.06) (xy 144.989347 138.3255)
				(xy 145.002197 138.265361) (xy 145.022131 138.215477) (xy 145.048056 138.175358) (xy 145.077876 138.146345)
				(xy 145.109294 138.128854) (xy 145.141105 138.122521) (xy 145.143 138.1225)
			)
		)
	)
	(zone
		(net 970)
		(net_name "/M.2 key M #2/M2_3V3")
		(layer "B.Cu")
		(hatch edge 0.5)
		(priority 6)
		(connect_pads
			(clearance 0.15)
		)
		(min_thickness 0.25)
		(filled_areas_thickness no)
		(fill yes
			(thermal_gap 0.2)
			(thermal_bridge_width 0.5)
		)
		(polygon
			(pts
				(xy 304.7 82.41) (xy 303.4 82.41) (xy 302.55 81.56) (xy 286.18 81.56) (xy 286.18 79.42) (xy 302.84 79.42)
				(xy 304.7 79.42)
			)
		)
	)
	(zone
		(net 683)
		(net_name "Net-(U45C-MODE_{SEL})")
		(layer "B.Cu")
		(name "$teardrop_padvia$")
		(hatch none 0.1)
		(priority 30409)
		(attr
			(teardrop
				(type padvia)
			)
		)
		(connect_pads yes
			(clearance 0)
		)
		(min_thickness 0.0254)
		(filled_areas_thickness no)
		(fill yes
			(thermal_gap 0.5)
			(thermal_bridge_width 0.5)
			(island_removal_mode 1)
			(island_area_min 10)
		)
		(polygon
			(pts
				(xy 126.983 141.9975) (xy 126.923588 141.977727) (xy 126.867503 141.914453) (xy 126.845801 141.865828)
				(xy 126.831127 141.806468) (xy 126.829347 141.7945) (xy 126.569 142.06) (xy 126.829347 142.3255)
				(xy 126.842197 142.265361) (xy 126.862131 142.215477) (xy 126.888056 142.175358) (xy 126.917876 142.146345)
				(xy 126.949294 142.128854) (xy 126.981105 142.122521) (xy 126.983 142.1225)
			)
		)
	)
	(zone
		(net 87)
		(net_name "/Com Express 7 Interfaces/PCIe_{B2Ax4}.RX1-")
		(layer "B.Cu")
		(name "$teardrop_padvia$")
		(hatch none 0.1)
		(priority 30616)
		(attr
			(teardrop
				(type padvia)
			)
		)
		(connect_pads yes
			(clearance 0)
		)
		(min_thickness 0.0254)
		(filled_areas_thickness no)
		(fill yes
			(thermal_gap 0.5)
			(thermal_bridge_width 0.5)
			(island_removal_mode 1)
			(island_area_min 10)
		)
		(polygon
			(pts
				(xy 212.804361 160.6045) (xy 212.778406 160.599768) (xy 212.768619 160.586642) (xy 212.779047 160.549054)
				(xy 212.802451 160.508633) (xy 212.828904 160.46296) (xy 212.845891 160.418681) (xy 212.624214 160.374786)
				(xy 212.500211 160.561867) (xy 212.568147 160.626535) (xy 212.605476 160.681621) (xy 212.637281 160.728974)
				(xy 212.675579 160.768808) (xy 212.728547 160.796268) (xy 212.804361 160.8065)
			)
		)
	)
	(zone
		(net 205)
		(net_name "/Backplane/PCIe_{REF}.CK-")
		(layer "B.Cu")
		(name "$teardrop_padvia$")
		(hatch none 0.1)
		(priority 30041)
		(attr
			(teardrop
				(type padvia)
			)
		)
		(connect_pads yes
			(clearance 0)
		)
		(min_thickness 0.0254)
		(filled_areas_thickness no)
		(fill yes
			(thermal_gap 0.5)
			(thermal_bridge_width 0.5)
			(island_removal_mode 1)
			(island_area_min 10)
		)
		(polygon
			(pts
				(xy 317.860744 164.8055) (xy 317.893777 164.811457) (xy 317.923712 164.833158) (xy 317.939644 164.860607)
				(xy 317.949306 164.900407) (xy 317.95 164.965591) (xy 319.451 164.91) (xy 319.254117 164.635) (xy 318.774522 164.644225)
				(xy 318.255858 164.620754) (xy 317.860744 164.6035)
			)
		)
	)
	(zone
		(net 81)
		(net_name "/Misc/FAN_12V")
		(layer "B.Cu")
		(name "$teardrop_padvia$")
		(hatch none 0.1)
		(priority 30055)
		(attr
			(teardrop
				(type padvia)
			)
		)
		(connect_pads yes
			(clearance 0)
		)
		(min_thickness 0.0254)
		(filled_areas_thickness no)
		(fill yes
			(thermal_gap 0.5)
			(thermal_bridge_width 0.5)
			(island_removal_mode 1)
			(island_area_min 10)
		)
		(polygon
			(pts
				(xy 263.575751 73.733594) (xy 263.641402 73.790823) (xy 263.715978 73.855229) (xy 263.786073 73.93492)
				(xy 263.837409 74.037136) (xy 263.851581 74.098953) (xy 263.855709 74.169116) (xy 264.256416 74.060707)
				(xy 264.264826 73.56) (xy 264.210711 73.569977) (xy 264.163184 73.569304) (xy 264.083601 73.542036)
				(xy 264.013484 73.482248) (xy 263.971089 73.430147) (xy 263.929303 73.380042)
			)
		)
	)
	(zone
		(net 1)
		(net_name "GND")
		(layer "B.Cu")
		(name "$teardrop_padvia$")
		(hatch none 0.1)
		(priority 30144)
		(attr
			(teardrop
				(type padvia)
			)
		)
		(connect_pads yes
			(clearance 0)
		)
		(min_thickness 0.0254)
		(filled_areas_thickness no)
		(fill yes
			(thermal_gap 0.5)
			(thermal_bridge_width 0.5)
			(island_removal_mode 1)
			(island_area_min 10)
		)
		(polygon
			(pts
				(xy 115.559999 77.286999) (xy 115.579201 77.333932) (xy 115.597284 77.36989) (xy 115.604939 77.405156)
				(xy 115.589575 77.435097) (xy 115.5386 77.455085) (xy 115.794999 77.725999) (xy 116.069009 77.481444)
				(xy 116.034809 77.466455) (xy 116.015848 77.447444) (xy 116.010729 77.405869) (xy 116.038102 77.342057)
				(xy 116.059999 77.286999)
			)
		)
	)
	(zone
		(net 249)
		(net_name "/Com Express 7 Interfaces/PCIe_{B2Bx4}.TX2+")
		(layer "B.Cu")
		(name "$teardrop_padvia$")
		(hatch none 0.1)
		(priority 30521)
		(attr
			(teardrop
				(type padvia)
			)
		)
		(connect_pads yes
			(clearance 0)
		)
		(min_thickness 0.0254)
		(filled_areas_thickness no)
		(fill yes
			(thermal_gap 0.5)
			(thermal_bridge_width 0.5)
			(island_removal_mode 1)
			(island_area_min 10)
		)
		(polygon
			(pts
				(xy 174.667496 98.3145) (xy 174.62071 98.309765) (xy 174.585258 98.296621) (xy 174.53706 98.251613)
				(xy 174.512884 98.213392) (xy 174.485514 98.170225) (xy 174.448852 98.128268) (xy 174.299 98.2915)
				(xy 174.31986 98.512177) (xy 174.420531 98.507548) (xy 174.503897 98.51098) (xy 174.505964 98.511105)
				(xy 174.667496 98.5165)
			)
		)
	)
	(zone
		(net 64)
		(net_name "Net-(U19-V_{CC})")
		(layer "B.Cu")
		(name "$teardrop_padvia$")
		(hatch none 0.1)
		(priority 30638)
		(attr
			(teardrop
				(type padvia)
			)
		)
		(connect_pads yes
			(clearance 0)
		)
		(min_thickness 0.0254)
		(filled_areas_thickness no)
		(fill yes
			(thermal_gap 0.5)
			(thermal_bridge_width 0.5)
			(island_removal_mode 1)
			(island_area_min 10)
		)
		(polygon
			(pts
				(xy 310.864322 106.6925) (xy 310.92675 106.697259) (xy 310.97369 106.710573) (xy 311.041855 106.755971)
				(xy 311.059672 106.772061) (xy 311.139996 106.837081) (xy 311.265999 106.65) (xy 311.187287 106.44333)
				(xy 311.083525 106.49688) (xy 311.073049 106.503628) (xy 310.989806 106.548528) (xy 310.935749 106.562381)
				(xy 310.864322 106.5675)
			)
		)
	)
	(zone
		(net 869)
		(net_name "/Backplane/PCIe_{x2}.TX1-")
		(layer "B.Cu")
		(name "$teardrop_padvia$")
		(hatch none 0.1)
		(priority 30561)
		(attr
			(teardrop
				(type padvia)
			)
		)
		(connect_pads yes
			(clearance 0)
		)
		(min_thickness 0.0254)
		(filled_areas_thickness no)
		(fill yes
			(thermal_gap 0.5)
			(thermal_bridge_width 0.5)
			(island_removal_mode 1)
			(island_area_min 10)
		)
		(polygon
			(pts
				(xy 269.367496 140.7935) (xy 269.205964 140.798895) (xy 269.121554 140.802445) (xy 269.01986 140.797823)
				(xy 268.999 141.0185) (xy 269.148852 141.181731) (xy 269.202992 141.113062) (xy 269.212883 141.096608)
				(xy 269.237383 141.057935) (xy 269.26689 141.025721) (xy 269.308046 141.003673) (xy 269.367496 140.9955)
			)
		)
	)
	(zone
		(net 1)
		(net_name "GND")
		(layer "B.Cu")
		(name "$teardrop_padvia$")
		(hatch none 0.1)
		(priority 30001)
		(attr
			(teardrop
				(type padvia)
			)
		)
		(connect_pads yes
			(clearance 0)
		)
		(min_thickness 0.0254)
		(filled_areas_thickness no)
		(fill yes
			(thermal_gap 0.5)
			(thermal_bridge_width 0.5)
			(island_removal_mode 1)
			(island_area_min 10)
		)
		(polygon
			(pts
				(xy 101.65 124.104669) (xy 101.645103 124.194072) (xy 101.630828 124.269367) (xy 101.609979 124.327145)
				(xy 101.582219 124.374974) (xy 101.509882 124.443277) (xy 101.408461 124.486448) (xy 101.26005 124.508579)
				(xy 101.058357 124.512442) (xy 100.890361 124.5141) (xy 100.71866 124.527518) (xy 100.549299 124.564474)
				(xy 100.467386 124.595459) (xy 100.388326 124.636745) (xy 100.89 125.465) (xy 101.846266 125.613698)
				(xy 101.920372 125.084138) (xy 101.946698 124.652106) (xy 101.95 124.104669)
			)
		)
	)
	(zone
		(net 54)
		(net_name "/USB-C console/SH")
		(layer "B.Cu")
		(name "$teardrop_padvia$")
		(hatch none 0.1)
		(priority 30032)
		(attr
			(teardrop
				(type padvia)
			)
		)
		(connect_pads yes
			(clearance 0)
		)
		(min_thickness 0.0254)
		(filled_areas_thickness no)
		(fill yes
			(thermal_gap 0.5)
			(thermal_bridge_width 0.5)
			(island_removal_mode 1)
			(island_area_min 10)
		)
		(polygon
			(pts
				(xy 105.208607 82.197) (xy 105.245236 82.196613) (xy 105.35436 82.198165) (xy 105.474176 82.219003)
				(xy 105.534817 82.242785) (xy 105.594198 82.278743) (xy 105.651009 82.329331) (xy 105.703938 82.397)
				(xy 106.425 81.947) (xy 105.703938 81.497) (xy 105.661137 81.553506) (xy 105.615597 81.598367) (xy 105.51487 81.660294)
				(xy 105.398291 81.691378) (xy 105.245236 81.697387) (xy 105.208607 81.697)
			)
		)
	)
	(zone
		(net 2)
		(net_name "+3V3")
		(layer "B.Cu")
		(name "$teardrop_padvia$")
		(hatch none 0.1)
		(priority 30901)
		(attr
			(teardrop
				(type padvia)
			)
		)
		(connect_pads yes
			(clearance 0)
		)
		(min_thickness 0.0254)
		(filled_areas_thickness no)
		(fill yes
			(thermal_gap 0.5)
			(thermal_bridge_width 0.5)
			(island_removal_mode 1)
			(island_area_min 10)
		)
		(polygon
			(pts
				(xy 195.173654 137.437096) (xy 195.169117 137.432694) (xy 195.145133 137.400812) (xy 195.142807 137.377367)
				(xy 195.154566 137.347295) (xy 194.784039 137.135868) (xy 194.995466 137.506395) (xy 195.022414 137.495168)
				(xy 195.044073 137.495469) (xy 195.080865 137.520946) (xy 195.085267 137.525483)
			)
		)
	)
	(zone
		(net 1)
		(net_name "GND")
		(layer "B.Cu")
		(hatch edge 0.5)
		(priority 32)
		(connect_pads
			(clearance 0.15)
		)
		(min_thickness 0.25)
		(filled_areas_thickness no)
		(fill yes
			(thermal_gap 0.2)
			(thermal_bridge_width 0.3)
			(smoothing fillet)
			(radius 0.2)
		)
		(polygon
			(pts
				(xy 213.2 131.18) (xy 218.15 131.18) (xy 218.15 126.13) (xy 213.2 126.13)
			)
		)
	)
	(zone
		(net 78)
		(net_name "+1V8")
		(layer "B.Cu")
		(name "$teardrop_padvia$")
		(hatch none 0.1)
		(priority 30408)
		(attr
			(teardrop
				(type padvia)
			)
		)
		(connect_pads yes
			(clearance 0)
		)
		(min_thickness 0.0254)
		(filled_areas_thickness no)
		(fill yes
			(thermal_gap 0.5)
			(thermal_bridge_width 0.5)
			(island_removal_mode 1)
			(island_area_min 10)
		)
		(polygon
			(pts
				(xy 147.843 133.8075) (xy 147.783588 133.787727) (xy 147.727503 133.724453) (xy 147.705801 133.675828)
				(xy 147.691127 133.616468) (xy 147.689347 133.6045) (xy 147.429 133.87) (xy 147.689347 134.1355)
				(xy 147.702197 134.075361) (xy 147.722131 134.025477) (xy 147.748056 133.985358) (xy 147.777876 133.956345)
				(xy 147.809294 133.938854) (xy 147.841105 133.932521) (xy 147.843 133.9325)
			)
		)
	)
	(zone
		(net 61)
		(net_name "/OCuLink/5V_CONN0")
		(layer "B.Cu")
		(name "$teardrop_padvia$")
		(hatch none 0.1)
		(priority 30047)
		(attr
			(teardrop
				(type padvia)
			)
		)
		(connect_pads yes
			(clearance 0)
		)
		(min_thickness 0.0254)
		(filled_areas_thickness no)
		(fill yes
			(thermal_gap 0.5)
			(thermal_bridge_width 0.5)
			(island_removal_mode 1)
			(island_area_min 10)
		)
		(polygon
			(pts
				(xy 104.09 153.54) (xy 104.095087 153.492513) (xy 104.110692 153.443147) (xy 104.137084 153.394144)
				(xy 104.17485 153.346944) (xy 104.221693 153.305453) (xy 104.279679 153.268783) (xy 104.345567 153.239798)
				(xy 104.422302 153.21792) (xy 104.452132 153.212132) (xy 103.94 152.649) (xy 103.427868 153.212132)
				(xy 103.505985 153.230397) (xy 103.573841 153.255782) (xy 103.633186 153.287984) (xy 103.682436 153.32511)
				(xy 103.75438 153.412868) (xy 103.787843 153.50929) (xy 103.79 153.54)
			)
		)
	)
	(zone
		(net 623)
		(net_name "/PCIe redriver/TX_EQ0")
		(layer "B.Cu")
		(name "$teardrop_padvia$")
		(hatch none 0.1)
		(priority 30930)
		(attr
			(teardrop
				(type padvia)
			)
		)
		(connect_pads yes
			(clearance 0)
		)
		(min_thickness 0.0254)
		(filled_areas_thickness no)
		(fill yes
			(thermal_gap 0.5)
			(thermal_bridge_width 0.5)
			(island_removal_mode 1)
			(island_area_min 10)
		)
		(polygon
			(pts
				(xy 112.4755 148.1715) (xy 112.482769 148.171303) (xy 112.518233 148.176012) (xy 112.533828 148.189883)
				(xy 112.543806 148.217694) (xy 112.964 148.111) (xy 112.555002 147.996824) (xy 112.543306 148.023547)
				(xy 112.527361 148.03856) (xy 112.482108 148.046603) (xy 112.4755 148.0465)
			)
		)
	)
	(zone
		(net 1)
		(net_name "GND")
		(layer "B.Cu")
		(name "$teardrop_padvia$")
		(hatch none 0.1)
		(priority 31038)
		(attr
			(teardrop
				(type padvia)
			)
		)
		(connect_pads yes
			(clearance 0)
		)
		(min_thickness 0.0254)
		(filled_areas_thickness no)
		(fill yes
			(thermal_gap 0.5)
			(thermal_bridge_width 0.5)
			(island_removal_mode 1)
			(island_area_min 10)
		)
		(polygon
			(pts
				(xy 316.390677 165.81) (xy 316.403178 165.814575) (xy 316.401704 165.8266) (xy 316.371187 165.867227)
				(xy 316.346504 165.898724) (xy 316.343418 165.908775) (xy 316.351 165.9125) (xy 316.351 165.71)
				(xy 316.351 165.9125) (xy 316.398378 165.894246) (xy 316.444299 165.835619) (xy 316.473774 165.737901)
				(xy 316.473536 165.69066) (xy 316.461433 165.650434) (xy 316.443378 165.627528) (xy 316.416906 165.613477)
				(xy 316.390677 165.61)
			)
		)
	)
	(zone
		(net 1)
		(net_name "GND")
		(layer "B.Cu")
		(name "$teardrop_padvia$")
		(hatch none 0.1)
		(priority 30377)
		(attr
			(teardrop
				(type padvia)
			)
		)
		(connect_pads yes
			(clearance 0)
		)
		(min_thickness 0.0254)
		(filled_areas_thickness no)
		(fill yes
			(thermal_gap 0.5)
			(thermal_bridge_width 0.5)
			(island_removal_mode 1)
			(island_area_min 10)
		)
		(polygon
			(pts
				(xy 147.488 169.5775) (xy 147.425134 169.557531) (xy 147.393156 169.531079) (xy 147.364642 169.493668)
				(xy 147.342118 169.446473) (xy 147.326907 169.388833) (xy 147.326798 169.388202) (xy 147.049 169.64)
				(xy 147.326798 169.891798) (xy 147.341095 169.836365) (xy 147.362175 169.79048) (xy 147.38954 169.752799)
				(xy 147.420448 169.725566) (xy 147.453735 169.708528) (xy 147.486566 169.702511) (xy 147.488 169.7025)
			)
		)
	)
	(zone
		(net 187)
		(net_name "/OCuLink/PCIe_{x4}.RX0-")
		(layer "B.Cu")
		(name "$teardrop_padvia$")
		(hatch none 0.1)
		(priority 30504)
		(attr
			(teardrop
				(type padvia)
			)
		)
		(connect_pads yes
			(clearance 0)
		)
		(min_thickness 0.0254)
		(filled_areas_thickness no)
		(fill yes
			(thermal_gap 0.5)
			(thermal_bridge_width 0.5)
			(island_removal_mode 1)
			(island_area_min 10)
		)
		(polygon
			(pts
				(xy 97.279092 149.318809) (xy 97.315522 149.289074) (xy 97.349885 149.2733) (xy 97.415791 149.271045)
				(xy 97.459912 149.280976) (xy 97.509788 149.292147) (xy 97.565381 149.295891) (xy 97.555921 149.074507)
				(xy 97.385129 148.933214) (xy 97.317215 149.007674) (xy 97.255836 149.064198) (xy 97.254294 149.065565)
				(xy 97.136256 149.175973)
			)
		)
	)
	(zone
		(net 154)
		(net_name "Net-(J1A-LED_D1)")
		(layer "B.Cu")
		(name "$teardrop_padvia$")
		(hatch none 0.1)
		(priority 30349)
		(attr
			(teardrop
				(type padvia)
			)
		)
		(connect_pads yes
			(clearance 0)
		)
		(min_thickness 0.0254)
		(filled_areas_thickness no)
		(fill yes
			(thermal_gap 0.5)
			(thermal_bridge_width 0.5)
			(island_removal_mode 1)
			(island_area_min 10)
		)
		(polygon
			(pts
				(xy 122.8575 96.422) (xy 122.837531 96.484866) (xy 122.811079 96.516844) (xy 122.773668 96.545358)
				(xy 122.726473 96.567882) (xy 122.668833 96.583093) (xy 122.668202 96.583202) (xy 122.92 96.861)
				(xy 123.171798 96.583202) (xy 123.116365 96.568905) (xy 123.07048 96.547825) (xy 123.032799 96.52046)
				(xy 123.005566 96.489552) (xy 122.988528 96.456265) (xy 122.982511 96.423434) (xy 122.9825 96.422)
			)
		)
	)
	(zone
		(net 65)
		(net_name "+12V")
		(layer "B.Cu")
		(name "$teardrop_padvia$")
		(hatch none 0.1)
		(priority 30679)
		(attr
			(teardrop
				(type padvia)
			)
		)
		(connect_pads yes
			(clearance 0)
		)
		(min_thickness 0.0254)
		(filled_areas_thickness no)
		(fill yes
			(thermal_gap 0.5)
			(thermal_bridge_width 0.5)
			(island_removal_mode 1)
			(island_area_min 10)
		)
		(polygon
			(pts
				(xy 282.844672 85.966285) (xy 282.79807 85.926226) (xy 282.75558 85.90126) (xy 282.666731 85.875967)
				(xy 282.600355 85.860119) (xy 282.525003 85.822919) (xy 282.399293 86.009293) (xy 282.525003 86.197081)
				(xy 282.584761 86.138848) (xy 282.610683 86.104779) (xy 282.643853 86.062322) (xy 282.677175 86.033374)
				(xy 282.713652 86.027603) (xy 282.756285 86.054672)
			)
		)
	)
	(zone
		(net 719)
		(net_name "Net-(U40-~{I2C_{RESET}})")
		(layer "B.Cu")
		(name "$teardrop_padvia$")
		(hatch none 0.1)
		(priority 30928)
		(attr
			(teardrop
				(type padvia)
			)
		)
		(connect_pads yes
			(clearance 0)
		)
		(min_thickness 0.0254)
		(filled_areas_thickness no)
		(fill yes
			(thermal_gap 0.5)
			(thermal_bridge_width 0.5)
			(island_removal_mode 1)
			(island_area_min 10)
		)
		(polygon
			(pts
				(xy 194.483519 131.975402) (xy 194.488159 131.979901) (xy 194.512478 132.01207) (xy 194.515048 132.035694)
				(xy 194.503608 132.065977) (xy 194.873841 132.275923) (xy 194.660921 131.905099) (xy 194.634085 131.916632)
				(xy 194.612545 131.91651) (xy 194.576212 131.891452) (xy 194.571906 131.887015)
			)
		)
	)
	(zone
		(net 288)
		(net_name "/2xUSB3.0+RJ45/~{GBE0_LINK_1000}")
		(layer "B.Cu")
		(name "$teardrop_padvia$")
		(hatch none 0.1)
		(priority 30712)
		(attr
			(teardrop
				(type padvia)
			)
		)
		(connect_pads yes
			(clearance 0)
		)
		(min_thickness 0.0254)
		(filled_areas_thickness no)
		(fill yes
			(thermal_gap 0.5)
			(thermal_bridge_width 0.5)
			(island_removal_mode 1)
			(island_area_min 10)
		)
		(polygon
			(pts
				(xy 126.099323 111.2625) (xy 126.168764 111.267318) (xy 126.220088 111.28104) (xy 126.295629 111.327755)
				(xy 126.307769 111.337299) (xy 126.374997 111.387081) (xy 126.501 111.2) (xy 126.374997 111.012919)
				(xy 126.307768 111.062702) (xy 126.224602 111.117106) (xy 126.171748 111.13219) (xy 126.099323 111.1375)
			)
		)
	)
	(zone
		(net 63)
		(net_name "Net-(U18-V_{CC})")
		(layer "B.Cu")
		(name "$teardrop_padvia$")
		(hatch none 0.1)
		(priority 30639)
		(attr
			(teardrop
				(type padvia)
			)
		)
		(connect_pads yes
			(clearance 0)
		)
		(min_thickness 0.0254)
		(filled_areas_thickness no)
		(fill yes
			(thermal_gap 0.5)
			(thermal_bridge_width 0.5)
			(island_removal_mode 1)
			(island_area_min 10)
		)
		(polygon
			(pts
				(xy 310.864322 122.5025) (xy 310.92675 122.507259) (xy 310.97369 122.520573) (xy 311.041855 122.565971)
				(xy 311.059672 122.582061) (xy 311.139996 122.647081) (xy 311.265999 122.46) (xy 311.187287 122.25333)
				(xy 311.083525 122.30688) (xy 311.073049 122.313628) (xy 310.989806 122.358528) (xy 310.935749 122.372381)
				(xy 310.864322 122.3775)
			)
		)
	)
	(zone
		(net 161)
		(net_name "/2xUSB3.0+RJ45/USBSS_2.RX+")
		(layer "B.Cu")
		(name "$teardrop_padvia$")
		(hatch none 0.1)
		(priority 30023)
		(attr
			(teardrop
				(type padvia)
			)
		)
		(connect_pads yes
			(clearance 0)
		)
		(min_thickness 0.0254)
		(filled_areas_thickness no)
		(fill yes
			(thermal_gap 0.5)
			(thermal_bridge_width 0.5)
			(island_removal_mode 1)
			(island_area_min 10)
		)
		(polygon
			(pts
				(xy 112.304729 108.081853) (xy 112.234728 108.075806) (xy 112.179306 108.060715) (xy 112.141059 108.040233)
				(xy 112.112187 108.013619) (xy 112.078494 107.944059) (xy 112.070416 107.838624) (xy 112.094304 107.646745)
				(xy 112.121181 107.441037) (xy 112.123568 107.33626) (xy 112.11203 107.233314) (xy 111.449001 107.364984)
				(xy 111.318314 108.02703) (xy 111.561985 108.091831) (xy 111.709561 108.147223) (xy 111.824435 108.190916)
				(xy 111.949788 108.227992) (xy 112.10305 108.254584) (xy 112.301651 108.266827)
			)
		)
	)
	(zone
		(net 78)
		(net_name "+1V8")
		(layer "B.Cu")
		(name "$teardrop_padvia$")
		(hatch none 0.1)
		(priority 30814)
		(attr
			(teardrop
				(type padvia)
			)
		)
		(connect_pads yes
			(clearance 0)
		)
		(min_thickness 0.0254)
		(filled_areas_thickness no)
		(fill yes
			(thermal_gap 0.5)
			(thermal_bridge_width 0.5)
			(island_removal_mode 1)
			(island_area_min 10)
		)
		(polygon
			(pts
				(xy 129.690677 133.8075) (xy 129.625169 133.80272) (xy 129.576274 133.78926) (xy 129.504764 133.743395)
				(xy 129.489678 133.730692) (xy 129.415003 133.672919) (xy 129.289 133.86) (xy 129.415003 134.047081)
				(xy 129.47207 134.006499) (xy 129.560784 133.951924) (xy 129.615503 133.937471) (xy 129.690677 133.9325)
			)
		)
	)
	(zone
		(net 2)
		(net_name "+3V3")
		(layer "B.Cu")
		(name "$teardrop_padvia$")
		(hatch none 0.1)
		(priority 30380)
		(attr
			(teardrop
				(type padvia)
			)
		)
		(connect_pads yes
			(clearance 0)
		)
		(min_thickness 0.0254)
		(filled_areas_thickness no)
		(fill yes
			(thermal_gap 0.5)
			(thermal_bridge_width 0.5)
			(island_removal_mode 1)
			(island_area_min 10)
		)
		(polygon
			(pts
				(xy 122.1175 162.122) (xy 122.097531 162.184866) (xy 122.071079 162.216844) (xy 122.033668 162.245358)
				(xy 121.986473 162.267882) (xy 121.928833 162.283093) (xy 121.928202 162.283202) (xy 122.18 162.561)
				(xy 122.431798 162.283202) (xy 122.376365 162.268905) (xy 122.33048 162.247825) (xy 122.292799 162.22046)
				(xy 122.265566 162.189552) (xy 122.248528 162.156265) (xy 122.242511 162.123434) (xy 122.2425 162.122)
			)
		)
	)
	(zone
		(net 104)
		(net_name "/OCuLink/PCIe_{x4}.TX2+")
		(layer "B.Cu")
		(name "$teardrop_padvia$")
		(hatch none 0.1)
		(priority 30982)
		(attr
			(teardrop
				(type padvia)
			)
		)
		(connect_pads yes
			(clearance 0)
		)
		(min_thickness 0.0254)
		(filled_areas_thickness no)
		(fill yes
			(thermal_gap 0.5)
			(thermal_bridge_width 0.5)
			(island_removal_mode 1)
			(island_area_min 10)
		)
		(polygon
			(pts
				(xy 104.058 160.711) (xy 104.078648 160.703802) (xy 104.110984 160.694208) (xy 104.125007 160.701035)
				(xy 104.134995 160.7225) (xy 104.384 160.61) (xy 104.134995 160.4975) (xy 104.125271 160.518676)
				(xy 104.111643 160.525731) (xy 104.078648 160.516198) (xy 104.058 160.509)
			)
		)
	)
	(zone
		(net 92)
		(net_name "/Com Express 7 Interfaces/PCIe_{B2Ax4}.RX2+")
		(layer "B.Cu")
		(name "$teardrop_padvia$")
		(hatch none 0.1)
		(priority 30495)
		(attr
			(teardrop
				(type padvia)
			)
		)
		(connect_pads yes
			(clearance 0)
		)
		(min_thickness 0.0254)
		(filled_areas_thickness no)
		(fill yes
			(thermal_gap 0.5)
			(thermal_bridge_width 0.5)
			(island_removal_mode 1)
			(island_area_min 10)
		)
		(polygon
			(pts
				(xy 290.153 75.019852) (xy 290.148265 75.066638) (xy 290.135121 75.10209) (xy 290.090113 75.150287)
				(xy 290.051893 75.174463) (xy 290.008726 75.201832) (xy 289.966768 75.238495) (xy 290.13 75.388348)
				(xy 290.350677 75.367488) (xy 290.346048 75.266817) (xy 290.34948 75.18345) (xy 290.349605 75.181383)
				(xy 290.355 75.019852)
			)
		)
	)
	(zone
		(net 98)
		(net_name "/OCuLink/PCIe_{x4}.TX3-")
		(layer "B.Cu")
		(name "$teardrop_padvia$")
		(hatch none 0.1)
		(priority 30981)
		(attr
			(teardrop
				(type padvia)
			)
		)
		(connect_pads yes
			(clearance 0)
		)
		(min_thickness 0.0254)
		(filled_areas_thickness no)
		(fill yes
			(thermal_gap 0.5)
			(thermal_bridge_width 0.5)
			(island_removal_mode 1)
			(island_area_min 10)
		)
		(polygon
			(pts
				(xy 104.83 158.713) (xy 104.850648 158.705802) (xy 104.882984 158.696208) (xy 104.897007 158.703035)
				(xy 104.906995 158.7245) (xy 105.156 158.612) (xy 104.906995 158.4995) (xy 104.897271 158.520676)
				(xy 104.883643 158.527731) (xy 104.850648 158.518198) (xy 104.83 158.511)
			)
		)
	)
	(zone
		(net 2)
		(net_name "+3V3")
		(layer "B.Cu")
		(name "$teardrop_padvia$")
		(hatch none 0.1)
		(priority 30283)
		(attr
			(teardrop
				(type padvia)
			)
		)
		(connect_pads yes
			(clearance 0)
		)
		(min_thickness 0.0254)
		(filled_areas_thickness no)
		(fill yes
			(thermal_gap 0.5)
			(thermal_bridge_width 0.5)
			(island_removal_mode 1)
			(island_area_min 10)
		)
		(polygon
			(pts
				(xy 124.420613 138.452745) (xy 124.502026 138.541767) (xy 124.551018 138.615736) (xy 124.591463 138.713204)
				(xy 124.800707 138.640707) (xy 124.888354 138.437738) (xy 124.811556 138.398184) (xy 124.746006 138.349331)
				(xy 124.632745 138.240613)
			)
		)
	)
	(zone
		(net 1)
		(net_name "GND")
		(layer "B.Cu")
		(name "$teardrop_padvia$")
		(hatch none 0.1)
		(priority 30865)
		(attr
			(teardrop
				(type padvia)
			)
		)
		(connect_pads yes
			(clearance 0)
		)
		(min_thickness 0.0254)
		(filled_areas_thickness no)
		(fill yes
			(thermal_gap 0.5)
			(thermal_bridge_width 0.5)
			(island_removal_mode 1)
			(island_area_min 10)
		)
		(polygon
			(pts
				(xy 104.025002 162.71) (xy 104.035117 162.709847) (xy 104.065834 162.71046) (xy 104.098322 162.718782)
				(xy 104.127477 162.742675) (xy 104.148193 162.79) (xy 104.381002 162.61) (xy 104.148193 162.43)
				(xy 104.134835 162.465901) (xy 104.116603 162.489199) (xy 104.071278 162.508899) (xy 104.035117 162.510153)
				(xy 104.025002 162.51)
			)
		)
	)
	(zone
		(net 2)
		(net_name "+3V3")
		(layer "B.Cu")
		(name "$teardrop_padvia$")
		(hatch none 0.1)
		(priority 30902)
		(attr
			(teardrop
				(type padvia)
			)
		)
		(connect_pads yes
			(clearance 0)
		)
		(min_thickness 0.0254)
		(filled_areas_thickness no)
		(fill yes
			(thermal_gap 0.5)
			(thermal_bridge_width 0.5)
			(island_removal_mode 1)
			(island_area_min 10)
		)
		(polygon
			(pts
				(xy 194.112994 138.497756) (xy 194.108457 138.493354) (xy 194.084473 138.461472) (xy 194.082147 138.438027)
				(xy 194.093906 138.407955) (xy 193.723379 138.196528) (xy 193.934806 138.567055) (xy 193.961754 138.555828)
				(xy 193.983413 138.556129) (xy 194.020205 138.581606) (xy 194.024607 138.586143)
			)
		)
	)
	(zone
		(net 715)
		(net_name "Net-(U39-~{I2C_{RESET}})")
		(layer "B.Cu")
		(name "$teardrop_padvia$")
		(hatch none 0.1)
		(priority 30923)
		(attr
			(teardrop
				(type padvia)
			)
		)
		(connect_pads yes
			(clearance 0)
		)
		(min_thickness 0.0254)
		(filled_areas_thickness no)
		(fill yes
			(thermal_gap 0.5)
			(thermal_bridge_width 0.5)
			(island_removal_mode 1)
			(island_area_min 10)
		)
		(polygon
			(pts
				(xy 120.8375 145.1855) (xy 120.837599 145.191963) (xy 120.83205 145.231906) (xy 120.817161 145.250428)
				(xy 120.787659 145.263752) (xy 120.901 145.674) (xy 121.012655 145.261231) (xy 120.985524 145.25041)
				(xy 120.97038 145.235092) (xy 120.962407 145.191683) (xy 120.9625 145.1855)
			)
		)
	)
	(zone
		(net 64)
		(net_name "Net-(U19-V_{CC})")
		(layer "B.Cu")
		(name "$teardrop_padvia$")
		(hatch none 0.1)
		(priority 30635)
		(attr
			(teardrop
				(type padvia)
			)
		)
		(connect_pads yes
			(clearance 0)
		)
		(min_thickness 0.0254)
		(filled_areas_thickness no)
		(fill yes
			(thermal_gap 0.5)
			(thermal_bridge_width 0.5)
			(island_removal_mode 1)
			(island_area_min 10)
		)
		(polygon
			(pts
				(xy 311.665676 106.5675) (xy 311.597103 106.562826) (xy 311.544623 106.550108) (xy 311.456949 106.503628)
				(xy 311.407032 106.473072) (xy 311.34271 106.44333) (xy 311.263999 106.65) (xy 311.390002 106.837081)
				(xy 311.470325 106.772062) (xy 311.546184 106.715149) (xy 311.596536 106.698507) (xy 311.665676 106.6925)
			)
		)
	)
	(zone
		(net 630)
		(net_name "Net-(U40-RXDET)")
		(layer "B.Cu")
		(name "$teardrop_padvia$")
		(hatch none 0.1)
		(priority 30605)
		(attr
			(teardrop
				(type padvia)
			)
		)
		(connect_pads yes
			(clearance 0)
		)
		(min_thickness 0.0254)
		(filled_areas_thickness no)
		(fill yes
			(thermal_gap 0.5)
			(thermal_bridge_width 0.5)
			(island_removal_mode 1)
			(island_area_min 10)
		)
		(polygon
			(pts
				(xy 198.108281 135.122302) (xy 198.122546 135.135879) (xy 198.126938 135.155355) (xy 198.105337 135.212131)
				(xy 198.050365 135.282664) (xy 198.413911 135.321432) (xy 198.394039 134.954928) (xy 198.307669 135.003717)
				(xy 198.207848 135.020198) (xy 198.157839 135.014911) (xy 198.116095 135.001293) (xy 198.108281 134.997302)
			)
		)
	)
	(zone
		(net 318)
		(net_name "Net-(J12D-LPC_SERIRQ{slash}~{ESPI_CS1})")
		(layer "B.Cu")
		(name "$teardrop_padvia$")
		(hatch none 0.1)
		(priority 30684)
		(attr
			(teardrop
				(type padvia)
			)
		)
		(connect_pads yes
			(clearance 0)
		)
		(min_thickness 0.0254)
		(filled_areas_thickness no)
		(fill yes
			(thermal_gap 0.5)
			(thermal_bridge_width 0.5)
			(island_removal_mode 1)
			(island_area_min 10)
		)
		(polygon
			(pts
				(xy 199.8375 169.949323) (xy 199.832682 170.018763) (xy 199.81896 170.070087) (xy 199.772245 170.145628)
				(xy 199.762702 170.157768) (xy 199.712919 170.224997) (xy 199.9 170.351) (xy 200.087081 170.224997)
				(xy 200.037299 170.157769) (xy 199.982894 170.074603) (xy 199.96781 170.021748) (xy 199.9625 169.949323)
			)
		)
	)
	(zone
		(net 710)
		(net_name "Net-(U37-SDAT)")
		(layer "B.Cu")
		(name "$teardrop_padvia$")
		(hatch none 0.1)
		(priority 30656)
		(attr
			(teardrop
				(type padvia)
			)
		)
		(connect_pads yes
			(clearance 0)
		)
		(min_thickness 0.0254)
		(filled_areas_thickness no)
		(fill yes
			(thermal_gap 0.5)
			(thermal_bridge_width 0.5)
			(island_removal_mode 1)
			(island_area_min 10)
		)
		(polygon
			(pts
				(xy 213.662078 125.270466) (xy 213.685399 125.300539) (xy 213.693877 125.327997) (xy 213.679964 125.374122)
				(xy 213.634778 125.426803) (xy 213.588207 125.479316) (xy 213.55583 125.542606) (xy 213.771538 125.600914)
				(xy 213.954612 125.471904) (xy 213.887295 125.362878) (xy 213.83747 125.28201) (xy 213.750466 125.182078)
			)
		)
	)
	(zone
		(net 213)
		(net_name "/Com Express 7 Interfaces/PCIe_{B1x4}.RX2-")
		(layer "B.Cu")
		(name "$teardrop_padvia$")
		(hatch none 0.1)
		(priority 30543)
		(attr
			(teardrop
				(type padvia)
			)
		)
		(connect_pads yes
			(clearance 0)
		)
		(min_thickness 0.0254)
		(filled_areas_thickness no)
		(fill yes
			(thermal_gap 0.5)
			(thermal_bridge_width 0.5)
			(island_removal_mode 1)
			(island_area_min 10)
		)
		(polygon
			(pts
				(xy 206.3685 161.032504) (xy 206.373895 161.194035) (xy 206.377445 161.278446) (xy 206.372823 161.38014)
				(xy 206.5935 161.401) (xy 206.756731 161.251147) (xy 206.688062 161.197007) (xy 206.671608 161.187116)
				(xy 206.632935 161.162616) (xy 206.600721 161.133109) (xy 206.578673 161.091953) (xy 206.5705 161.032504)
			)
		)
	)
	(zone
		(net 78)
		(net_name "+1V8")
		(layer "B.Cu")
		(name "$teardrop_padvia$")
		(hatch none 0.1)
		(priority 30354)
		(attr
			(teardrop
				(type padvia)
			)
		)
		(connect_pads yes
			(clearance 0)
		)
		(min_thickness 0.0254)
		(filled_areas_thickness no)
		(fill yes
			(thermal_gap 0.5)
			(thermal_bridge_width 0.5)
			(island_removal_mode 1)
			(island_area_min 10)
		)
		(polygon
			(pts
				(xy 140.2825 140.798) (xy 140.302469 140.735134) (xy 140.328921 140.703156) (xy 140.366332 140.674642)
				(xy 140.413527 140.652118) (xy 140.471167 140.636907) (xy 140.471798 140.636798) (xy 140.22 140.359)
				(xy 139.968202 140.636798) (xy 140.023635 140.651095) (xy 140.06952 140.672175) (xy 140.107201 140.69954)
				(xy 140.134434 140.730448) (xy 140.151472 140.763735) (xy 140.157489 140.796566) (xy 140.1575 140.798)
			)
		)
	)
	(zone
		(net 201)
		(net_name "/OCuLink/~{CPRSNT_D0}")
		(layer "B.Cu")
		(name "$teardrop_padvia$")
		(hatch none 0.1)
		(priority 31032)
		(attr
			(teardrop
				(type padvia)
			)
		)
		(connect_pads yes
			(clearance 0)
		)
		(min_thickness 0.0254)
		(filled_areas_thickness no)
		(fill yes
			(thermal_gap 0.5)
			(thermal_bridge_width 0.5)
			(island_removal_mode 1)
			(island_area_min 10)
		)
		(polygon
			(pts
				(xy 104.055002 161.6745) (xy 104.061324 161.674404) (xy 104.100827 161.679989) (xy 104.119049 161.694922)
				(xy 104.131997 161.7245) (xy 104.381002 161.612) (xy 104.131997 161.4995) (xy 104.120881 161.526493)
				(xy 104.105354 161.541595) (xy 104.061324 161.549596) (xy 104.055002 161.5495)
			)
		)
	)
	(zone
		(net 2)
		(net_name "+3V3")
		(layer "B.Cu")
		(name "$teardrop_padvia$")
		(hatch none 0.1)
		(priority 30918)
		(attr
			(teardrop
				(type padvia)
			)
		)
		(connect_pads yes
			(clearance 0)
		)
		(min_thickness 0.0254)
		(filled_areas_thickness no)
		(fill yes
			(thermal_gap 0.5)
			(thermal_bridge_width 0.5)
			(island_removal_mode 1)
			(island_area_min 10)
		)
		(polygon
			(pts
				(xy 115.8385 145.1855) (xy 115.838596 145.191822) (xy 115.833011 145.231325) (xy 115.818078 145.249547)
				(xy 115.7885 145.262495) (xy 115.901 145.674) (xy 116.0135 145.262495) (xy 115.986507 145.251379)
				(xy 115.971405 145.235852) (xy 115.963404 145.191822) (xy 115.9635 145.1855)
			)
		)
	)
	(zone
		(net 654)
		(net_name "Net-(U43C-GPI0)")
		(layer "B.Cu")
		(name "$teardrop_padvia$")
		(hatch none 0.1)
		(priority 30668)
		(attr
			(teardrop
				(type padvia)
			)
		)
		(connect_pads yes
			(clearance 0)
		)
		(min_thickness 0.0254)
		(filled_areas_thickness no)
		(fill yes
			(thermal_gap 0.5)
			(thermal_bridge_width 0.5)
			(island_removal_mode 1)
			(island_area_min 10)
		)
		(polygon
			(pts
				(xy 148.131792 140.996596) (xy 148.162252 140.97288) (xy 148.190253 140.963802) (xy 148.238515 140.976218)
				(xy 148.288639 141.013334) (xy 148.341528 141.053314) (xy 148.404769 141.080123) (xy 148.450707 140.859293)
				(xy 148.312143 140.685772) (xy 148.224496 140.752284) (xy 148.145248 140.813478) (xy 148.043404 140.908208)
			)
		)
	)
	(zone
		(net 186)
		(net_name "/OCuLink/PCIe_{x4}.RX0+")
		(layer "B.Cu")
		(name "$teardrop_padvia$")
		(hatch none 0.1)
		(priority 30541)
		(attr
			(teardrop
				(type padvia)
			)
		)
		(connect_pads yes
			(clearance 0)
		)
		(min_thickness 0.0254)
		(filled_areas_thickness no)
		(fill yes
			(thermal_gap 0.5)
			(thermal_bridge_width 0.5)
			(island_removal_mode 1)
			(island_area_min 10)
		)
		(polygon
			(pts
				(xy 97.004027 149.043744) (xy 97.114432 148.925708) (xy 97.171608 148.86351) (xy 97.246785 148.79487)
				(xy 97.105493 148.624079) (xy 96.884109 148.614618) (xy 96.894381 148.701455) (xy 96.899023 148.720088)
				(xy 96.909045 148.764757) (xy 96.91096 148.8084) (xy 96.897448 148.853092) (xy 96.861191 148.900908)
			)
		)
	)
	(zone
		(net 123)
		(net_name "/2xUSB3.0+RJ45/P1_D-")
		(layer "B.Cu")
		(name "$teardrop_padvia$")
		(hatch none 0.1)
		(priority 30580)
		(attr
			(teardrop
				(type padvia)
			)
		)
		(connect_pads yes
			(clearance 0)
		)
		(min_thickness 0.0254)
		(filled_areas_thickness no)
		(fill yes
			(thermal_gap 0.5)
			(thermal_bridge_width 0.5)
			(island_removal_mode 1)
			(island_area_min 10)
		)
		(polygon
			(pts
				(xy 104.847325 105.0825) (xy 104.802713 105.07776) (xy 104.769317 105.064582) (xy 104.725721 105.019799)
				(xy 104.702889 104.977179) (xy 104.677231 104.929337) (xy 104.640636 104.883311) (xy 104.486741 105.0425)
				(xy 104.500179 105.263177) (xy 104.682883 105.263316) (xy 104.847325 105.2675)
			)
		)
	)
	(zone
		(net 201)
		(net_name "/OCuLink/~{CPRSNT_D0}")
		(layer "B.Cu")
		(name "$teardrop_padvia$")
		(hatch none 0.1)
		(priority 30735)
		(attr
			(teardrop
				(type padvia)
			)
		)
		(connect_pads yes
			(clearance 0)
		)
		(min_thickness 0.0254)
		(filled_areas_thickness no)
		(fill yes
			(thermal_gap 0.5)
			(thermal_bridge_width 0.5)
			(island_removal_mode 1)
			(island_area_min 10)
		)
		(polygon
			(pts
				(xy 120.750677 161.4975) (xy 120.681236 161.492682) (xy 120.629913 161.47896) (xy 120.554371 161.432246)
				(xy 120.542231 161.422701) (xy 120.475003 161.372919) (xy 120.349 161.56) (xy 120.475003 161.747081)
				(xy 120.542229 161.697299) (xy 120.625396 161.642894) (xy 120.678251 161.62781) (xy 120.750677 161.6225)
			)
		)
	)
	(zone
		(net 1)
		(net_name "GND")
		(layer "B.Cu")
		(name "$teardrop_padvia$")
		(hatch none 0.1)
		(priority 30227)
		(attr
			(teardrop
				(type padvia)
			)
		)
		(connect_pads yes
			(clearance 0)
		)
		(min_thickness 0.0254)
		(filled_areas_thickness no)
		(fill yes
			(thermal_gap 0.5)
			(thermal_bridge_width 0.5)
			(island_removal_mode 1)
			(island_area_min 10)
		)
		(polygon
			(pts
				(xy 98.259926 165.299903) (xy 98.361806 165.299535) (xy 98.520417 165.302403) (xy 98.609195 165.099903)
				(xy 98.520417 164.897403) (xy 98.361795 164.90027) (xy 98.259926 164.899903)
			)
		)
	)
	(zone
		(net 267)
		(net_name "/Com Express 7 Interfaces/PCIe_{B2Bx4}.TX0-")
		(layer "B.Cu")
		(name "$teardrop_padvia$")
		(hatch none 0.1)
		(priority 30558)
		(attr
			(teardrop
				(type padvia)
			)
		)
		(connect_pads yes
			(clearance 0)
		)
		(min_thickness 0.0254)
		(filled_areas_thickness no)
		(fill yes
			(thermal_gap 0.5)
			(thermal_bridge_width 0.5)
			(island_removal_mode 1)
			(island_area_min 10)
		)
		(polygon
			(pts
				(xy 174.607496 104.7035) (xy 174.445964 104.708895) (xy 174.361554 104.712445) (xy 174.25986 104.707823)
				(xy 174.239 104.9285) (xy 174.388852 105.091731) (xy 174.442992 105.023062) (xy 174.452883 105.006608)
				(xy 174.477383 104.967935) (xy 174.50689 104.935721) (xy 174.548046 104.913673) (xy 174.607496 104.9055)
			)
		)
	)
	(zone
		(net 1)
		(net_name "GND")
		(layer "B.Cu")
		(name "$teardrop_padvia$")
		(hatch none 0.1)
		(priority 30678)
		(attr
			(teardrop
				(type padvia)
			)
		)
		(connect_pads yes
			(clearance 0)
		)
		(min_thickness 0.0254)
		(filled_areas_thickness no)
		(fill yes
			(thermal_gap 0.5)
			(thermal_bridge_width 0.5)
			(island_removal_mode 1)
			(island_area_min 10)
		)
		(polygon
			(pts
				(xy 127.734672 135.816285) (xy 127.68807 135.776226) (xy 127.64558 135.75126) (xy 127.556731 135.725967)
				(xy 127.490355 135.710119) (xy 127.415003 135.672919) (xy 127.289293 135.859293) (xy 127.415003 136.047081)
				(xy 127.474761 135.988848) (xy 127.500683 135.954779) (xy 127.533853 135.912322) (xy 127.567175 135.883374)
				(xy 127.603652 135.877603) (xy 127.646285 135.904672)
			)
		)
	)
	(zone
		(net 211)
		(net_name "/Com Express 7 Interfaces/PCIe_{B1x4}.TX3-")
		(layer "B.Cu")
		(name "$teardrop_padvia$")
		(hatch none 0.1)
		(priority 30544)
		(attr
			(teardrop
				(type padvia)
			)
		)
		(connect_pads yes
			(clearance 0)
		)
		(min_thickness 0.0254)
		(filled_areas_thickness no)
		(fill yes
			(thermal_gap 0.5)
			(thermal_bridge_width 0.5)
			(island_removal_mode 1)
			(island_area_min 10)
		)
		(polygon
			(pts
				(xy 204.8685 164.932504) (xy 204.873895 165.094035) (xy 204.877445 165.178446) (xy 204.872823 165.28014)
				(xy 205.0935 165.301) (xy 205.256731 165.151147) (xy 205.188062 165.097007) (xy 205.171608 165.087116)
				(xy 205.132935 165.062616) (xy 205.100721 165.033109) (xy 205.078673 164.991953) (xy 205.0705 164.932504)
			)
		)
	)
	(zone
		(net 1)
		(net_name "GND")
		(layer "B.Cu")
		(name "$teardrop_padvia$")
		(hatch none 0.1)
		(priority 31037)
		(attr
			(teardrop
				(type padvia)
			)
		)
		(connect_pads yes
			(clearance 0)
		)
		(min_thickness 0.0254)
		(filled_areas_thickness no)
		(fill yes
			(thermal_gap 0.5)
			(thermal_bridge_width 0.5)
			(island_removal_mode 1)
			(island_area_min 10)
		)
		(polygon
			(pts
				(xy 317.740677 161.01) (xy 317.753178 161.014575) (xy 317.751704 161.0266) (xy 317.721187 161.067227)
				(xy 317.696504 161.098724) (xy 317.693418 161.108775) (xy 317.701 161.1125) (xy 317.701 160.91)
				(xy 317.701 161.1125) (xy 317.748378 161.094246) (xy 317.794299 161.035619) (xy 317.823774 160.937901)
				(xy 317.823536 160.89066) (xy 317.811433 160.850434) (xy 317.793378 160.827528) (xy 317.766906 160.813477)
				(xy 317.740677 160.81)
			)
		)
	)
	(zone
		(net 381)
		(net_name "Net-(J12D-~{SYS_RESET})")
		(layer "B.Cu")
		(name "$teardrop_padvia$")
		(hatch none 0.1)
		(priority 30100)
		(attr
			(teardrop
				(type padvia)
			)
		)
		(connect_pads yes
			(clearance 0)
		)
		(min_thickness 0.0254)
		(filled_areas_thickness no)
		(fill yes
			(thermal_gap 0.5)
			(thermal_bridge_width 0.5)
			(island_removal_mode 1)
			(island_area_min 10)
		)
		(polygon
			(pts
				(xy 193.478007 162.833604) (xy 193.416577 162.888225) (xy 193.36068 162.924741) (xy 193.261808 162.95777)
				(xy 193.158096 162.96502) (xy 193.074901 162.968798) (xy 192.976841 162.982206) (xy 193.049293 163.350707)
				(xy 193.417794 163.423159) (xy 193.434169 163.269576) (xy 193.43498 163.241905) (xy 193.439032 163.162683)
				(xy 193.454488 163.087512) (xy 193.493043 163.009559) (xy 193.566396 162.921993)
			)
		)
	)
	(zone
		(net 2)
		(net_name "+3V3")
		(layer "B.Cu")
		(name "$teardrop_padvia$")
		(hatch none 0.1)
		(priority 30736)
		(attr
			(teardrop
				(type padvia)
			)
		)
		(connect_pads yes
			(clearance 0)
		)
		(min_thickness 0.0254)
		(filled_areas_thickness no)
		(fill yes
			(thermal_gap 0.5)
			(thermal_bridge_width 0.5)
			(island_removal_mode 1)
			(island_area_min 10)
		)
		(polygon
			(pts
				(xy 139.450677 169.5775) (xy 139.381236 169.572682) (xy 139.329913 169.55896) (xy 139.254371 169.512246)
				(xy 139.242231 169.502701) (xy 139.175003 169.452919) (xy 139.049 169.64) (xy 139.175003 169.827081)
				(xy 139.242229 169.777299) (xy 139.325396 169.722894) (xy 139.378251 169.70781) (xy 139.450677 169.7025)
			)
		)
	)
	(zone
		(net 956)
		(net_name "/PCIe redriver/PCIe_{I}_C.RX3-")
		(layer "B.Cu")
		(name "$teardrop_padvia$")
		(hatch none 0.1)
		(priority 30886)
		(attr
			(teardrop
				(type padvia)
			)
		)
		(connect_pads yes
			(clearance 0)
		)
		(min_thickness 0.0254)
		(filled_areas_thickness no)
		(fill yes
			(thermal_gap 0.5)
			(thermal_bridge_width 0.5)
			(island_removal_mode 1)
			(island_area_min 10)
		)
		(polygon
			(pts
				(xy 193.786665 138.824086) (xy 193.766974 138.814575) (xy 193.737326 138.798494) (xy 193.732238 138.783751)
				(xy 193.740353 138.761509) (xy 193.369826 138.550082) (xy 193.581253 138.920609) (xy 193.603104 138.912512)
				(xy 193.617729 138.91716) (xy 193.634319 138.94723) (xy 193.64383 138.966921)
			)
		)
	)
	(zone
		(net 962)
		(net_name "/PCIe redriver/PCIe_{O}_C.TX1+")
		(layer "B.Cu")
		(name "$teardrop_padvia$")
		(hatch none 0.1)
		(priority 30830)
		(attr
			(teardrop
				(type padvia)
			)
		)
		(connect_pads yes
			(clearance 0)
		)
		(min_thickness 0.0254)
		(filled_areas_thickness no)
		(fill yes
			(thermal_gap 0.5)
			(thermal_bridge_width 0.5)
			(island_removal_mode 1)
			(island_area_min 10)
		)
		(polygon
			(pts
				(xy 118.4445 149.5355) (xy 118.438582 149.5214) (xy 118.430798 149.497512) (xy 118.439075 149.488883)
				(xy 118.462662 149.4855) (xy 118.401 149.047) (xy 118.276 149.146594) (xy 118.284495 149.275006)
				(xy 118.260482 149.420975) (xy 118.2425 149.5355)
			)
		)
	)
	(zone
		(net 977)
		(net_name "/PCIe redriver/RX_EQ1")
		(layer "B.Cu")
		(name "$teardrop_padvia$")
		(hatch none 0.1)
		(priority 30750)
		(attr
			(teardrop
				(type padvia)
			)
		)
		(connect_pads yes
			(clearance 0)
		)
		(min_thickness 0.0254)
		(filled_areas_thickness no)
		(fill yes
			(thermal_gap 0.5)
			(thermal_bridge_width 0.5)
			(island_removal_mode 1)
			(island_area_min 10)
		)
		(polygon
			(pts
				(xy 190.081903 139.71739) (xy 190.029394 139.763086) (xy 189.983399 139.789673) (xy 189.89695 139.810057)
				(xy 189.881617 139.811893) (xy 189.798881 139.824228) (xy 189.842069 140.045612) (xy 190.063453 140.0888)
				(xy 190.075787 140.006065) (xy 190.096125 139.908786) (xy 190.122833 139.860746) (xy 190.170291 139.805778)
			)
		)
	)
	(zone
		(net 111)
		(net_name "/2xSFP+/10GKR_SFP0.TX+")
		(layer "B.Cu")
		(name "$teardrop_padvia$")
		(hatch none 0.1)
		(priority 30629)
		(attr
			(teardrop
				(type padvia)
			)
		)
		(connect_pads yes
			(clearance 0)
		)
		(min_thickness 0.0254)
		(filled_areas_thickness no)
		(fill yes
			(thermal_gap 0.5)
			(thermal_bridge_width 0.5)
			(island_removal_mode 1)
			(island_area_min 10)
		)
		(polygon
			(pts
				(xy 155.84 147.977084) (xy 155.837432 147.797777) (xy 155.835677 147.632143) (xy 155.615 147.629)
				(xy 155.489997 147.817081) (xy 155.574781 147.855729) (xy 155.615597 147.871388) (xy 155.649058 147.892373)
				(xy 155.671685 147.925376) (xy 155.68 147.977084)
			)
		)
	)
	(zone
		(net 96)
		(net_name "/OCuLink/PCIe_{x4}.TX1-")
		(layer "B.Cu")
		(name "$teardrop_padvia$")
		(hatch none 0.1)
		(priority 31006)
		(attr
			(teardrop
				(type padvia)
			)
		)
		(connect_pads yes
			(clearance 0)
		)
		(min_thickness 0.0254)
		(filled_areas_thickness no)
		(fill yes
			(thermal_gap 0.5)
			(thermal_bridge_width 0.5)
			(island_removal_mode 1)
			(island_area_min 10)
		)
		(polygon
			(pts
				(xy 105.48 164.511) (xy 105.459352 164.518199) (xy 105.427017 164.527792) (xy 105.412994 164.520965)
				(xy 105.403005 164.4995) (xy 105.154 164.612) (xy 105.403005 164.7245) (xy 105.41273 164.703324)
				(xy 105.426358 164.696269) (xy 105.459352 164.705801) (xy 105.48 164.713)
			)
		)
	)
	(zone
		(net 706)
		(net_name "Net-(U24-GPIO0)")
		(layer "B.Cu")
		(name "$teardrop_padvia$")
		(hatch none 0.1)
		(priority 30680)
		(attr
			(teardrop
				(type padvia)
			)
		)
		(connect_pads yes
			(clearance 0)
		)
		(min_thickness 0.0254)
		(filled_areas_thickness no)
		(fill yes
			(thermal_gap 0.5)
			(thermal_bridge_width 0.5)
			(island_removal_mode 1)
			(island_area_min 10)
		)
		(polygon
			(pts
				(xy 260.439323 87.0725) (xy 260.513953 87.077387) (xy 260.568393 87.0916) (xy 260.65793 87.146498)
				(xy 260.714997 87.18708) (xy 260.841 86.999999) (xy 260.714997 86.812918) (xy 260.64032 86.870692)
				(xy 260.561254 86.926019) (xy 260.509813 86.941845) (xy 260.439323 86.9475)
			)
		)
	)
	(zone
		(net 1)
		(net_name "GND")
		(layer "B.Cu")
		(name "$teardrop_padvia$")
		(hatch none 0.1)
		(priority 30370)
		(attr
			(teardrop
				(type padvia)
			)
		)
		(connect_pads yes
			(clearance 0)
		)
		(min_thickness 0.0254)
		(filled_areas_thickness no)
		(fill yes
			(thermal_gap 0.5)
			(thermal_bridge_width 0.5)
			(island_removal_mode 1)
			(island_area_min 10)
		)
		(polygon
			(pts
				(xy 143.7075 141.622) (xy 143.687531 141.684866) (xy 143.661079 141.716844) (xy 143.623668 141.745358)
				(xy 143.576473 141.767882) (xy 143.518833 141.783093) (xy 143.518202 141.783202) (xy 143.77 142.061)
				(xy 144.021798 141.783202) (xy 143.966365 141.768905) (xy 143.92048 141.747825) (xy 143.882799 141.72046)
				(xy 143.855566 141.689552) (xy 143.838528 141.656265) (xy 143.832511 141.623434) (xy 143.8325 141.622)
			)
		)
	)
	(zone
		(net 2)
		(net_name "+3V3")
		(layer "B.Cu")
		(name "$teardrop_padvia$")
		(hatch none 0.1)
		(priority 30913)
		(attr
			(teardrop
				(type padvia)
			)
		)
		(connect_pads yes
			(clearance 0)
		)
		(min_thickness 0.0254)
		(filled_areas_thickness no)
		(fill yes
			(thermal_gap 0.5)
			(thermal_bridge_width 0.5)
			(island_removal_mode 1)
			(island_area_min 10)
		)
		(polygon
			(pts
				(xy 117.4635 149.5355) (xy 117.463404 149.529178) (xy 117.468989 149.489675) (xy 117.483922 149.471452)
				(xy 117.5135 149.458504) (xy 117.401 149.047) (xy 117.2885 149.458504) (xy 117.315493 149.46962)
				(xy 117.330595 149.485147) (xy 117.338596 149.529178) (xy 117.3385 149.5355)
			)
		)
	)
	(zone
		(net 365)
		(net_name "/Com Express 7 MGMT/PWR_OK")
		(layer "B.Cu")
		(name "$teardrop_padvia$")
		(hatch none 0.1)
		(priority 30615)
		(attr
			(teardrop
				(type padvia)
			)
		)
		(connect_pads yes
			(clearance 0)
		)
		(min_thickness 0.0254)
		(filled_areas_thickness no)
		(fill yes
			(thermal_gap 0.5)
			(thermal_bridge_width 0.5)
			(island_removal_mode 1)
			(island_area_min 10)
		)
		(polygon
			(pts
				(xy 187.6125 158.948148) (xy 187.617144 158.871004) (xy 187.629655 158.812896) (xy 187.663974 158.731874)
				(xy 187.712254 158.614229) (xy 187.5 158.549) (xy 187.312919 158.675003) (xy 187.380725 158.750925)
				(xy 187.397582 158.765668) (xy 187.461108 158.833758) (xy 187.480413 158.881532) (xy 187.4875 158.948148)
			)
		)
	)
	(zone
		(net 1)
		(net_name "GND")
		(layer "B.Cu")
		(name "$teardrop_padvia$")
		(hatch none 0.1)
		(priority 30869)
		(attr
			(teardrop
				(type padvia)
			)
		)
		(connect_pads yes
			(clearance 0)
		)
		(min_thickness 0.0254)
		(filled_areas_thickness no)
		(fill yes
			(thermal_gap 0.5)
			(thermal_bridge_width 0.5)
			(island_removal_mode 1)
			(island_area_min 10)
		)
		(polygon
			(pts
				(xy 100.97 105.465) (xy 100.980115 105.464847) (xy 101.010832 105.46546) (xy 101.04332 105.473782)
				(xy 101.072475 105.497675) (xy 101.093191 105.545) (xy 101.326 105.365) (xy 101.093191 105.185)
				(xy 101.079833 105.220901) (xy 101.061601 105.244199) (xy 101.016276 105.263899) (xy 100.980115 105.265153)
				(xy 100.97 105.265)
			)
		)
	)
	(zone
		(net 254)
		(net_name "/Com Express 7 Interfaces/PCIe_{B2Bx4}.RX1+")
		(layer "B.Cu")
		(name "$teardrop_padvia$")
		(hatch none 0.1)
		(priority 30510)
		(attr
			(teardrop
				(type padvia)
			)
		)
		(connect_pads yes
			(clearance 0)
		)
		(min_thickness 0.0254)
		(filled_areas_thickness no)
		(fill yes
			(thermal_gap 0.5)
			(thermal_bridge_width 0.5)
			(island_removal_mode 1)
			(island_area_min 10)
		)
		(polygon
			(pts
				(xy 173.967496 99.8145) (xy 173.92071 99.809765) (xy 173.885258 99.796621) (xy 173.83706 99.751613)
				(xy 173.812884 99.713392) (xy 173.785514 99.670225) (xy 173.748852 99.628268) (xy 173.599 99.7915)
				(xy 173.61986 100.012177) (xy 173.720531 100.007548) (xy 173.803897 100.01098) (xy 173.805964 100.011105)
				(xy 173.967496 100.0165)
			)
		)
	)
	(zone
		(net 47)
		(net_name "/2xUSB3.0+RJ45/USBSS_1.TX-")
		(layer "B.Cu")
		(name "$teardrop_padvia$")
		(hatch none 0.1)
		(priority 30947)
		(attr
			(teardrop
				(type padvia)
			)
		)
		(connect_pads yes
			(clearance 0)
		)
		(min_thickness 0.0254)
		(filled_areas_thickness no)
		(fill yes
			(thermal_gap 0.5)
			(thermal_bridge_width 0.5)
			(island_removal_mode 1)
			(island_area_min 10)
		)
		(polygon
			(pts
				(xy 100.228 104.8995) (xy 100.240525 104.89622) (xy 100.265501 104.893286) (xy 100.274607 104.904247)
				(xy 100.278225 104.930633) (xy 100.554 104.867) (xy 100.496351 104.742) (xy 100.408227 104.750841)
				(xy 100.308309 104.730252) (xy 100.228 104.7145)
			)
		)
	)
	(zone
		(net 632)
		(net_name "Net-(U40-EN_{I2C})")
		(layer "B.Cu")
		(name "$teardrop_padvia$")
		(hatch none 0.1)
		(priority 30225)
		(attr
			(teardrop
				(type padvia)
			)
		)
		(connect_pads yes
			(clearance 0)
		)
		(min_thickness 0.0254)
		(filled_areas_thickness no)
		(fill yes
			(thermal_gap 0.5)
			(thermal_bridge_width 0.5)
			(island_removal_mode 1)
			(island_area_min 10)
		)
		(polygon
			(pts
				(xy 197.834662 132.847099) (xy 197.892616 132.847062) (xy 197.959035 132.888193) (xy 198.052723 132.994126)
				(xy 198.090336 133.045828) (xy 198.264418 132.765948) (xy 198.100769 132.512403) (xy 197.988234 132.622564)
				(xy 197.843766 132.71602) (xy 197.746275 132.758712)
			)
		)
	)
	(zone
		(net 895)
		(net_name "Net-(J2B-RS0)")
		(layer "B.Cu")
		(name "$teardrop_padvia$")
		(hatch none 0.1)
		(priority 30728)
		(attr
			(teardrop
				(type padvia)
			)
		)
		(connect_pads yes
			(clearance 0)
		)
		(min_thickness 0.0254)
		(filled_areas_thickness no)
		(fill yes
			(thermal_gap 0.5)
			(thermal_bridge_width 0.5)
			(island_removal_mode 1)
			(island_area_min 10)
		)
		(polygon
			(pts
				(xy 139.1125 167.410677) (xy 139.117318 167.341236) (xy 139.13104 167.289912) (xy 139.177755 167.21437)
				(xy 139.187299 167.202229) (xy 139.237081 167.135003) (xy 139.05 167.009) (xy 138.862919 167.135003)
				(xy 138.912701 167.202231) (xy 138.967106 167.285397) (xy 138.98219 167.338251) (xy 138.9875 167.410677)
			)
		)
	)
	(zone
		(net 1)
		(net_name "GND")
		(layer "B.Cu")
		(name "$teardrop_padvia$")
		(hatch none 0.1)
		(priority 30051)
		(attr
			(teardrop
				(type padvia)
			)
		)
		(connect_pads yes
			(clearance 0)
		)
		(min_thickness 0.0254)
		(filled_areas_thickness no)
		(fill yes
			(thermal_gap 0.5)
			(thermal_bridge_width 0.5)
			(island_removal_mode 1)
			(island_area_min 10)
		)
		(polygon
			(pts
				(xy 317.84 165.81) (xy 317.892671 165.817457) (xy 317.946335 165.849659) (xy 317.969018 165.880423)
				(xy 317.985714 165.923461) (xy 317.990273 165.944727) (xy 319.451 165.71) (xy 317.990273 165.475273)
				(xy 317.977656 165.521208) (xy 317.958906 165.555539) (xy 317.908407 165.596597) (xy 317.84 165.61)
			)
		)
	)
	(zone
		(net 705)
		(net_name "Net-(U24-GPIO1)")
		(layer "B.Cu")
		(name "$teardrop_padvia$")
		(hatch none 0.1)
		(priority 30811)
		(attr
			(teardrop
				(type padvia)
			)
		)
		(connect_pads yes
			(clearance 0)
		)
		(min_thickness 0.0254)
		(filled_areas_thickness no)
		(fill yes
			(thermal_gap 0.5)
			(thermal_bridge_width 0.5)
			(island_removal_mode 1)
			(island_area_min 10)
		)
		(polygon
			(pts
				(xy 261.499323 86.4225) (xy 261.564831 86.42728) (xy 261.613726 86.44074) (xy 261.685237 86.486605)
				(xy 261.700321 86.499307) (xy 261.774997 86.55708) (xy 261.901 86.369999) (xy 261.774997 86.182918)
				(xy 261.717926 86.223503) (xy 261.629214 86.278076) (xy 261.574495 86.292529) (xy 261.499323 86.2975)
			)
		)
	)
	(zone
		(net 78)
		(net_name "+1V8")
		(layer "B.Cu")
		(name "$teardrop_padvia$")
		(hatch none 0.1)
		(priority 30477)
		(attr
			(teardrop
				(type padvia)
			)
		)
		(connect_pads yes
			(clearance 0)
		)
		(min_thickness 0.0254)
		(filled_areas_thickness no)
		(fill yes
			(thermal_gap 0.5)
			(thermal_bridge_width 0.5)
			(island_removal_mode 1)
			(island_area_min 10)
		)
		(polygon
			(pts
				(xy 301.938 134.478323) (xy 301.933287 134.556234) (xy 301.9203 134.615018) (xy 301.878199 134.706048)
				(xy 301.8355 134.791221) (xy 302.038 134.88) (xy 302.2405 134.791221) (xy 302.197801 134.70605)
				(xy 302.155133 134.613217) (xy 302.142556 134.555078) (xy 302.138 134.478323)
			)
		)
	)
	(zone
		(net 714)
		(net_name "Net-(U39-I2C_{DONE})")
		(layer "B.Cu")
		(name "$teardrop_padvia$")
		(hatch none 0.1)
		(priority 30089)
		(attr
			(teardrop
				(type padvia)
			)
		)
		(connect_pads yes
			(clearance 0)
		)
		(min_thickness 0.0254)
		(filled_areas_thickness no)
		(fill yes
			(thermal_gap 0.5)
			(thermal_bridge_width 0.5)
			(island_removal_mode 1)
			(island_area_min 10)
		)
		(polygon
			(pts
				(xy 121.818602 149.8225) (xy 121.868509 149.827339) (xy 121.904637 149.841209) (xy 121.926464 149.860011)
				(xy 121.940476 149.884346) (xy 121.950078 149.956168) (xy 121.938899 150.061822) (xy 121.926436 150.172235)
				(xy 121.932206 150.283159) (xy 122.301 150.21) (xy 122.373159 149.842206) (xy 122.211393 149.7945)
				(xy 122.150494 149.768636) (xy 122.016147 149.718976) (xy 121.930083 149.70333) (xy 121.818602 149.6975)
			)
		)
	)
	(zone
		(net 101)
		(net_name "/PCIe redriver/PCIe_{I}_C.RX0-")
		(layer "B.Cu")
		(name "$teardrop_padvia$")
		(hatch none 0.1)
		(priority 30194)
		(attr
			(teardrop
				(type padvia)
			)
		)
		(connect_pads yes
			(clearance 0)
		)
		(min_thickness 0.0254)
		(filled_areas_thickness no)
		(fill yes
			(thermal_gap 0.5)
			(thermal_bridge_width 0.5)
			(island_removal_mode 1)
			(island_area_min 10)
		)
		(polygon
			(pts
				(xy 197.675383 136.713004) (xy 197.760377 136.738662) (xy 197.855526 136.782882) (xy 197.920747 136.82638)
				(xy 197.979353 136.881289) (xy 198.017465 136.932755) (xy 198.221992 136.684734) (xy 198.08263 136.405488)
				(xy 197.996669 136.495431) (xy 197.923547 136.550843) (xy 197.881812 136.568552) (xy 197.841861 136.573357)
				(xy 197.818218 136.57017)
			)
		)
	)
	(zone
		(net 212)
		(net_name "/Com Express 7 Interfaces/PCIe_{B1x4}.TX3+")
		(layer "B.Cu")
		(name "$teardrop_padvia$")
		(hatch none 0.1)
		(priority 30851)
		(attr
			(teardrop
				(type padvia)
			)
		)
		(connect_pads yes
			(clearance 0)
		)
		(min_thickness 0.0254)
		(filled_areas_thickness no)
		(fill yes
			(thermal_gap 0.5)
			(thermal_bridge_width 0.5)
			(island_removal_mode 1)
			(island_area_min 10)
		)
		(polygon
			(pts
				(xy 115.2445 145.1855) (xy 115.26193 145.297903) (xy 115.283683 145.421778) (xy 115.285642 145.492695)
				(xy 115.276 145.570348) (xy 115.401 145.674) (xy 115.464425 145.235684) (xy 115.438818 145.231225)
				(xy 115.432399 145.220281) (xy 115.440542 145.19966) (xy 115.4465 145.1855)
			)
		)
	)
	(zone
		(net 54)
		(net_name "/USB-C console/SH")
		(layer "B.Cu")
		(name "$teardrop_padvia$")
		(hatch none 0.1)
		(priority 30040)
		(attr
			(teardrop
				(type padvia)
			)
		)
		(connect_pads yes
			(clearance 0)
		)
		(min_thickness 0.0254)
		(filled_areas_thickness no)
		(fill yes
			(thermal_gap 0.5)
			(thermal_bridge_width 0.5)
			(island_removal_mode 1)
			(island_area_min 10)
		)
		(polygon
			(pts
				(xy 97.860355 82.765198) (xy 97.892979 82.732021) (xy 97.990435 82.636781) (xy 98.112283 82.544439)
				(xy 98.184872 82.505492) (xy 98.266583 82.474633) (xy 98.358422 82.454317) (xy 98.461396 82.447)
				(xy 98.325707 81.946293) (xy 97.397542 82.238062) (xy 97.482648 82.284859) (xy 97.529183 82.321726)
				(xy 97.544373 82.344903) (xy 97.545713 82.364339) (xy 97.517156 82.401867) (xy 97.506802 82.411645)
			)
		)
	)
	(zone
		(net 1)
		(net_name "GND")
		(layer "B.Cu")
		(name "$teardrop_padvia$")
		(hatch none 0.1)
		(priority 30464)
		(attr
			(teardrop
				(type padvia)
			)
		)
		(connect_pads yes
			(clearance 0)
		)
		(min_thickness 0.0254)
		(filled_areas_thickness no)
		(fill yes
			(thermal_gap 0.5)
			(thermal_bridge_width 0.5)
			(island_removal_mode 1)
			(island_area_min 10)
		)
		(polygon
			(pts
				(xy 124.99739 149.124031) (xy 125.052112 149.075976) (xy 125.100379 149.046097) (xy 125.199299 149.014559)
				(xy 125.293204 148.988536) (xy 125.220707 148.779293) (xy 125.017738 148.691645) (xy 124.984769 148.776908)
				(xy 124.943546 148.873282) (xy 124.909079 148.923747) (xy 124.855969 148.98261)
			)
		)
	)
	(zone
		(net 703)
		(net_name "Net-(U24-GPIO3)")
		(layer "B.Cu")
		(name "$teardrop_padvia$")
		(hatch none 0.1)
		(priority 30620)
		(attr
			(teardrop
				(type padvia)
			)
		)
		(connect_pads yes
			(clearance 0)
		)
		(min_thickness 0.0254)
		(filled_areas_thickness no)
		(fill yes
			(thermal_gap 0.5)
			(thermal_bridge_width 0.5)
			(island_removal_mode 1)
			(island_area_min 10)
		)
		(polygon
			(pts
				(xy 261.499323 85.1225) (xy 261.557279 85.127242) (xy 261.601278 85.140434) (xy 261.664173 85.185447)
				(xy 261.686758 85.208849) (xy 261.774997 85.28708) (xy 261.901 85.099999) (xy 261.831376 84.889564)
				(xy 261.714329 84.941827) (xy 261.627596 84.981024) (xy 261.572104 84.993061) (xy 261.499323 84.9975)
			)
		)
	)
	(zone
		(net 124)
		(net_name "/2xUSB3.0+RJ45/P1_D+")
		(layer "B.Cu")
		(name "$teardrop_padvia$")
		(hatch none 0.1)
		(priority 30133)
		(attr
			(teardrop
				(type padvia)
			)
		)
		(connect_pads yes
			(clearance 0)
		)
		(min_thickness 0.0254)
		(filled_areas_thickness no)
		(fill yes
			(thermal_gap 0.5)
			(thermal_bridge_width 0.5)
			(island_removal_mode 1)
			(island_area_min 10)
		)
		(polygon
			(pts
				(xy 104.95074 105.695555) (xy 104.995026 105.747461) (xy 105.035608 105.8131) (xy 105.065882 105.883081)
				(xy 105.088082 105.963791) (xy 105.101 106.096838) (xy 105.401707 106.015707) (xy 105.482838 105.715)
				(xy 105.326698 105.696961) (xy 105.193092 105.646442) (xy 105.087252 105.570327) (xy 105.081555 105.56474)
			)
		)
	)
	(zone
		(net 74)
		(net_name "+1V0")
		(layer "B.Cu")
		(name "$teardrop_padvia$")
		(hatch none 0.1)
		(priority 30061)
		(attr
			(teardrop
				(type padvia)
			)
		)
		(connect_pads yes
			(clearance 0)
		)
		(min_thickness 0.0254)
		(filled_areas_thickness no)
		(fill yes
			(thermal_gap 0.5)
			(thermal_bridge_width 0.5)
			(island_removal_mode 1)
			(island_area_min 10)
		)
		(polygon
			(pts
				(xy 153.94 133.11) (xy 154.015682 133.096011) (xy 154.080186 133.081508) (xy 154.146412 133.078415)
				(xy 154.208353 133.100117) (xy 154.235838 133.12445) (xy 154.26 133.16) (xy 154.601 132.76) (xy 154.109905 132.470198)
				(xy 154.103664 132.531074) (xy 154.089748 132.572845) (xy 154.072215 132.596781) (xy 154.0512 132.610496)
				(xy 153.998272 132.616499) (xy 153.971479 132.613199) (xy 153.94 132.61)
			)
		)
	)
	(zone
		(net 2)
		(net_name "+3V3")
		(layer "B.Cu")
		(name "$teardrop_padvia$")
		(hatch none 0.1)
		(priority 30792)
		(attr
			(teardrop
				(type padvia)
			)
		)
		(connect_pads yes
			(clearance 0)
		)
		(min_thickness 0.0254)
		(filled_areas_thickness no)
		(fill yes
			(thermal_gap 0.5)
			(thermal_bridge_width 0.5)
			(island_removal_mode 1)
			(island_area_min 10)
		)
		(polygon
			(pts
				(xy 115.8385 149.500323) (xy 115.833687 149.569322) (xy 115.819999 149.620376) (xy 115.773394 149.695477)
				(xy 115.763545 149.70792) (xy 115.712919 149.775997) (xy 115.9 149.902) (xy 116.087081 149.775997)
				(xy 116.038154 149.709644) (xy 115.983791 149.626) (xy 115.968776 149.572982) (xy 115.9635 149.500323)
			)
		)
	)
	(zone
		(net 119)
		(net_name "/2xSFP+/10GKR_SFP1.TX+")
		(layer "B.Cu")
		(name "$teardrop_padvia$")
		(hatch none 0.1)
		(priority 30628)
		(attr
			(teardrop
				(type padvia)
			)
		)
		(connect_pads yes
			(clearance 0)
		)
		(min_thickness 0.0254)
		(filled_areas_thickness no)
		(fill yes
			(thermal_gap 0.5)
			(thermal_bridge_width 0.5)
			(island_removal_mode 1)
			(island_area_min 10)
		)
		(polygon
			(pts
				(xy 137.525 147.272916) (xy 137.520244 147.3137) (xy 137.506954 147.343028) (xy 137.462594 147.377688)
				(xy 137.419782 147.39427) (xy 137.334997 147.432919) (xy 137.46 147.621) (xy 137.680677 147.617856)
				(xy 137.682432 147.452216) (xy 137.685 147.272916)
			)
		)
	)
	(zone
		(net 126)
		(net_name "/2xUSB3.0+RJ45/P2_D+")
		(layer "B.Cu")
		(name "$teardrop_padvia$")
		(hatch none 0.1)
		(priority 30314)
		(attr
			(teardrop
				(type padvia)
			)
		)
		(connect_pads yes
			(clearance 0)
		)
		(min_thickness 0.0254)
		(filled_areas_thickness no)
		(fill yes
			(thermal_gap 0.5)
			(thermal_bridge_width 0.5)
			(island_removal_mode 1)
			(island_area_min 10)
		)
		(polygon
			(pts
				(xy 112.8875 105.831) (xy 112.882112 105.86372) (xy 112.864394 105.895774) (xy 112.838243 105.919504)
				(xy 112.80034 105.937952) (xy 112.71 105.951) (xy 112.98 106.252) (xy 113.25 105.951) (xy 113.192616 105.946315)
				(xy 113.147963 105.933521) (xy 113.115117 105.914716) (xy 113.092431 105.891649) (xy 113.072642 105.836361)
				(xy 113.0725 105.831)
			)
		)
	)
	(zone
		(net 125)
		(net_name "/2xUSB3.0+RJ45/P2_D-")
		(layer "B.Cu")
		(name "$teardrop_padvia$")
		(hatch none 0.1)
		(priority 30136)
		(attr
			(teardrop
				(type padvia)
			)
		)
		(connect_pads yes
			(clearance 0)
		)
		(min_thickness 0.0254)
		(filled_areas_thickness no)
		(fill yes
			(thermal_gap 0.5)
			(thermal_bridge_width 0.5)
			(island_removal_mode 1)
			(island_area_min 10)
		)
		(polygon
			(pts
				(xy 113.960555 106.70126) (xy 114.01246 106.656974) (xy 114.078097 106.616393) (xy 114.148077 106.586119)
				(xy 114.228786 106.563918) (xy 114.361838 106.551) (xy 114.280707 106.250293) (xy 113.98 106.169163)
				(xy 113.961961 106.325302) (xy 113.911442 106.458908) (xy 113.835326 106.564748) (xy 113.82974 106.570445)
			)
		)
	)
	(zone
		(net 156)
		(net_name "Net-(J1A-LED_D3)")
		(layer "B.Cu")
		(name "$teardrop_padvia$")
		(hatch none 0.1)
		(priority 30382)
		(attr
			(teardrop
				(type padvia)
			)
		)
		(connect_pads yes
			(clearance 0)
		)
		(min_thickness 0.0254)
		(filled_areas_thickness no)
		(fill yes
			(thermal_gap 0.5)
			(thermal_bridge_width 0.5)
			(island_removal_mode 1)
			(island_area_min 10)
		)
		(polygon
			(pts
				(xy 122.9825 110.248) (xy 123.002469 110.185134) (xy 123.028921 110.153156) (xy 123.066332 110.124642)
				(xy 123.113527 110.102118) (xy 123.171167 110.086907) (xy 123.171798 110.086798) (xy 122.92 109.809)
				(xy 122.668202 110.086798) (xy 122.723635 110.101095) (xy 122.76952 110.122175) (xy 122.807201 110.14954)
				(xy 122.834434 110.180448) (xy 122.851472 110.213735) (xy 122.857489 110.246566) (xy 122.8575 110.248)
			)
		)
	)
	(zone
		(net 100)
		(net_name "/OCuLink/PCIe_{x4}.TX0+")
		(layer "B.Cu")
		(name "$teardrop_padvia$")
		(hatch none 0.1)
		(priority 30980)
		(attr
			(teardrop
				(type padvia)
			)
		)
		(connect_pads yes
			(clearance 0)
		)
		(min_thickness 0.0254)
		(filled_areas_thickness no)
		(fill yes
			(thermal_gap 0.5)
			(thermal_bridge_width 0.5)
			(island_removal_mode 1)
			(island_area_min 10)
		)
		(polygon
			(pts
				(xy 104.058 166.711) (xy 104.078648 166.703802) (xy 104.110984 166.694208) (xy 104.125007 166.701035)
				(xy 104.134995 166.7225) (xy 104.384 166.61) (xy 104.134995 166.4975) (xy 104.125271 166.518676)
				(xy 104.111643 166.525731) (xy 104.078648 166.516198) (xy 104.058 166.509)
			)
		)
	)
	(zone
		(net 1)
		(net_name "GND")
		(layer "B.Cu")
		(name "$teardrop_padvia$")
		(hatch none 0.1)
		(priority 30600)
		(attr
			(teardrop
				(type padvia)
			)
		)
		(connect_pads yes
			(clearance 0)
		)
		(min_thickness 0.0254)
		(filled_areas_thickness no)
		(fill yes
			(thermal_gap 0.5)
			(thermal_bridge_width 0.5)
			(island_removal_mode 1)
			(island_area_min 10)
		)
		(polygon
			(pts
				(xy 308.881921 102.603534) (xy 308.884513 102.58253) (xy 308.897111 102.564622) (xy 308.955312 102.536985)
				(xy 309.053945 102.523772) (xy 308.824292 102.239293) (xy 308.567376 102.504611) (xy 308.663836 102.533934)
				(xy 308.74374 102.594659) (xy 308.772505 102.633449) (xy 308.789616 102.672503) (xy 308.793534 102.691921)
			)
		)
	)
	(zone
		(net 959)
		(net_name "/PCIe redriver/PCIe_{I}_C.RX2+")
		(layer "B.Cu")
		(name "$teardrop_padvia$")
		(hatch none 0.1)
		(priority 30184)
		(attr
			(teardrop
				(type padvia)
			)
		)
		(connect_pads yes
			(clearance 0)
		)
		(min_thickness 0.0254)
		(filled_areas_thickness no)
		(fill yes
			(thermal_gap 0.5)
			(thermal_bridge_width 0.5)
			(island_removal_mode 1)
			(island_area_min 10)
		)
		(polygon
			(pts
				(xy 195.262785 139.100246) (xy 195.26431 139.137372) (xy 195.255323 139.175105) (xy 195.202932 139.258646)
				(xy 195.094734 139.365099) (xy 195.372351 139.50609) (xy 195.622521 139.303712) (xy 195.534026 139.228355)
				(xy 195.461332 139.120032) (xy 195.412195 138.988219) (xy 195.405619 138.957411)
			)
		)
	)
	(zone
		(net 674)
		(net_name "Net-(U45C-TESTEN)")
		(layer "B.Cu")
		(name "$teardrop_padvia$")
		(hatch none 0.1)
		(priority 30415)
		(attr
			(teardrop
				(type padvia)
			)
		)
		(connect_pads yes
			(clearance 0)
		)
		(min_thickness 0.0254)
		(filled_areas_thickness no)
		(fill yes
			(thermal_gap 0.5)
			(thermal_bridge_width 0.5)
			(island_removal_mode 1)
			(island_area_min 10)
		)
		(polygon
			(pts
				(xy 126.983 139.9975) (xy 126.923588 139.977727) (xy 126.867503 139.914453) (xy 126.845801 139.865828)
				(xy 126.831127 139.806468) (xy 126.829347 139.7945) (xy 126.569 140.06) (xy 126.829347 140.3255)
				(xy 126.842197 140.265361) (xy 126.862131 140.215477) (xy 126.888056 140.175358) (xy 126.917876 140.146345)
				(xy 126.949294 140.128854) (xy 126.981105 140.122521) (xy 126.983 140.1225)
			)
		)
	)
	(zone
		(net 1)
		(net_name "GND")
		(layer "B.Cu")
		(name "$teardrop_padvia$")
		(hatch none 0.1)
		(priority 30241)
		(attr
			(teardrop
				(type padvia)
			)
		)
		(connect_pads yes
			(clearance 0)
		)
		(min_thickness 0.0254)
		(filled_areas_thickness no)
		(fill yes
			(thermal_gap 0.5)
			(thermal_bridge_width 0.5)
			(island_removal_mode 1)
			(island_area_min 10)
		)
		(polygon
			(pts
				(xy 176.779323 99.51) (xy 176.9369 99.516932) (xy 177.050434 99.545456) (xy 177.092222 99.5625)
				(xy 177.181 99.36) (xy 177.092222 99.1575) (xy 176.996177 99.191883) (xy 176.894296 99.207101) (xy 176.779323 99.21)
			)
		)
	)
	(zone
		(net 292)
		(net_name "/2xUSB3.0+RJ45/GbE.MDI1-")
		(layer "B.Cu")
		(name "$teardrop_padvia$")
		(hatch none 0.1)
		(priority 30664)
		(attr
			(teardrop
				(type padvia)
			)
		)
		(connect_pads yes
			(clearance 0)
		)
		(min_thickness 0.0254)
		(filled_areas_thickness no)
		(fill yes
			(thermal_gap 0.5)
			(thermal_bridge_width 0.5)
			(island_removal_mode 1)
			(island_area_min 10)
		)
		(polygon
			(pts
				(xy 170.7 163.657916) (xy 170.702203 163.8633) (xy 170.704323 164.001757) (xy 170.925 164.001) (xy 171.050003 163.812919)
				(xy 170.973862 163.779004) (xy 170.957261 163.773949) (xy 170.915719 163.760156) (xy 170.881601 163.740737)
				(xy 170.858499 163.708917) (xy 170.85 163.657916)
			)
		)
	)
	(zone
		(net 575)
		(net_name "Net-(U18-MODE)")
		(layer "B.Cu")
		(name "$teardrop_padvia$")
		(hatch none 0.1)
		(priority 30199)
		(attr
			(teardrop
				(type padvia)
			)
		)
		(connect_pads yes
			(clearance 0)
		)
		(min_thickness 0.0254)
		(filled_areas_thickness no)
		(fill yes
			(thermal_gap 0.5)
			(thermal_bridge_width 0.5)
			(island_removal_mode 1)
			(island_area_min 10)
		)
		(polygon
			(pts
				(xy 309.502949 121.850438) (xy 309.581289 121.799788) (xy 309.704271 121.769586) (xy 309.87068 121.771975)
				(xy 309.892925 121.775) (xy 309.825706 121.479293) (xy 309.504999 121.409441) (xy 309.504099 121.556329)
				(xy 309.489868 121.623957) (xy 309.467988 121.682903) (xy 309.414561 121.76205)
			)
		)
	)
	(zone
		(net 1)
		(net_name "GND")
		(layer "B.Cu")
		(name "$teardrop_padvia$")
		(hatch none 0.1)
		(priority 30874)
		(attr
			(teardrop
				(type padvia)
			)
		)
		(connect_pads yes
			(clearance 0)
		)
		(min_thickness 0.0254)
		(filled_areas_thickness no)
		(fill yes
			(thermal_gap 0.5)
			(thermal_bridge_width 0.5)
			(island_removal_mode 1)
			(island_area_min 10)
		)
		(polygon
			(pts
				(xy 104.738 165.5475) (xy 104.704137 165.541719) (xy 104.669515 165.521254) (xy 104.647693 165.494188)
				(xy 104.632 165.454848) (xy 104.628711 165.439289) (xy 104.382 165.61) (xy 104.628711 165.780711)
				(xy 104.640301 165.74049) (xy 104.657885 165.711016) (xy 104.705468 165.677827) (xy 104.738 165.6725)
			)
		)
	)
	(zone
		(net 203)
		(net_name "/Backplane/PCIe_{REF}.CK+")
		(layer "B.Cu")
		(name "$teardrop_padvia$")
		(hatch none 0.1)
		(priority 30044)
		(attr
			(teardrop
				(type padvia)
			)
		)
		(connect_pads yes
			(clearance 0)
		)
		(min_thickness 0.0254)
		(filled_areas_thickness no)
		(fill yes
			(thermal_gap 0.5)
			(thermal_bridge_width 0.5)
			(island_removal_mode 1)
			(island_area_min 10)
		)
		(polygon
			(pts
				(xy 317.860744 164.4165) (xy 318.255858 164.399246) (xy 318.69849 164.377362) (xy 318.959827 164.375348)
				(xy 319.254117 164.385) (xy 319.451 164.11) (xy 317.95 164.054408) (xy 317.950007 164.113332) (xy 317.940774 164.156415)
				(xy 317.925619 164.184485) (xy 317.906098 164.202295) (xy 317.860744 164.2145)
			)
		)
	)
	(zone
		(net 674)
		(net_name "Net-(U45C-TESTEN)")
		(layer "B.Cu")
		(name "$teardrop_padvia$")
		(hatch none 0.1)
		(priority 30824)
		(attr
			(teardrop
				(type padvia)
			)
		)
		(connect_pads yes
			(clearance 0)
		)
		(min_thickness 0.0254)
		(filled_areas_thickness no)
		(fill yes
			(thermal_gap 0.5)
			(thermal_bridge_width 0.5)
			(island_removal_mode 1)
			(island_area_min 10)
		)
		(polygon
			(pts
				(xy 128.202901 140.521289) (xy 128.223971 140.549104) (xy 128.230503 140.574568) (xy 128.213557 140.617676)
				(xy 128.167171 140.665489) (xy 128.102919 140.734997) (xy 128.290707 140.860707) (xy 128.477081 140.734997)
				(xy 128.41193 140.611746) (xy 128.371279 140.530407) (xy 128.291289 140.432901)
			)
		)
	)
	(zone
		(net 1)
		(net_name "GND")
		(layer "B.Cu")
		(name "$teardrop_padvia$")
		(hatch none 0.1)
		(priority 30284)
		(attr
			(teardrop
				(type padvia)
			)
		)
		(connect_pads yes
			(clearance 0)
		)
		(min_thickness 0.0254)
		(filled_areas_thickness no)
		(fill yes
			(thermal_gap 0.5)
			(thermal_bridge_width 0.5)
			(island_removal_mode 1)
			(island_area_min 10)
		)
		(polygon
			(pts
				(xy 123.056887 137.569755) (xy 122.979414 137.484861) (xy 122.932294 137.414076) (xy 122.88941 137.308904)
				(xy 122.679293 137.379293) (xy 122.589925 137.581548) (xy 122.663826 137.620436) (xy 122.726371 137.667507)
				(xy 122.834859 137.771988) (xy 122.844755 137.781887)
			)
		)
	)
	(zone
		(net 49)
		(net_name "/2xUSB3.0+RJ45/USBSS_2.TX-")
		(layer "B.Cu")
		(name "$teardrop_padvia$")
		(hatch none 0.1)
		(priority 31021)
		(attr
			(teardrop
				(type padvia)
			)
		)
		(connect_pads yes
			(clearance 0)
		)
		(min_thickness 0.0254)
		(filled_areas_thickness no)
		(fill yes
			(thermal_gap 0.5)
			(thermal_bridge_width 0.5)
			(island_removal_mode 1)
			(island_area_min 10)
		)
		(polygon
			(pts
				(xy 123.338 103.7095) (xy 123.319153 103.7144) (xy 123.285892 103.720518) (xy 123.271353 103.712159)
				(xy 123.261005 103.6895) (xy 123.012 103.802) (xy 123.261005 103.9145) (xy 123.270976 103.892283)
				(xy 123.284951 103.883669) (xy 123.319153 103.8896) (xy 123.338 103.8945)
			)
		)
	)
	(zone
		(net 964)
		(net_name "/PCIe redriver/PCIe_{O}_C.TX2-")
		(layer "B.Cu")
		(name "$teardrop_padvia$")
		(hatch none 0.1)
		(priority 30168)
		(attr
			(teardrop
				(type padvia)
			)
		)
		(connect_pads yes
			(clearance 0)
		)
		(min_thickness 0.0254)
		(filled_areas_thickness no)
		(fill yes
			(thermal_gap 0.5)
			(thermal_bridge_width 0.5)
			(island_removal_mode 1)
			(island_area_min 10)
		)
		(polygon
			(pts
				(xy 110.660959 160.062786) (xy 110.632959 160.043462) (xy 110.611631 160.015826) (xy 110.587003 159.932023)
				(xy 110.586 159.765097) (xy 110.29 159.869) (xy 110.265937 160.189) (xy 110.379193 160.179285) (xy 110.508359 160.203097)
				(xy 110.660959 160.264786)
			)
		)
	)
	(zone
		(net 352)
		(net_name "Net-(J12D-LPC_AD3{slash}ESPI_IO_3)")
		(layer "B.Cu")
		(name "$teardrop_padvia$")
		(hatch none 0.1)
		(priority 30107)
		(attr
			(teardrop
				(type padvia)
			)
		)
		(connect_pads yes
			(clearance 0)
		)
		(min_thickness 0.0254)
		(filled_areas_thickness no)
		(fill yes
			(thermal_gap 0.5)
			(thermal_bridge_width 0.5)
			(island_removal_mode 1)
			(island_area_min 10)
		)
		(polygon
			(pts
				(xy 178.017794 163.7375) (xy 177.935734 163.732685) (xy 177.870388 163.718981) (xy 177.777121 163.672424)
				(xy 177.698658 163.604214) (xy 177.637159 163.548058) (xy 177.558339 163.488199) (xy 177.349 163.8)
				(xy 177.558339 164.111801) (xy 177.678517 164.01478) (xy 177.698657 163.995787) (xy 177.757541 163.942634)
				(xy 177.821624 163.900409) (xy 177.904008 163.872551) (xy 178.017794 163.8625)
			)
		)
	)
	(zone
		(net 78)
		(net_name "+1V8")
		(layer "B.Cu")
		(name "$teardrop_padvia$")
		(hatch none 0.1)
		(priority 30813)
		(attr
			(teardrop
				(type padvia)
			)
		)
		(connect_pads yes
			(clearance 0)
		)
		(min_thickness 0.0254)
		(filled_areas_thickness no)
		(fill yes
			(thermal_gap 0.5)
			(thermal_bridge_width 0.5)
			(island_removal_mode 1)
			(island_area_min 10)
		)
		(polygon
			(pts
				(xy 147.850677 133.8075) (xy 147.785169 133.80272) (xy 147.736274 133.78926) (xy 147.664764 133.743395)
				(xy 147.649678 133.730692) (xy 147.575003 133.672919) (xy 147.449 133.86) (xy 147.575003 134.047081)
				(xy 147.63207 134.006499) (xy 147.720784 133.951924) (xy 147.775503 133.937471) (xy 147.850677 133.9325)
			)
		)
	)
	(zone
		(net 2)
		(net_name "+3V3")
		(layer "B.Cu")
		(name "$teardrop_padvia$")
		(hatch none 0.1)
		(priority 30196)
		(attr
			(teardrop
				(type padvia)
			)
		)
		(connect_pads yes
			(clearance 0)
		)
		(min_thickness 0.0254)
		(filled_areas_thickness no)
		(fill yes
			(thermal_gap 0.5)
			(thermal_bridge_width 0.5)
			(island_removal_mode 1)
			(island_area_min 10)
		)
		(polygon
			(pts
				(xy 218.7 129.888) (xy 218.696707 129.928701) (xy 218.677798 129.968694) (xy 218.629729 129.999856)
				(xy 218.538954 130.014065) (xy 218.727 130.327) (xy 219.022 130.1535) (xy 218.984663 130.098296)
				(xy 218.977964 130.026398) (xy 218.99017 129.952806) (xy 219 129.888)
			)
		)
	)
	(zone
		(net 578)
		(net_name "/Power/PG_{1V0}")
		(layer "B.Cu")
		(name "$teardrop_padvia$")
		(hatch none 0.1)
		(priority 30741)
		(attr
			(teardrop
				(type padvia)
			)
		)
		(connect_pads yes
			(clearance 0)
		)
		(min_thickness 0.0254)
		(filled_areas_thickness no)
		(fill yes
			(thermal_gap 0.5)
			(thermal_bridge_width 0.5)
			(island_removal_mode 1)
			(island_area_min 10)
		)
		(polygon
			(pts
				(xy 311.665676 118.5975) (xy 311.596235 118.592682) (xy 311.544912 118.57896) (xy 311.46937 118.532246)
				(xy 311.45723 118.522701) (xy 311.390002 118.472919) (xy 311.263999 118.66) (xy 311.390002 118.847081)
				(xy 311.457228 118.797299) (xy 311.540395 118.742894) (xy 311.59325 118.72781) (xy 311.665676 118.7225)
			)
		)
	)
	(zone
		(net 574)
		(net_name "Net-(U19-EN)")
		(layer "B.Cu")
		(name "$teardrop_padvia$")
		(hatch none 0.1)
		(priority 30428)
		(attr
			(teardrop
				(type padvia)
			)
		)
		(connect_pads yes
			(clearance 0)
		)
		(min_thickness 0.0254)
		(filled_areas_thickness no)
		(fill yes
			(thermal_gap 0.5)
			(thermal_bridge_width 0.5)
			(island_removal_mode 1)
			(island_area_min 10)
		)
		(polygon
			(pts
				(xy 308.762499 100.867) (xy 308.742726 100.926412) (xy 308.679452 100.982496) (xy 308.630827 101.004198)
				(xy 308.571468 101.018872) (xy 308.559499 101.020652) (xy 308.824999 101.281) (xy 309.090499 101.020652)
				(xy 309.030361 101.007803) (xy 308.980477 100.987869) (xy 308.940357 100.961944) (xy 308.911344 100.932124)
				(xy 308.893853 100.900706) (xy 308.88752 100.868895) (xy 308.887499 100.867)
			)
		)
	)
	(zone
		(net 427)
		(net_name "/2xSFP+/10GKR_SFP1.RX+")
		(layer "B.Cu")
		(name "$teardrop_padvia$")
		(hatch none 0.1)
		(priority 30609)
		(attr
			(teardrop
				(type padvia)
			)
		)
		(connect_pads yes
			(clearance 0)
		)
		(min_thickness 0.0254)
		(filled_areas_thickness no)
		(fill yes
			(thermal_gap 0.5)
			(thermal_bridge_width 0.5)
			(island_removal_mode 1)
			(island_area_min 10)
		)
		(polygon
			(pts
				(xy 135.055 147.972566) (xy 135.05976 147.931044) (xy 135.073082 147.901025) (xy 135.117478 147.865545)
				(xy 135.165059 147.847389) (xy 135.255003 147.807081) (xy 135.13 147.619) (xy 134.909323 147.618026)
				(xy 134.902491 147.772392) (xy 134.895 147.972566)
			)
		)
	)
	(zone
		(net 47)
		(net_name "/2xUSB3.0+RJ45/USBSS_1.TX-")
		(layer "B.Cu")
		(name "$teardrop_padvia$")
		(hatch none 0.1)
		(priority 30037)
		(attr
			(teardrop
				(type padvia)
			)
		)
		(connect_pads yes
			(clearance 0)
		)
		(min_thickness 0.0254)
		(filled_areas_thickness no)
		(fill yes
			(thermal_gap 0.5)
			(thermal_bridge_width 0.5)
			(island_removal_mode 1)
			(island_area_min 10)
		)
		(polygon
			(pts
				(xy 107.483266 103.05787) (xy 107.523245 103.034791) (xy 107.552142 103.030844) (xy 107.578057 103.054935)
				(xy 107.589296 103.12432) (xy 107.584811 103.254453) (xy 107.579403 103.381055) (xy 107.58797 103.496686)
				(xy 108.250809 103.364413) (xy 108.118314 102.70297) (xy 107.9037 102.73131) (xy 107.858316 102.734528)
				(xy 107.746424 102.744375) (xy 107.63756 102.767196) (xy 107.518127 102.817102) (xy 107.374528 102.908202)
			)
		)
	)
	(zone
		(net 157)
		(net_name "Net-(J1A-LED_D4)")
		(layer "B.Cu")
		(name "$teardrop_padvia$")
		(hatch none 0.1)
		(priority 30386)
		(attr
			(teardrop
				(type padvia)
			)
		)
		(connect_pads yes
			(clearance 0)
		)
		(min_thickness 0.0254)
		(filled_areas_thickness no)
		(fill yes
			(thermal_gap 0.5)
			(thermal_bridge_width 0.5)
			(island_removal_mode 1)
			(island_area_min 10)
		)
		(polygon
			(pts
				(xy 122.8575 112.372) (xy 122.837531 112.434866) (xy 122.811079 112.466844) (xy 122.773668 112.495358)
				(xy 122.726473 112.517882) (xy 122.668833 112.533093) (xy 122.668202 112.533202) (xy 122.92 112.811)
				(xy 123.171798 112.533202) (xy 123.116365 112.518905) (xy 123.07048 112.497825) (xy 123.032799 112.47046)
				(xy 123.005566 112.439552) (xy 122.988528 112.406265) (xy 122.982511 112.373434) (xy 122.9825 112.372)
			)
		)
	)
	(zone
		(net 84)
		(net_name "/Com Express 7 MGMT/PWRBTN")
		(layer "B.Cu")
		(name "$teardrop_padvia$")
		(hatch none 0.1)
		(priority 30280)
		(attr
			(teardrop
				(type padvia)
			)
		)
		(connect_pads yes
			(clearance 0)
		)
		(min_thickness 0.0254)
		(filled_areas_thickness no)
		(fill yes
			(thermal_gap 0.5)
			(thermal_bridge_width 0.5)
			(island_removal_mode 1)
			(island_area_min 10)
		)
		(polygon
			(pts
				(xy 99.279 121.46) (xy 99.290728 121.45977) (xy 99.326014 121.46069) (xy 99.361192 121.473174) (xy 99.388205 121.509014)
				(xy 99.399 121.58) (xy 99.7 121.31) (xy 99.399 121.04) (xy 99.394355 121.090215) (xy 99.38184 121.124212)
				(xy 99.344927 121.154973) (xy 99.290728 121.16023) (xy 99.279 121.16)
			)
		)
	)
	(zone
		(net 289)
		(net_name "/2xUSB3.0+RJ45/GbE.MDI2-")
		(layer "B.Cu")
		(name "$teardrop_padvia$")
		(hatch none 0.1)
		(priority 30649)
		(attr
			(teardrop
				(type padvia)
			)
		)
		(connect_pads yes
			(clearance 0)
		)
		(min_thickness 0.0254)
		(filled_areas_thickness no)
		(fill yes
			(thermal_gap 0.5)
			(thermal_bridge_width 0.5)
			(island_removal_mode 1)
			(island_area_min 10)
		)
		(polygon
			(pts
				(xy 166.65 150.142084) (xy 166.654756 150.102162) (xy 166.66805 150.073745) (xy 166.712129 150.041329)
				(xy 166.757262 150.02605) (xy 166.803541 150.010756) (xy 166.850003 149.987081) (xy 166.725 149.799)
				(xy 166.504323 149.798242) (xy 166.502203 149.936699) (xy 166.5 150.142084)
			)
		)
	)
	(zone
		(net 1)
		(net_name "GND")
		(layer "B.Cu")
		(name "$teardrop_padvia$")
		(hatch none 0.1)
		(priority 30677)
		(attr
			(teardrop
				(type padvia)
			)
		)
		(connect_pads yes
			(clearance 0)
		)
		(min_thickness 0.0254)
		(filled_areas_thickness no)
		(fill yes
			(thermal_gap 0.5)
			(thermal_bridge_width 0.5)
			(island_removal_mode 1)
			(island_area_min 10)
		)
		(polygon
			(pts
				(xy 145.894672 135.816285) (xy 145.84807 135.776226) (xy 145.80558 135.75126) (xy 145.716731 135.725967)
				(xy 145.650355 135.710119) (xy 145.575003 135.672919) (xy 145.449293 135.859293) (xy 145.575003 136.047081)
				(xy 145.634761 135.988848) (xy 145.660683 135.954779) (xy 145.693853 135.912322) (xy 145.727175 135.883374)
				(xy 145.763652 135.877603) (xy 145.806285 135.904672)
			)
		)
	)
	(zone
		(net 213)
		(net_name "/Com Express 7 Interfaces/PCIe_{B1x4}.RX2-")
		(layer "B.Cu")
		(name "$teardrop_padvia$")
		(hatch none 0.1)
		(priority 30164)
		(attr
			(teardrop
				(type padvia)
			)
		)
		(connect_pads yes
			(clearance 0)
		)
		(min_thickness 0.0254)
		(filled_areas_thickness no)
		(fill yes
			(thermal_gap 0.5)
			(thermal_bridge_width 0.5)
			(island_removal_mode 1)
			(island_area_min 10)
		)
		(polygon
			(pts
				(xy 196.870812 139.872473) (xy 196.865162 139.839769) (xy 196.870102 139.806378) (xy 196.912695 139.733105)
				(xy 197.040769 139.611094) (xy 196.763937 139.46932) (xy 196.512741 139.670672) (xy 196.595927 139.747935)
				(xy 196.667147 139.861404) (xy 196.727977 140.015308)
			)
		)
	)
	(zone
		(net 203)
		(net_name "/Backplane/PCIe_{REF}.CK+")
		(layer "B.Cu")
		(name "$teardrop_padvia$")
		(hatch none 0.1)
		(priority 31001)
		(attr
			(teardrop
				(type padvia)
			)
		)
		(connect_pads yes
			(clearance 0)
		)
		(min_thickness 0.0254)
		(filled_areas_thickness no)
		(fill yes
			(thermal_gap 0.5)
			(thermal_bridge_width 0.5)
			(island_removal_mode 1)
			(island_area_min 10)
		)
		(polygon
			(pts
				(xy 314.69 164.609) (xy 314.669352 164.616199) (xy 314.637017 164.625792) (xy 314.622994 164.618965)
				(xy 314.613005 164.5975) (xy 314.364 164.71) (xy 314.613005 164.8225) (xy 314.62273 164.801324)
				(xy 314.636358 164.794269) (xy 314.669352 164.803801) (xy 314.69 164.811)
			)
		)
	)
	(zone
		(net 1)
		(net_name "GND")
		(layer "B.Cu")
		(name "$teardrop_padvia$")
		(hatch none 0.1)
		(priority 30226)
		(attr
			(teardrop
				(type padvia)
			)
		)
		(connect_pads yes
			(clearance 0)
		)
		(min_thickness 0.0254)
		(filled_areas_thickness no)
		(fill yes
			(thermal_gap 0.5)
			(thermal_bridge_width 0.5)
			(island_removal_mode 1)
			(island_area_min 10)
		)
		(polygon
			(pts
				(xy 98.261739 160.801739) (xy 98.363619 160.801371) (xy 98.52223 160.804239) (xy 98.611008 160.601739)
				(xy 98.52223 160.399239) (xy 98.363608 160.402106) (xy 98.261739 160.401739)
			)
		)
	)
	(zone
		(net 126)
		(net_name "/2xUSB3.0+RJ45/P2_D+")
		(layer "B.Cu")
		(name "$teardrop_padvia$")
		(hatch none 0.1)
		(priority 30134)
		(attr
			(teardrop
				(type padvia)
			)
		)
		(connect_pads yes
			(clearance 0)
		)
		(min_thickness 0.0254)
		(filled_areas_thickness no)
		(fill yes
			(thermal_gap 0.5)
			(thermal_bridge_width 0.5)
			(island_removal_mode 1)
			(island_area_min 10)
		)
		(polygon
			(pts
				(xy 113.43026 106.570445) (xy 113.385974 106.518539) (xy 113.345392 106.4529) (xy 113.315118 106.382919)
				(xy 113.292918 106.302209) (xy 113.28 106.169162) (xy 112.979293 106.250293) (xy 112.898162 106.551)
				(xy 113.054302 106.569039) (xy 113.187908 106.619558) (xy 113.293748 106.695673) (xy 113.299445 106.70126)
			)
		)
	)
	(zone
		(net 53)
		(net_name "/2xSFP+/SH")
		(layer "B.Cu")
		(name "$teardrop_padvia$")
		(hatch none 0.1)
		(priority 30009)
		(attr
			(teardrop
				(type padvia)
			)
		)
		(connect_pads yes
			(clearance 0)
		)
		(min_thickness 0.0254)
		(filled_areas_thickness no)
		(fill yes
			(thermal_gap 0.5)
			(thermal_bridge_width 0.5)
			(island_removal_mode 1)
			(island_area_min 10)
		)
		(polygon
			(pts
				(xy 152.4 159.623353) (xy 152.4048 159.48413) (xy 152.418403 159.3652) (xy 152.466855 159.174229)
				(xy 152.545638 159.000686) (xy 152.581503 158.934521) (xy 152.675659 158.751109) (xy 152.721191 158.640509)
				(xy 152.763354 158.509996) (xy 152.05 158.309) (xy 151.431573 158.731853) (xy 151.548256 158.872002)
				(xy 151.691813 158.992685) (xy 151.768624 159.047206) (xy 151.896431 159.141754) (xy 151.952671 159.193788)
				(xy 152.001894 159.253056) (xy 152.042669 159.322602) (xy 152.073566 159.40547) (xy 152.093153 159.504706)
				(xy 152.1 159.623353)
			)
		)
	)
	(zone
		(net 313)
		(net_name "/2xUSB3.0+RJ45/USB_1.D+")
		(layer "B.Cu")
		(name "$teardrop_padvia$")
		(hatch none 0.1)
		(priority 30585)
		(attr
			(teardrop
				(type padvia)
			)
		)
		(connect_pads yes
			(clearance 0)
		)
		(min_thickness 0.0254)
		(filled_areas_thickness no)
		(fill yes
			(thermal_gap 0.5)
			(thermal_bridge_width 0.5)
			(island_removal_mode 1)
			(island_area_min 10)
		)
		(polygon
			(pts
				(xy 134.604506 115.595978) (xy 134.569609 115.624171) (xy 134.536676 115.638468) (xy 134.474183 115.637628)
				(xy 134.427903 115.623636) (xy 134.375931 115.60795) (xy 134.31751 115.601281) (xy 134.321251 115.822665)
				(xy 134.486794 115.969205) (xy 134.616085 115.840111) (xy 134.735321 115.726793)
			)
		)
	)
	(zone
		(net 78)
		(net_name "+1V8")
		(layer "B.Cu")
		(name "$teardrop_padvia$")
		(hatch none 0.1)
		(priority 30364)
		(attr
			(teardrop
				(type padvia)
			)
		)
		(connect_pads yes
			(clearance 0)
		)
		(min_thickness 0.0254)
		(filled_areas_thickness no)
		(fill yes
			(thermal_gap 0.5)
			(thermal_bridge_width 0.5)
			(island_removal_mode 1)
			(island_area_min 10)
		)
		(polygon
			(pts
				(xy 140.1575 140.922) (xy 140.137531 140.984866) (xy 140.111079 141.016844) (xy 140.073668 141.045358)
				(xy 140.026473 141.067882) (xy 139.968833 141.083093) (xy 139.968202 141.083202) (xy 140.22 141.361)
				(xy 140.471798 141.083202) (xy 140.416365 141.068905) (xy 140.37048 141.047825) (xy 140.332799 141.02046)
				(xy 140.305566 140.989552) (xy 140.288528 140.956265) (xy 140.282511 140.923434) (xy 140.2825 140.922)
			)
		)
	)
	(zone
		(net 88)
		(net_name "/Com Express 7 Interfaces/PCIe_{B2Ax4}.RX2-")
		(layer "B.Cu")
		(name "$teardrop_padvia$")
		(hatch none 0.1)
		(priority 30549)
		(attr
			(teardrop
				(type padvia)
			)
		)
		(connect_pads yes
			(clearance 0)
		)
		(min_thickness 0.0254)
		(filled_areas_thickness no)
		(fill yes
			(thermal_gap 0.5)
			(thermal_bridge_width 0.5)
			(island_removal_mode 1)
			(island_area_min 10)
		)
		(polygon
			(pts
				(xy 290.542 75.019852) (xy 290.547395 75.181383) (xy 290.550945 75.265794) (xy 290.546323 75.367488)
				(xy 290.767 75.388348) (xy 290.930231 75.238495) (xy 290.861562 75.184355) (xy 290.845108 75.174464)
				(xy 290.806435 75.149964) (xy 290.774221 75.120457) (xy 290.752173 75.079301) (xy 290.744 75.019852)
			)
		)
	)
	(zone
		(net 168)
		(net_name "Net-(J2A-RX_{LOS})")
		(layer "B.Cu")
		(name "$teardrop_padvia$")
		(hatch none 0.1)
		(priority 30071)
		(attr
			(teardrop
				(type padvia)
			)
		)
		(connect_pads yes
			(clearance 0)
		)
		(min_thickness 0.0254)
		(filled_areas_thickness no)
		(fill yes
			(thermal_gap 0.5)
			(thermal_bridge_width 0.5)
			(island_removal_mode 1)
			(island_area_min 10)
		)
		(polygon
			(pts
				(xy 144.252736 165.095652) (xy 144.317615 165.037595) (xy 144.377096 164.997584) (xy 144.482061 164.959114)
				(xy 144.618356 164.949873) (xy 144.71714 164.946966) (xy 144.833889 164.931738) (xy 144.750707 164.509293)
				(xy 144.328262 164.426111) (xy 144.310953 164.588348) (xy 144.310127 164.641644) (xy 144.307095 164.731998)
				(xy 144.29074 164.818037) (xy 144.247634 164.907285) (xy 144.164348 165.007264)
			)
		)
	)
	(zone
		(net 1)
		(net_name "GND")
		(layer "B.Cu")
		(name "$teardrop_padvia$")
		(hatch none 0.1)
		(priority 30876)
		(attr
			(teardrop
				(type padvia)
			)
		)
		(connect_pads yes
			(clearance 0)
		)
		(min_thickness 0.0254)
		(filled_areas_thickness no)
		(fill yes
			(thermal_gap 0.5)
			(thermal_bridge_width 0.5)
			(island_removal_mode 1)
			(island_area_min 10)
		)
		(polygon
			(pts
				(xy 104.8 165.6725) (xy 104.833863 165.678281) (xy 104.868484 165.698745) (xy 104.890306 165.72581)
				(xy 104.906 165.76515) (xy 104.909289 165.780711) (xy 105.156 165.61) (xy 104.909289 165.439289)
				(xy 104.8977 165.47951) (xy 104.880116 165.508984) (xy 104.832534 165.542173) (xy 104.8 165.5475)
			)
		)
	)
	(zone
		(net 237)
		(net_name "/Com Express 7 Interfaces/PCIe_{B2Bx4}.RX3-")
		(layer "B.Cu")
		(name "$teardrop_padvia$")
		(hatch none 0.1)
		(priority 30306)
		(attr
			(teardrop
				(type padvia)
			)
		)
		(connect_pads yes
			(clearance 0)
		)
		(min_thickness 0.0254)
		(filled_areas_thickness no)
		(fill yes
			(thermal_gap 0.5)
			(thermal_bridge_width 0.5)
			(island_removal_mode 1)
			(island_area_min 10)
		)
		(polygon
			(pts
				(xy 175.39 94.461) (xy 175.404678 94.457463) (xy 175.434685 94.454192) (xy 175.445673 94.466143)
				(xy 175.45 94.495) (xy 176.201 94.36) (xy 175.45 94.225) (xy 175.445525 94.254204) (xy 175.434203 94.265997)
				(xy 175.404678 94.262537) (xy 175.39 94.259)
			)
		)
	)
	(zone
		(net 2)
		(net_name "+3V3")
		(layer "B.Cu")
		(name "$teardrop_padvia$")
		(hatch none 0.1)
		(priority 30141)
		(attr
			(teardrop
				(type padvia)
			)
		)
		(connect_pads yes
			(clearance 0)
		)
		(min_thickness 0.0254)
		(filled_areas_thickness no)
		(fill yes
			(thermal_gap 0.5)
			(thermal_bridge_width 0.5)
			(island_removal_mode 1)
			(island_area_min 10)
		)
		(polygon
			(pts
				(xy 142.818305 138.266174) (xy 142.806438 138.254412) (xy 142.756135 138.201859) (xy 142.708835 138.134852)
				(xy 142.677477 138.048744) (xy 142.675 137.938889) (xy 142.379293 138.009293) (xy 142.313201 138.33)
				(xy 142.36575 138.327894) (xy 142.412177 138.334939) (xy 142.494873 138.373118) (xy 142.582573 138.453544)
				(xy 142.606174 138.478305)
			)
		)
	)
	(zone
		(net 111)
		(net_name "/2xSFP+/10GKR_SFP0.TX+")
		(layer "B.Cu")
		(name "$teardrop_padvia$")
		(hatch none 0.1)
		(priority 30671)
		(attr
			(teardrop
				(type padvia)
			)
		)
		(connect_pads yes
			(clearance 0)
		)
		(min_thickness 0.0254)
		(filled_areas_thickness no)
		(fill yes
			(thermal_gap 0.5)
			(thermal_bridge_width 0.5)
			(island_removal_mode 1)
			(island_area_min 10)
		)
		(polygon
			(pts
				(xy 197.800121 153.767284) (xy 197.776468 153.736918) (xy 197.766839 153.708579) (xy 197.776611 153.656251)
				(xy 197.795726 153.619162) (xy 197.817046 153.577925) (xy 197.832558 153.531014) (xy 197.611174 153.486412)
				(xy 197.454691 153.642013) (xy 197.54914 153.739445) (xy 197.686985 153.88042)
			)
		)
	)
	(zone
		(net 977)
		(net_name "/PCIe redriver/RX_EQ1")
		(layer "B.Cu")
		(name "$teardrop_padvia$")
		(hatch none 0.1)
		(priority 30897)
		(attr
			(teardrop
				(type padvia)
			)
		)
		(connect_pads yes
			(clearance 0)
		)
		(min_thickness 0.0254)
		(filled_areas_thickness no)
		(fill yes
			(thermal_gap 0.5)
			(thermal_bridge_width 0.5)
			(island_removal_mode 1)
			(island_area_min 10)
		)
		(polygon
			(pts
				(xy 190.329265 139.646803) (xy 190.333571 139.642366) (xy 190.365164 139.618719) (xy 190.388425 139.616639)
				(xy 190.418279 139.62872) (xy 190.631201 139.257896) (xy 190.260968 139.467841) (xy 190.271893 139.494898)
				(xy 190.271413 139.516673) (xy 190.24552 139.553915) (xy 190.240878 139.558416)
			)
		)
	)
	(zone
		(net 159)
		(net_name "/2xUSB3.0+RJ45/USBSS_1.RX+")
		(layer "B.Cu")
		(name "$teardrop_padvia$")
		(hatch none 0.1)
		(priority 30959)
		(attr
			(teardrop
				(type padvia)
			)
		)
		(connect_pads yes
			(clearance 0)
		)
		(min_thickness 0.0254)
		(filled_areas_thickness no)
		(fill yes
			(thermal_gap 0.5)
			(thermal_bridge_width 0.5)
			(island_removal_mode 1)
			(island_area_min 10)
		)
		(polygon
			(pts
				(xy 100.878 105.8295) (xy 100.865345 105.83285) (xy 100.840235 105.835949) (xy 100.831032 105.825122)
				(xy 100.827289 105.798926) (xy 100.552 105.865) (xy 100.613729 105.99) (xy 100.700586 105.979937)
				(xy 100.800085 105.999581) (xy 100.878 106.0145)
			)
		)
	)
	(zone
		(net 95)
		(net_name "/OCuLink/PCIe_{x4}.TX0-")
		(layer "B.Cu")
		(name "$teardrop_padvia$")
		(hatch none 0.1)
		(priority 31000)
		(attr
			(teardrop
				(type padvia)
			)
		)
		(connect_pads yes
			(clearance 0)
		)
		(min_thickness 0.0254)
		(filled_areas_thickness no)
		(fill yes
			(thermal_gap 0.5)
			(thermal_bridge_width 0.5)
			(island_removal_mode 1)
			(island_area_min 10)
		)
		(polygon
			(pts
				(xy 105.48 166.009) (xy 105.459352 166.016199) (xy 105.427017 166.025792) (xy 105.412994 166.018965)
				(xy 105.403005 165.9975) (xy 105.154 166.11) (xy 105.403005 166.2225) (xy 105.41273 166.201324)
				(xy 105.426358 166.194269) (xy 105.459352 166.203801) (xy 105.48 166.211)
			)
		)
	)
	(zone
		(net 59)
		(net_name "/OCuLink/V_{ACT_TX}0")
		(layer "B.Cu")
		(name "$teardrop_padvia$")
		(hatch none 0.1)
		(priority 30060)
		(attr
			(teardrop
				(type padvia)
			)
		)
		(connect_pads yes
			(clearance 0)
		)
		(min_thickness 0.0254)
		(filled_areas_thickness no)
		(fill yes
			(thermal_gap 0.5)
			(thermal_bridge_width 0.5)
			(island_removal_mode 1)
			(island_area_min 10)
		)
		(polygon
			(pts
				(xy 103.552884 157.469248) (xy 103.615243 157.416182) (xy 103.697647 157.370547) (xy 103.758665 157.35161)
				(xy 103.827731 157.343203) (xy 103.890603 157.346243) (xy 103.959117 157.36) (xy 103.950707 156.859293)
				(xy 103.55 156.750883) (xy 103.53507 156.912412) (xy 103.486465 157.055269) (xy 103.407388 157.182166)
				(xy 103.340752 157.257116)
			)
		)
	)
	(zone
		(net 1)
		(net_name "GND")
		(layer "B.Cu")
		(hatch edge 0.5)
		(priority 43)
		(connect_pads yes
			(clearance 0.15)
		)
		(min_thickness 0.25)
		(filled_areas_thickness no)
		(fill yes
			(thermal_gap 0.5)
			(thermal_bridge_width 0.5)
		)
		(polygon
			(pts
				(xy 110.82 97.21) (xy 111.87 97.21) (xy 111.87 95.211236) (xy 110.82 96.249438)
			)
		)
	)
	(zone
		(net 215)
		(net_name "/Com Express 7 Interfaces/PCIe_{B1x4}.TX2-")
		(layer "B.Cu")
		(name "$teardrop_padvia$")
		(hatch none 0.1)
		(priority 30576)
		(attr
			(teardrop
				(type padvia)
			)
		)
		(connect_pads yes
			(clearance 0)
		)
		(min_thickness 0.0254)
		(filled_areas_thickness no)
		(fill yes
			(thermal_gap 0.5)
			(thermal_bridge_width 0.5)
			(island_removal_mode 1)
			(island_area_min 10)
		)
		(polygon
			(pts
				(xy 205.876476 166.0065) (xy 205.917103 166.01125) (xy 205.946627 166.024504) (xy 205.982126 166.068999)
				(xy 206.000073 166.115363) (xy 206.038133 166.199789) (xy 206.226214 166.074786) (xy 206.235094 165.854109)
				(xy 206.098141 165.833818) (xy 206.084571 165.830559) (xy 205.998033 165.812699) (xy 205.876476 165.8045)
			)
		)
	)
	(zone
		(net 259)
		(net_name "/Com Express 7 Interfaces/PCIe_{B2Bx4}.TX1+")
		(layer "B.Cu")
		(name "$teardrop_padvia$")
		(hatch none 0.1)
		(priority 30308)
		(attr
			(teardrop
				(type padvia)
			)
		)
		(connect_pads yes
			(clearance 0)
		)
		(min_thickness 0.0254)
		(filled_areas_thickness no)
		(fill yes
			(thermal_gap 0.5)
			(thermal_bridge_width 0.5)
			(island_removal_mode 1)
			(island_area_min 10)
		)
		(polygon
			(pts
				(xy 175.39 101.461) (xy 175.404678 101.457463) (xy 175.434685 101.454192) (xy 175.445673 101.466143)
				(xy 175.45 101.495) (xy 176.201 101.36) (xy 175.45 101.225) (xy 175.445525 101.254204) (xy 175.434203 101.265997)
				(xy 175.404678 101.262537) (xy 175.39 101.259)
			)
		)
	)
	(zone
		(net 2)
		(net_name "+3V3")
		(layer "B.Cu")
		(name "$teardrop_padvia$")
		(hatch none 0.1)
		(priority 30209)
		(attr
			(teardrop
				(type padvia)
			)
		)
		(connect_pads yes
			(clearance 0)
		)
		(min_thickness 0.0254)
		(filled_areas_thickness no)
		(fill yes
			(thermal_gap 0.5)
			(thermal_bridge_width 0.5)
			(island_removal_mode 1)
			(island_area_min 10)
		)
		(polygon
			(pts
				(xy 116.012 70.49) (xy 116.02887 70.489662) (xy 116.073826 70.490241) (xy 116.121169 70.502059)
				(xy 116.163573 70.536638) (xy 116.193708 70.6055) (xy 116.451 70.34) (xy 116.193708 70.0745) (xy 116.178151 70.119269)
				(xy 116.157435 70.150885) (xy 116.106299 70.183619) (xy 116.02887 70.190338) (xy 116.012 70.19)
			)
		)
	)
	(zone
		(net 1)
		(net_name "GND")
		(layer "B.Cu")
		(name "$teardrop_padvia$")
		(hatch none 0.1)
		(priority 30121)
		(attr
			(teardrop
				(type padvia)
			)
		)
		(connect_pads yes
			(clearance 0)
		)
		(min_thickness 0.0254)
		(filled_areas_thickness no)
		(fill yes
			(thermal_gap 0.5)
			(thermal_bridge_width 0.5)
			(island_removal_mode 1)
			(island_area_min 10)
		)
		(polygon
			(pts
				(xy 136.54 131.86) (xy 136.536537 131.838752) (xy 136.533987 131.818574) (xy 136.547654 131.80285)
				(xy 136.592905 131.792639) (xy 136.685104 131.789) (xy 136.426 131.388) (xy 135.956409 131.717512)
				(xy 136.013623 131.734519) (xy 136.045988 131.754228) (xy 136.058217 131.772073) (xy 136.060608 131.790591)
				(xy 136.049483 131.827529) (xy 136.04 131.86)
			)
		)
	)
	(zone
		(net 627)
		(net_name "/PCIe redriver/TX_FG1")
		(layer "B.Cu")
		(name "$teardrop_padvia$")
		(hatch none 0.1)
		(priority 30911)
		(attr
			(teardrop
				(type padvia)
			)
		)
		(connect_pads yes
			(clearance 0)
		)
		(min_thickness 0.0254)
		(filled_areas_thickness no)
		(fill yes
			(thermal_gap 0.5)
			(thermal_bridge_width 0.5)
			(island_removal_mode 1)
			(island_area_min 10)
		)
		(polygon
			(pts
				(xy 113.4635 149.5355) (xy 113.463404 149.529178) (xy 113.468989 149.489675) (xy 113.483922 149.471452)
				(xy 113.5135 149.458504) (xy 113.401 149.047) (xy 113.2885 149.458504) (xy 113.315493 149.46962)
				(xy 113.330595 149.485147) (xy 113.338596 149.529178) (xy 113.3385 149.5355)
			)
		)
	)
	(zone
		(net 1)
		(net_name "GND")
		(layer "B.Cu")
		(name "$teardrop_padvia$")
		(hatch none 0.1)
		(priority 30870)
		(attr
			(teardrop
				(type padvia)
			)
		)
		(connect_pads yes
			(clearance 0)
		)
		(min_thickness 0.0254)
		(filled_areas_thickness no)
		(fill yes
			(thermal_gap 0.5)
			(thermal_bridge_width 0.5)
			(island_removal_mode 1)
			(island_area_min 10)
		)
		(polygon
			(pts
				(xy 314.782 161.01) (xy 314.792115 161.009847) (xy 314.822832 161.01046) (xy 314.85532 161.018782)
				(xy 314.884475 161.042675) (xy 314.905191 161.09) (xy 315.138 160.91) (xy 314.905191 160.73) (xy 314.891833 160.765901)
				(xy 314.873601 160.789199) (xy 314.828276 160.808899) (xy 314.792115 160.810153) (xy 314.782 160.81)
			)
		)
	)
	(zone
		(net 155)
		(net_name "Net-(J1A-LED_D2)")
		(layer "B.Cu")
		(name "$teardrop_padvia$")
		(hatch none 0.1)
		(priority 30454)
		(attr
			(teardrop
				(type padvia)
			)
		)
		(connect_pads yes
			(clearance 0)
		)
		(min_thickness 0.0254)
		(filled_areas_thickness no)
		(fill yes
			(thermal_gap 0.5)
			(thermal_bridge_width 0.5)
			(island_removal_mode 1)
			(island_area_min 10)
		)
		(polygon
			(pts
				(xy 122.507 99.9225) (xy 122.566412 99.942273) (xy 122.622497 100.005547) (xy 122.644199 100.054172)
				(xy 122.658873 100.113531) (xy 122.660653 100.1255) (xy 122.921 99.86) (xy 122.660653 99.5945) (xy 122.647804 99.654638)
				(xy 122.62787 99.704522) (xy 122.601945 99.744641) (xy 122.572125 99.773654) (xy 122.540707 99.791146)
				(xy 122.508896 99.797479) (xy 122.507 99.7975)
			)
		)
	)
	(zone
		(net 166)
		(net_name "Net-(J2A-MOD_{ABS})")
		(layer "B.Cu")
		(name "$teardrop_padvia$")
		(hatch none 0.1)
		(priority 30665)
		(attr
			(teardrop
				(type padvia)
			)
		)
		(connect_pads yes
			(clearance 0)
		)
		(min_thickness 0.0254)
		(filled_areas_thickness no)
		(fill yes
			(thermal_gap 0.5)
			(thermal_bridge_width 0.5)
			(island_removal_mode 1)
			(island_area_min 10)
		)
		(polygon
			(pts
				(xy 144.1125 168.227834) (xy 144.107989 168.110515) (xy 144.096415 168.027767) (xy 144.090415 167.996134)
				(xy 144.070677 167.87972) (xy 143.85 167.909) (xy 143.73032 168.099286) (xy 143.800761 168.124827)
				(xy 143.862409 168.13135) (xy 143.910685 168.136095) (xy 143.950493 168.148474) (xy 143.977531 168.176412)
				(xy 143.9875 168.227834)
			)
		)
	)
	(zone
		(net 78)
		(net_name "+1V8")
		(layer "B.Cu")
		(name "$teardrop_padvia$")
		(hatch none 0.1)
		(priority 30340)
		(attr
			(teardrop
				(type padvia)
			)
		)
		(connect_pads yes
			(clearance 0)
		)
		(min_thickness 0.0254)
		(filled_areas_thickness no)
		(fill yes
			(thermal_gap 0.5)
			(thermal_bridge_width 0.5)
			(island_removal_mode 1)
			(island_area_min 10)
		)
		(polygon
			(pts
				(xy 158.3175 140.922) (xy 158.297531 140.984866) (xy 158.271079 141.016844) (xy 158.233668 141.045358)
				(xy 158.186473 141.067882) (xy 158.128833 141.083093) (xy 158.128202 141.083202) (xy 158.38 141.361)
				(xy 158.631798 141.083202) (xy 158.576365 141.068905) (xy 158.53048 141.047825) (xy 158.492799 141.02046)
				(xy 158.465566 140.989552) (xy 158.448528 140.956265) (xy 158.442511 140.923434) (xy 158.4425 140.922)
			)
		)
	)
	(zone
		(net 629)
		(net_name "Net-(U39-EN_{I2C})")
		(layer "B.Cu")
		(name "$teardrop_padvia$")
		(hatch none 0.1)
		(priority 30935)
		(attr
			(teardrop
				(type padvia)
			)
		)
		(connect_pads yes
			(clearance 0)
		)
		(min_thickness 0.0254)
		(filled_areas_thickness no)
		(fill yes
			(thermal_gap 0.5)
			(thermal_bridge_width 0.5)
			(island_removal_mode 1)
			(island_area_min 10)
		)
		(polygon
			(pts
				(xy 122.3255 148.0875) (xy 122.322086 148.087527) (xy 122.290565 148.080989) (xy 122.278069 148.064747)
				(xy 122.272397 148.032902) (xy 121.837 148.111) (xy 122.236918 148.231242) (xy 122.249682 148.214899)
				(xy 122.265964 148.207741) (xy 122.306367 148.209995) (xy 122.3255 148.2125)
			)
		)
	)
	(zone
		(net 575)
		(net_name "Net-(U18-MODE)")
		(layer "B.Cu")
		(name "$teardrop_padvia$")
		(hatch none 0.1)
		(priority 30217)
		(attr
			(teardrop
				(type padvia)
			)
		)
		(connect_pads yes
			(clearance 0)
		)
		(min_thickness 0.0254)
		(filled_areas_thickness no)
		(fill yes
			(thermal_gap 0.5)
			(thermal_bridge_width 0.5)
			(island_removal_mode 1)
			(island_area_min 10)
		)
		(polygon
			(pts
				(xy 309.126055 122.050556) (xy 309.042712 122.105935) (xy 308.912723 122.142154) (xy 308.832133 122.148517)
				(xy 308.744525 122.145) (xy 308.824292 122.440707) (xy 309.144999 122.495474) (xy 309.135981 122.344316)
				(xy 309.145825 122.276785) (xy 309.16409 122.217974) (xy 309.214443 122.138944)
			)
		)
	)
	(zone
		(net 373)
		(net_name "Net-(J12D-~{THRM})")
		(layer "B.Cu")
		(name "$teardrop_padvia$")
		(hatch none 0.1)
		(priority 30727)
		(attr
			(teardrop
				(type padvia)
			)
		)
		(connect_pads yes
			(clearance 0)
		)
		(min_thickness 0.0254)
		(filled_areas_thickness no)
		(fill yes
			(thermal_gap 0.5)
			(thermal_bridge_width 0.5)
			(island_removal_mode 1)
			(island_area_min 10)
		)
		(polygon
			(pts
				(xy 193.0625 164.700677) (xy 193.067318 164.631236) (xy 193.08104 164.579912) (xy 193.127755 164.50437)
				(xy 193.137299 164.492229) (xy 193.187081 164.425003) (xy 193 164.299) (xy 192.812919 164.425003)
				(xy 192.862701 164.492231) (xy 192.917106 164.575397) (xy 192.93219 164.628251) (xy 192.9375 164.700677)
			)
		)
	)
	(zone
		(net 267)
		(net_name "/Com Express 7 Interfaces/PCIe_{B2Bx4}.TX0-")
		(layer "B.Cu")
		(name "$teardrop_padvia$")
		(hatch none 0.1)
		(priority 30162)
		(attr
			(teardrop
				(type padvia)
			)
		)
		(connect_pads yes
			(clearance 0)
		)
		(min_thickness 0.0254)
		(filled_areas_thickness no)
		(fill yes
			(thermal_gap 0.5)
			(thermal_bridge_width 0.5)
			(island_removal_mode 1)
			(island_area_min 10)
		)
		(polygon
			(pts
				(xy 175.39 104.9055) (xy 175.404152 104.902492) (xy 175.434502 104.900505) (xy 175.445621 104.91353)
				(xy 175.45 104.943921) (xy 176.201 104.86) (xy 175.986425 104.71) (xy 175.779648 104.729346) (xy 175.541135 104.714604)
				(xy 175.39 104.7035)
			)
		)
	)
	(zone
		(net 1)
		(net_name "GND")
		(layer "B.Cu")
		(name "$teardrop_padvia$")
		(hatch none 0.1)
		(priority 30320)
		(attr
			(teardrop
				(type padvia)
			)
		)
		(connect_pads yes
			(clearance 0)
		)
		(min_thickness 0.0254)
		(filled_areas_thickness no)
		(fill yes
			(thermal_gap 0.5)
			(thermal_bridge_width 0.5)
			(island_removal_mode 1)
			(island_area_min 10)
		)
		(polygon
			(pts
				(xy 107.331532 157.333663) (xy 107.379207 157.374818) (xy 107.424471 157.402727) (xy 107.531674 157.438994)
				(xy 107.597906 157.458155) (xy 107.662143 157.494227) (xy 107.800707 157.320707) (xy 107.754769 157.099876)
				(xy 107.690195 157.12588) (xy 107.61851 157.152339) (xy 107.581809 157.147607) (xy 107.543663 157.121532)
			)
		)
	)
	(zone
		(net 2)
		(net_name "+3V3")
		(layer "B.Cu")
		(name "$teardrop_padvia$")
		(hatch none 0.1)
		(priority 30925)
		(attr
			(teardrop
				(type padvia)
			)
		)
		(connect_pads yes
			(clearance 0)
		)
		(min_thickness 0.0254)
		(filled_areas_thickness no)
		(fill yes
			(thermal_gap 0.5)
			(thermal_bridge_width 0.5)
			(island_removal_mode 1)
			(island_area_min 10)
		)
		(polygon
			(pts
				(xy 120.3375 145.1855) (xy 120.337599 145.191963) (xy 120.33205 145.231906) (xy 120.317161 145.250428)
				(xy 120.287659 145.263752) (xy 120.401 145.674) (xy 120.512655 145.261231) (xy 120.485524 145.25041)
				(xy 120.47038 145.235092) (xy 120.462407 145.191683) (xy 120.4625 145.1855)
			)
		)
	)
	(zone
		(net 2)
		(net_name "+3V3")
		(layer "B.Cu")
		(name "$teardrop_padvia$")
		(hatch none 0.1)
		(priority 30799)
		(attr
			(teardrop
				(type padvia)
			)
		)
		(connect_pads yes
			(clearance 0)
		)
		(min_thickness 0.0254)
		(filled_areas_thickness no)
		(fill yes
			(thermal_gap 0.5)
			(thermal_bridge_width 0.5)
			(island_removal_mode 1)
			(island_area_min 10)
		)
		(polygon
			(pts
				(xy 197.181006 135.379996) (xy 197.226393 135.432189) (xy 197.252814 135.477969) (xy 197.272964 135.564028)
				(xy 197.274799 135.579792) (xy 197.287137 135.663726) (xy 197.508521 135.620538) (xy 197.551709 135.399154)
				(xy 197.470196 135.386832) (xy 197.372609 135.366128) (xy 197.324503 135.339255) (xy 197.269394 135.291608)
			)
		)
	)
	(zone
		(net 1)
		(net_name "GND")
		(layer "B.Cu")
		(name "$teardrop_padvia$")
		(hatch none 0.1)
		(priority 30373)
		(attr
			(teardrop
				(type padvia)
			)
		)
		(connect_pads yes
			(clearance 0)
		)
		(min_thickness 0.0254)
		(filled_areas_thickness no)
		(fill yes
			(thermal_gap 0.5)
			(thermal_bridge_width 0.5)
			(island_removal_mode 1)
			(island_area_min 10)
		)
		(polygon
			(pts
				(xy 125.6725 138.498) (xy 125.692469 138.435134) (xy 125.718921 138.403156) (xy 125.756332 138.374642)
				(xy 125.803527 138.352118) (xy 125.861167 138.336907) (xy 125.861798 138.336798) (xy 125.61 138.059)
				(xy 125.358202 138.336798) (xy 125.413635 138.351095) (xy 125.45952 138.372175) (xy 125.497201 138.39954)
				(xy 125.524434 138.430448) (xy 125.541472 138.463735) (xy 125.547489 138.496566) (xy 125.5475 138.498)
			)
		)
	)
	(zone
		(net 53)
		(net_name "/2xSFP+/SH")
		(layer "B.Cu")
		(name "$teardrop_padvia$")
		(hatch none 0.1)
		(priority 30213)
		(attr
			(teardrop
				(type padvia)
			)
		)
		(connect_pads yes
			(clearance 0)
		)
		(min_thickness 0.0254)
		(filled_areas_thickness no)
		(fill yes
			(thermal_gap 0.5)
			(thermal_bridge_width 0.5)
			(island_removal_mode 1)
			(island_area_min 10)
		)
		(polygon
			(pts
				(xy 108.11 156.102) (xy 108.110338 156.11887) (xy 108.109759 156.163826) (xy 108.097941 156.211169)
				(xy 108.063362 156.253573) (xy 107.9945 156.283708) (xy 108.26 156.541) (xy 108.5255 156.283708)
				(xy 108.480731 156.268151) (xy 108.449115 156.247435) (xy 108.416381 156.196299) (xy 108.409662 156.11887)
				(xy 108.41 156.102)
			)
		)
	)
	(zone
		(net 624)
		(net_name "/PCIe redriver/TX_EQ1")
		(layer "B.Cu")
		(name "$teardrop_padvia$")
		(hatch none 0.1)
		(priority 30742)
		(attr
			(teardrop
				(type padvia)
			)
		)
		(connect_pads yes
			(clearance 0)
		)
		(min_thickness 0.0254)
		(filled_areas_thickness no)
		(fill yes
			(thermal_gap 0.5)
			(thermal_bridge_width 0.5)
			(island_removal_mode 1)
			(island_area_min 10)
		)
		(polygon
			(pts
				(xy 112.250677 147.5475) (xy 112.181236 147.542682) (xy 112.129913 147.52896) (xy 112.054371 147.482246)
				(xy 112.042231 147.472701) (xy 111.975003 147.422919) (xy 111.849 147.61) (xy 111.975003 147.797081)
				(xy 112.042229 147.747299) (xy 112.125396 147.692894) (xy 112.178251 147.67781) (xy 112.250677 147.6725)
			)
		)
	)
	(zone
		(net 200)
		(net_name "/OCuLink/~{PERST_D0}")
		(layer "B.Cu")
		(name "$teardrop_padvia$")
		(hatch none 0.1)
		(priority 30337)
		(attr
			(teardrop
				(type padvia)
			)
		)
		(connect_pads yes
			(clearance 0)
		)
		(min_thickness 0.0254)
		(filled_areas_thickness no)
		(fill yes
			(thermal_gap 0.5)
			(thermal_bridge_width 0.5)
			(island_removal_mode 1)
			(island_area_min 10)
		)
		(polygon
			(pts
				(xy 121.1575 163.122) (xy 121.137531 163.184866) (xy 121.111079 163.216844) (xy 121.073668 163.245358)
				(xy 121.026473 163.267882) (xy 120.968833 163.283093) (xy 120.968202 163.283202) (xy 121.22 163.561)
				(xy 121.471798 163.283202) (xy 121.416365 163.268905) (xy 121.37048 163.247825) (xy 121.332799 163.22046)
				(xy 121.305566 163.189552) (xy 121.288528 163.156265) (xy 121.282511 163.123434) (xy 121.2825 163.122)
			)
		)
	)
	(zone
		(net 433)
		(net_name "/2xSFP+/10GKR_SFP0.RX-")
		(layer "B.Cu")
		(name "$teardrop_padvia$")
		(hatch none 0.1)
		(priority 30630)
		(attr
			(teardrop
				(type padvia)
			)
		)
		(connect_pads yes
			(clearance 0)
		)
		(min_thickness 0.0254)
		(filled_areas_thickness no)
		(fill yes
			(thermal_gap 0.5)
			(thermal_bridge_width 0.5)
			(island_removal_mode 1)
			(island_area_min 10)
		)
		(polygon
			(pts
				(xy 152.84 147.977084) (xy 152.837432 147.797777) (xy 152.835677 147.632143) (xy 152.615 147.629)
				(xy 152.489997 147.817081) (xy 152.574781 147.855729) (xy 152.615597 147.871388) (xy 152.649058 147.892373)
				(xy 152.671685 147.925376) (xy 152.68 147.977084)
			)
		)
	)
	(zone
		(net 868)
		(net_name "/Backplane/PCIe_{x2}.TX1+")
		(layer "B.Cu")
		(name "$teardrop_padvia$")
		(hatch none 0.1)
		(priority 30976)
		(attr
			(teardrop
				(type padvia)
			)
		)
		(connect_pads yes
			(clearance 0)
		)
		(min_thickness 0.0254)
		(filled_areas_thickness no)
		(fill yes
			(thermal_gap 0.5)
			(thermal_bridge_width 0.5)
			(island_removal_mode 1)
			(island_area_min 10)
		)
		(polygon
			(pts
				(xy 314.812 161.509) (xy 314.832648 161.501802) (xy 314.864984 161.492208) (xy 314.879007 161.499035)
				(xy 314.888995 161.5205) (xy 315.138 161.408) (xy 314.888995 161.2955) (xy 314.879271 161.316676)
				(xy 314.865643 161.323731) (xy 314.832648 161.314198) (xy 314.812 161.307)
			)
		)
	)
	(zone
		(net 426)
		(net_name "Net-(J12K-10G_SDP0)")
		(layer "B.Cu")
		(name "$teardrop_padvia$")
		(hatch none 0.1)
		(priority 30111)
		(attr
			(teardrop
				(type padvia)
			)
		)
		(connect_pads yes
			(clearance 0)
		)
		(min_thickness 0.0254)
		(filled_areas_thickness no)
		(fill yes
			(thermal_gap 0.5)
			(thermal_bridge_width 0.5)
			(island_removal_mode 1)
			(island_area_min 10)
		)
		(polygon
			(pts
				(xy 197.1375 158.292794) (xy 197.142315 158.210733) (xy 197.156019 158.145388) (xy 197.202576 158.05212)
				(xy 197.270787 157.973657) (xy 197.326942 157.912158) (xy 197.386801 157.833339) (xy 197.075 157.624)
				(xy 196.763199 157.833339) (xy 196.860219 157.953517) (xy 196.879214 157.973658) (xy 196.932366 158.032541)
				(xy 196.974591 158.096624) (xy 197.002449 158.179008) (xy 197.0125 158.292794)
			)
		)
	)
	(zone
		(net 141)
		(net_name "/2xSFP+/KR to SFI #1/~{RESET}")
		(layer "B.Cu")
		(name "$teardrop_padvia$")
		(hatch none 0.1)
		(priority 30128)
		(attr
			(teardrop
				(type padvia)
			)
		)
		(connect_pads yes
			(clearance 0)
		)
		(min_thickness 0.0254)
		(filled_areas_thickness no)
		(fill yes
			(thermal_gap 0.5)
			(thermal_bridge_width 0.5)
			(island_removal_mode 1)
			(island_area_min 10)
		)
		(polygon
			(pts
				(xy 140.22 131.4985) (xy 140.16274 131.478779) (xy 140.110216 131.415967) (xy 140.090449 131.367347)
				(xy 140.077923 131.308049) (xy 140.076072 131.291) (xy 139.599 131.561) (xy 140.076072 131.831)
				(xy 140.086248 131.769756) (xy 140.103925 131.718829) (xy 140.127823 131.677986) (xy 140.156022 131.648303)
				(xy 140.186012 131.63037) (xy 140.216862 131.623559) (xy 140.22 131.6235)
			)
		)
	)
	(zone
		(net 157)
		(net_name "Net-(J1A-LED_D4)")
		(layer "B.Cu")
		(name "$teardrop_padvia$")
		(hatch none 0.1)
		(priority 30450)
		(attr
			(teardrop
				(type padvia)
			)
		)
		(connect_pads yes
			(clearance 0)
		)
		(min_thickness 0.0254)
		(filled_areas_thickness no)
		(fill yes
			(thermal_gap 0.5)
			(thermal_bridge_width 0.5)
			(island_removal_mode 1)
			(island_area_min 10)
		)
		(polygon
			(pts
				(xy 122.507 107.8725) (xy 122.566412 107.892273) (xy 122.622497 107.955547) (xy 122.644199 108.004172)
				(xy 122.658873 108.063531) (xy 122.660653 108.0755) (xy 122.921 107.81) (xy 122.660653 107.5445)
				(xy 122.647804 107.604638) (xy 122.62787 107.654522) (xy 122.601945 107.694641) (xy 122.572125 107.723654)
				(xy 122.540707 107.741146) (xy 122.508896 107.747479) (xy 122.507 107.7475)
			)
		)
	)
	(zone
		(net 772)
		(net_name "/Backplane/PCIe_{x2}.RX1-")
		(layer "B.Cu")
		(name "$teardrop_padvia$")
		(hatch none 0.1)
		(priority 30572)
		(attr
			(teardrop
				(type padvia)
			)
		)
		(connect_pads yes
			(clearance 0)
		)
		(min_thickness 0.0254)
		(filled_areas_thickness no)
		(fill yes
			(thermal_gap 0.5)
			(thermal_bridge_width 0.5)
			(island_removal_mode 1)
			(island_area_min 10)
		)
		(polygon
			(pts
				(xy 219.717496 154.7435) (xy 219.555964 154.748895) (xy 219.471554 154.752445) (xy 219.36986 154.747823)
				(xy 219.349 154.9685) (xy 219.498852 155.131731) (xy 219.552992 155.063062) (xy 219.562883 155.046608)
				(xy 219.587383 155.007935) (xy 219.61689 154.975721) (xy 219.658046 154.953673) (xy 219.717496 154.9455)
			)
		)
	)
	(zone
		(net 1)
		(net_name "GND")
		(layer "B.Cu")
		(name "$teardrop_padvia$")
		(hatch none 0.1)
		(priority 30597)
		(attr
			(teardrop
				(type padvia)
			)
		)
		(connect_pads yes
			(clearance 0)
		)
		(min_thickness 0.0254)
		(filled_areas_thickness no)
		(fill yes
			(thermal_gap 0.5)
			(thermal_bridge_width 0.5)
			(island_removal_mode 1)
			(island_area_min 10)
		)
		(polygon
			(pts
				(xy 308.835959 105.235652) (xy 308.805623 105.277514) (xy 308.761846 105.319606) (xy 308.711456 105.353143)
				(xy 308.65269 105.376974) (xy 308.596772 105.386084) (xy 308.824292 105.670707) (xy 309.101797 105.418202)
				(xy 308.998427 105.396766) (xy 308.936791 105.37027) (xy 308.921297 105.352586) (xy 308.920438 105.332732)
				(xy 308.924348 105.324041)
			)
		)
	)
	(zone
		(net 2)
		(net_name "+3V3")
		(layer "B.Cu")
		(name "$teardrop_padvia$")
		(hatch none 0.1)
		(priority 30466)
		(attr
			(teardrop
				(type padvia)
			)
		)
		(connect_pads yes
			(clearance 0)
		)
		(min_thickness 0.0254)
		(filled_areas_thickness no)
		(fill yes
			(thermal_gap 0.5)
			(thermal_bridge_width 0.5)
			(island_removal_mode 1)
			(island_area_min 10)
		)
		(polygon
			(pts
				(xy 180.430969 88.962389) (xy 180.480776 89.018861) (xy 180.511857 89.068312) (xy 180.545003 89.164915)
				(xy 180.573142 89.257258) (xy 180.780707 89.180707) (xy 180.864812 88.976271) (xy 180.776731 88.944609)
				(xy 180.680724 88.906311) (xy 180.630516 88.872995) (xy 180.57239 88.820968)
			)
		)
	)
	(zone
		(net 154)
		(net_name "Net-(J1A-LED_D1)")
		(layer "B.Cu")
		(name "$teardrop_padvia$")
		(hatch none 0.1)
		(priority 30344)
		(attr
			(teardrop
				(type padvia)
			)
		)
		(connect_pads yes
			(clearance 0)
		)
		(min_thickness 0.0254)
		(filled_areas_thickness no)
		(fill yes
			(thermal_gap 0.5)
			(thermal_bridge_width 0.5)
			(island_removal_mode 1)
			(island_area_min 10)
		)
		(polygon
			(pts
				(xy 122.9825 97.298) (xy 123.002469 97.235134) (xy 123.028921 97.203156) (xy 123.066332 97.174642)
				(xy 123.113527 97.152118) (xy 123.171167 97.136907) (xy 123.171798 97.136798) (xy 122.92 96.859)
				(xy 122.668202 97.136798) (xy 122.723635 97.151095) (xy 122.76952 97.172175) (xy 122.807201 97.19954)
				(xy 122.834434 97.230448) (xy 122.851472 97.263735) (xy 122.857489 97.296566) (xy 122.8575 97.298)
			)
		)
	)
	(zone
		(net 271)
		(net_name "/M.2 key M #2/PCIE_{REF}.CK-")
		(layer "B.Cu")
		(name "$teardrop_padvia$")
		(hatch none 0.1)
		(priority 30553)
		(attr
			(teardrop
				(type padvia)
			)
		)
		(connect_pads yes
			(clearance 0)
		)
		(min_thickness 0.0254)
		(filled_areas_thickness no)
		(fill yes
			(thermal_gap 0.5)
			(thermal_bridge_width 0.5)
			(island_removal_mode 1)
			(island_area_min 10)
		)
		(polygon
			(pts
				(xy 260.9935 136.632504) (xy 260.998895 136.794035) (xy 261.002445 136.878446) (xy 260.997823 136.98014)
				(xy 261.2185 137.001) (xy 261.381731 136.851147) (xy 261.313062 136.797007) (xy 261.296608 136.787116)
				(xy 261.257935 136.762616) (xy 261.225721 136.733109) (xy 261.203673 136.691953) (xy 261.1955 136.632504)
			)
		)
	)
	(zone
		(net 350)
		(net_name "Net-(J12D-LPC_AD1{slash}ESPI_IO_1)")
		(layer "B.Cu")
		(name "$teardrop_padvia$")
		(hatch none 0.1)
		(priority 30714)
		(attr
			(teardrop
				(type padvia)
			)
		)
		(connect_pads yes
			(clearance 0)
		)
		(min_thickness 0.0254)
		(filled_areas_thickness no)
		(fill yes
			(thermal_gap 0.5)
			(thermal_bridge_width 0.5)
			(island_removal_mode 1)
			(island_area_min 10)
		)
		(polygon
			(pts
				(xy 177.599323 164.5625) (xy 177.668764 164.567318) (xy 177.720088 164.58104) (xy 177.795629 164.627755)
				(xy 177.807769 164.637299) (xy 177.874997 164.687081) (xy 178.001 164.5) (xy 177.874997 164.312919)
				(xy 177.807768 164.362702) (xy 177.724602 164.417106) (xy 177.671748 164.43219) (xy 177.599323 164.4375)
			)
		)
	)
	(zone
		(net 96)
		(net_name "/OCuLink/PCIe_{x4}.TX1-")
		(layer "B.Cu")
		(name "$teardrop_padvia$")
		(hatch none 0.1)
		(priority 30188)
		(attr
			(teardrop
				(type padvia)
			)
		)
		(connect_pads yes
			(clearance 0)
		)
		(min_thickness 0.0254)
		(filled_areas_thickness no)
		(fill yes
			(thermal_gap 0.5)
			(thermal_bridge_width 0.5)
			(island_removal_mode 1)
			(island_area_min 10)
		)
		(polygon
			(pts
				(xy 107.045071 164.7685) (xy 107.118327 164.74513) (xy 107.270463 164.700967) (xy 107.353293 164.690654)
				(xy 107.436769 164.697) (xy 107.414 164.377) (xy 107.118 164.272146) (xy 107.123839 164.397179)
				(xy 107.113687 164.486812) (xy 107.098361 164.525374) (xy 107.075399 164.551842) (xy 107.045071 164.5665)
			)
		)
	)
	(zone
		(net 623)
		(net_name "/PCIe redriver/TX_EQ0")
		(layer "B.Cu")
		(name "$teardrop_padvia$")
		(hatch none 0.1)
		(priority 30749)
		(attr
			(teardrop
				(type padvia)
			)
		)
		(connect_pads yes
			(clearance 0)
		)
		(min_thickness 0.0254)
		(filled_areas_thickness no)
		(fill yes
			(thermal_gap 0.5)
			(thermal_bridge_width 0.5)
			(island_removal_mode 1)
			(island_area_min 10)
		)
		(polygon
			(pts
				(xy 112.089127 148.082485) (xy 112.036618 148.128181) (xy 111.990623 148.154768) (xy 111.904174 148.175152)
				(xy 111.888841 148.176988) (xy 111.806105 148.189323) (xy 111.849293 148.410707) (xy 112.070677 148.453895)
				(xy 112.083011 148.37116) (xy 112.103349 148.273881) (xy 112.130057 148.225841) (xy 112.177515 148.170873)
			)
		)
	)
	(zone
		(net 78)
		(net_name "+1V8")
		(layer "B.Cu")
		(name "$teardrop_padvia$")
		(hatch none 0.1)
		(priority 30388)
		(attr
			(teardrop
				(type padvia)
			)
		)
		(connect_pads yes
			(clearance 0)
		)
		(min_thickness 0.0254)
		(filled_areas_thickness no)
		(fill yes
			(thermal_gap 0.5)
			(thermal_bridge_width 0.5)
			(island_removal_mode 1)
			(island_area_min 10)
		)
		(polygon
			(pts
				(xy 140.1575 139.922) (xy 140.137531 139.984866) (xy 140.111079 140.016844) (xy 140.073668 140.045358)
				(xy 140.026473 140.067882) (xy 139.968833 140.083093) (xy 139.968202 140.083202) (xy 140.22 140.361)
				(xy 140.471798 140.083202) (xy 140.416365 140.068905) (xy 140.37048 140.047825) (xy 140.332799 140.02046)
				(xy 140.305566 139.989552) (xy 140.288528 139.956265) (xy 140.282511 139.923434) (xy 140.2825 139.922)
			)
		)
	)
	(zone
		(net 1)
		(net_name "GND")
		(layer "B.Cu")
		(name "$teardrop_padvia$")
		(hatch none 0.1)
		(priority 30263)
		(attr
			(teardrop
				(type padvia)
			)
		)
		(connect_pads yes
			(clearance 0)
		)
		(min_thickness 0.0254)
		(filled_areas_thickness no)
		(fill yes
			(thermal_gap 0.5)
			(thermal_bridge_width 0.5)
			(island_removal_mode 1)
			(island_area_min 10)
		)
		(polygon
			(pts
				(xy 99.860677 164.95) (xy 99.703106 164.943069) (xy 99.589578 164.914549) (xy 99.547778 164.8975)
				(xy 99.459 165.1) (xy 99.547778 165.3025) (xy 99.643817 165.268118) (xy 99.745689 165.2529) (xy 99.860677 165.25)
			)
		)
	)
	(zone
		(net 168)
		(net_name "Net-(J2A-RX_{LOS})")
		(layer "B.Cu")
		(name "$teardrop_padvia$")
		(hatch none 0.1)
		(priority 30124)
		(attr
			(teardrop
				(type padvia)
			)
		)
		(connect_pads yes
			(clearance 0)
		)
		(min_thickness 0.0254)
		(filled_areas_thickness no)
		(fill yes
			(thermal_gap 0.5)
			(thermal_bridge_width 0.5)
			(island_removal_mode 1)
			(island_area_min 10)
		)
		(polygon
			(pts
				(xy 145.1125 167.71) (xy 145.117324 167.660303) (xy 145.13109 167.623922) (xy 145.174687 167.585558)
				(xy 145.248602 167.570595) (xy 145.31698 167.569628) (xy 145.438254 167.564354) (xy 145.498473 167.550462)
				(xy 145.555328 167.523047) (xy 145.35 167.209) (xy 144.982206 167.283159) (xy 144.997358 167.383396)
				(xy 144.999681 167.461002) (xy 144.995149 167.534062) (xy 144.9875 167.71)
			)
		)
	)
	(zone
		(net 484)
		(net_name "Net-(J12K-10G_PHY_CAP_01)")
		(layer "B.Cu")
		(name "$teardrop_padvia$")
		(hatch none 0.1)
		(priority 30115)
		(attr
			(teardrop
				(type padvia)
			)
		)
		(connect_pads yes
			(clearance 0)
		)
		(min_thickness 0.0254)
		(filled_areas_thickness no)
		(fill yes
			(thermal_gap 0.5)
			(thermal_bridge_width 0.5)
			(island_removal_mode 1)
			(island_area_min 10)
		)
		(polygon
			(pts
				(xy 193.116142 150.004531) (xy 193.166601 150.061782) (xy 193.200254 150.114692) (xy 193.229452 150.209778)
				(xy 193.229999 150.32433) (xy 193.227614 150.418965) (xy 193.239744 150.530697) (xy 193.608245 150.458245)
				(xy 193.680697 150.089744) (xy 193.532704 150.068777) (xy 193.449808 150.05821) (xy 193.37351 150.037265)
				(xy 193.294767 149.993917) (xy 193.204531 149.916142)
			)
		)
	)
	(zone
		(net 210)
		(net_name "/Com Express 7 Interfaces/PCIe_{B1x4}.RX3+")
		(layer "B.Cu")
		(name "$teardrop_padvia$")
		(hatch none 0.1)
		(priority 30176)
		(attr
			(teardrop
				(type padvia)
			)
		)
		(connect_pads yes
			(clearance 0)
		)
		(min_thickness 0.0254)
		(filled_areas_thickness no)
		(fill yes
			(thermal_gap 0.5)
			(thermal_bridge_width 0.5)
			(island_removal_mode 1)
			(island_area_min 10)
		)
		(polygon
			(pts
				(xy 196.890661 142.556702) (xy 196.871293 142.549183) (xy 196.704205 142.473772) (xy 196.619952 142.415535)
				(xy 196.550245 142.338614) (xy 196.346744 142.587661) (xy 196.486879 142.866132) (xy 196.57582 142.768068)
				(xy 196.650083 142.710142) (xy 196.687888 142.695165) (xy 196.723756 142.693254) (xy 196.747826 142.699537)
			)
		)
	)
	(zone
		(net 204)
		(net_name "/Backplane/USB.D-")
		(layer "B.Cu")
		(name "$teardrop_padvia$")
		(hatch none 0.1)
		(priority 30595)
		(attr
			(teardrop
				(type padvia)
			)
		)
		(connect_pads yes
			(clearance 0)
		)
		(min_thickness 0.0254)
		(filled_areas_thickness no)
		(fill yes
			(thermal_gap 0.5)
			(thermal_bridge_width 0.5)
			(island_removal_mode 1)
			(island_area_min 10)
		)
		(polygon
			(pts
				(xy 226.085321 145.473207) (xy 225.966083 145.359886) (xy 225.836795 145.230795) (xy 225.671251 145.377335)
				(xy 225.667509 145.598719) (xy 225.749818 145.585534) (xy 225.777902 145.576363) (xy 225.821487 145.563007)
				(xy 225.864102 145.558163) (xy 225.907768 145.569334) (xy 225.954506 145.604022)
			)
		)
	)
	(zone
		(net 157)
		(net_name "Net-(J1A-LED_D4)")
		(layer "B.Cu")
		(name "$teardrop_padvia$")
		(hatch none 0.1)
		(priority 30035)
		(attr
			(teardrop
				(type padvia)
			)
		)
		(connect_pads yes
			(clearance 0)
		)
		(min_thickness 0.0254)
		(filled_areas_thickness no)
		(fill yes
			(thermal_gap 0.5)
			(thermal_bridge_width 0.5)
			(island_removal_mode 1)
			(island_area_min 10)
		)
		(polygon
			(pts
				(xy 119.965843 111.759231) (xy 120.037988 111.838243) (xy 120.092074 111.912113) (xy 120.129082 111.978855)
				(xy 120.154132 112.043187) (xy 120.177464 112.176106) (xy 120.176812 112.330923) (xy 120.175135 112.498082)
				(xy 120.19797 112.696686) (xy 120.860707 112.565707) (xy 120.991686 111.90297) (xy 120.793295 111.880142)
				(xy 120.625923 111.881812) (xy 120.485166 111.883207) (xy 120.350203 111.86271) (xy 120.281501 111.837597)
				(xy 120.210177 111.799022) (xy 120.134872 111.744325) (xy 120.054231 111.670843)
			)
		)
	)
	(zone
		(net 52)
		(net_name "+5V")
		(layer "B.Cu")
		(hatch edge 0.5)
		(priority 1)
		(connect_pads
			(clearance 0.15)
		)
		(min_thickness 0.25)
		(filled_areas_thickness no)
		(fill yes
			(thermal_gap 0.2)
			(thermal_bridge_width 0.5)
			(smoothing fillet)
			(radius 0.2)
		)
		(polygon
			(pts
				(xy 119.3 87.71) (xy 119.3 93.31) (xy 117.05 93.31) (xy 117.05 87.71) (xy 117.05 84.81) (xy 119.3 84.81)
			)
		)
	)
	(zone
		(net 771)
		(net_name "/Backplane/PCIe_{x2}.RX1+")
		(layer "B.Cu")
		(name "$teardrop_padvia$")
		(hatch none 0.1)
		(priority 30516)
		(attr
			(teardrop
				(type padvia)
			)
		)
		(connect_pads yes
			(clearance 0)
		)
		(min_thickness 0.0254)
		(filled_areas_thickness no)
		(fill yes
			(thermal_gap 0.5)
			(thermal_bridge_width 0.5)
			(island_removal_mode 1)
			(island_area_min 10)
		)
		(polygon
			(pts
				(xy 219.717496 154.3545) (xy 219.67071 154.349765) (xy 219.635258 154.336621) (xy 219.58706 154.291613)
				(xy 219.562884 154.253392) (xy 219.535514 154.210225) (xy 219.498852 154.168268) (xy 219.349 154.3315)
				(xy 219.36986 154.552177) (xy 219.470531 154.547548) (xy 219.553897 154.55098) (xy 219.555964 154.551105)
				(xy 219.717496 154.5565)
			)
		)
	)
	(zone
		(net 290)
		(net_name "/2xUSB3.0+RJ45/GbE.MDI2+")
		(layer "B.Cu")
		(name "$teardrop_padvia$")
		(hatch none 0.1)
		(priority 30648)
		(attr
			(teardrop
				(type padvia)
			)
		)
		(connect_pads yes
			(clearance 0)
		)
		(min_thickness 0.0254)
		(filled_areas_thickness no)
		(fill yes
			(thermal_gap 0.5)
			(thermal_bridge_width 0.5)
			(island_removal_mode 1)
			(island_area_min 10)
		)
		(polygon
			(pts
				(xy 179.025 167.742084) (xy 179.029756 167.702162) (xy 179.04305 167.673745) (xy 179.087129 167.641329)
				(xy 179.132262 167.62605) (xy 179.178541 167.610756) (xy 179.225003 167.587081) (xy 179.1 167.399)
				(xy 178.879323 167.398242) (xy 178.877203 167.536699) (xy 178.875 167.742084)
			)
		)
	)
	(zone
		(net 231)
		(net_name "/M.2 key M #1/PCIE_{REF}.CK+")
		(layer "B.Cu")
		(name "$teardrop_padvia$")
		(hatch none 0.1)
		(priority 30533)
		(attr
			(teardrop
				(type padvia)
			)
		)
		(connect_pads yes
			(clearance 0)
		)
		(min_thickness 0.0254)
		(filled_areas_thickness no)
		(fill yes
			(thermal_gap 0.5)
			(thermal_bridge_width 0.5)
			(island_removal_mode 1)
			(island_area_min 10)
		)
		(polygon
			(pts
				(xy 207.032504 128.2265) (xy 207.194035 128.221105) (xy 207.278445 128.217554) (xy 207.38014 128.222177)
				(xy 207.401 128.0015) (xy 207.251147 127.838268) (xy 207.197007 127.906935) (xy 207.187115 127.923393)
				(xy 207.162615 127.962065) (xy 207.133109 127.994279) (xy 207.091953 128.016327) (xy 207.032504 128.0245)
			)
		)
	)
	(zone
		(net 286)
		(net_name "/2xUSB3.0+RJ45/GbE.MDI3+")
		(layer "B.Cu")
		(name "$teardrop_padvia$")
		(hatch none 0.1)
		(priority 30661)
		(attr
			(teardrop
				(type padvia)
			)
		)
		(connect_pads yes
			(clearance 0)
		)
		(min_thickness 0.0254)
		(filled_areas_thickness no)
		(fill yes
			(thermal_gap 0.5)
			(thermal_bridge_width 0.5)
			(island_removal_mode 1)
			(island_area_min 10)
		)
		(polygon
			(pts
				(xy 172.3 161.542084) (xy 172.297797 161.336718) (xy 172.295677 161.198242) (xy 172.075 161.199)
				(xy 171.949997 161.387081) (xy 172.026138 161.420995) (xy 172.042738 161.42605) (xy 172.084281 161.439844)
				(xy 172.118398 161.459262) (xy 172.141501 161.491083) (xy 172.15 161.542084)
			)
		)
	)
	(zone
		(net 257)
		(net_name "/Com Express 7 Interfaces/PCIe_{B2Bx4}.TX1-")
		(layer "B.Cu")
		(name "$teardrop_padvia$")
		(hatch none 0.1)
		(priority 30296)
		(attr
			(teardrop
				(type padvia)
			)
		)
		(connect_pads yes
			(clearance 0)
		)
		(min_thickness 0.0254)
		(filled_areas_thickness no)
		(fill yes
			(thermal_gap 0.5)
			(thermal_bridge_width 0.5)
			(island_removal_mode 1)
			(island_area_min 10)
		)
		(polygon
			(pts
				(xy 175.39 101.961) (xy 175.404678 101.957463) (xy 175.434685 101.954192) (xy 175.445673 101.966143)
				(xy 175.45 101.995) (xy 176.201 101.86) (xy 175.45 101.725) (xy 175.445525 101.754204) (xy 175.434203 101.765997)
				(xy 175.404678 101.762537) (xy 175.39 101.759)
			)
		)
	)
	(zone
		(net 866)
		(net_name "/Backplane/PCIe_{x2}.TX0+")
		(layer "B.Cu")
		(name "$teardrop_padvia$")
		(hatch none 0.1)
		(priority 30511)
		(attr
			(teardrop
				(type padvia)
			)
		)
		(connect_pads yes
			(clearance 0)
		)
		(min_thickness 0.0254)
		(filled_areas_thickness no)
		(fill yes
			(thermal_gap 0.5)
			(thermal_bridge_width 0.5)
			(island_removal_mode 1)
			(island_area_min 10)
		)
		(polygon
			(pts
				(xy 269.367496 138.8045) (xy 269.32071 138.799765) (xy 269.285258 138.786621) (xy 269.23706 138.741613)
				(xy 269.212884 138.703392) (xy 269.185514 138.660225) (xy 269.148852 138.618268) (xy 268.999 138.7815)
				(xy 269.01986 139.002177) (xy 269.120531 138.997548) (xy 269.203897 139.00098) (xy 269.205964 139.001105)
				(xy 269.367496 139.0065)
			)
		)
	)
	(zone
		(net 697)
		(net_name "Net-(U5-IO0_6)")
		(layer "B.Cu")
		(name "$teardrop_padvia$")
		(hatch none 0.1)
		(priority 30083)
		(attr
			(teardrop
				(type padvia)
			)
		)
		(connect_pads yes
			(clearance 0)
		)
		(min_thickness 0.0254)
		(filled_areas_thickness no)
		(fill yes
			(thermal_gap 0.5)
			(thermal_bridge_width 0.5)
			(island_removal_mode 1)
			(island_area_min 10)
		)
		(polygon
			(pts
				(xy 157.9125 163.095966) (xy 157.917184 162.996254) (xy 157.929975 162.917049) (xy 157.974464 162.789573)
				(xy 157.987893 162.760215) (xy 158.028753 162.665) (xy 158.0655 162.538696) (xy 157.7 162.459) (xy 157.40699 162.68713)
				(xy 157.490323 162.767225) (xy 157.601392 162.831613) (xy 157.672887 162.87062) (xy 157.732148 162.919317)
				(xy 157.772559 162.990251) (xy 157.7875 163.095966)
			)
		)
	)
	(zone
		(net 201)
		(net_name "/OCuLink/~{CPRSNT_D0}")
		(layer "B.Cu")
		(name "$teardrop_padvia$")
		(hatch none 0.1)
		(priority 30829)
		(attr
			(teardrop
				(type padvia)
			)
		)
		(connect_pads yes
			(clearance 0)
		)
		(min_thickness 0.0254)
		(filled_areas_thickness no)
		(fill yes
			(thermal_gap 0.5)
			(thermal_bridge_width 0.5)
			(island_removal_mode 1)
			(island_area_min 10)
		)
		(polygon
			(pts
				(xy 104.004193 161.567805) (xy 103.911902 161.482169) (xy 103.839813 161.428385) (xy 103.821159 161.415627)
				(xy 103.746867 161.363772) (xy 103.615315 161.544304) (xy 103.741025 161.732092) (xy 103.795605 161.683404)
				(xy 103.852715 161.636902) (xy 103.882579 161.634785) (xy 103.915805 161.656193)
			)
		)
	)
	(zone
		(net 201)
		(net_name "/OCuLink/~{CPRSNT_D0}")
		(layer "B.Cu")
		(name "$teardrop_padvia$")
		(hatch none 0.1)
		(priority 31033)
		(attr
			(teardrop
				(type padvia)
			)
		)
		(connect_pads yes
			(clearance 0)
		)
		(min_thickness 0.0254)
		(filled_areas_thickness no)
		(fill yes
			(thermal_gap 0.5)
			(thermal_bridge_width 0.5)
			(island_removal_mode 1)
			(island_area_min 10)
		)
		(polygon
			(pts
				(xy 104.827002 161.6745) (xy 104.833324 161.674404) (xy 104.872827 161.679989) (xy 104.891049 161.694922)
				(xy 104.903997 161.7245) (xy 105.153002 161.612) (xy 104.903997 161.4995) (xy 104.892881 161.526493)
				(xy 104.877354 161.541595) (xy 104.833324 161.549596) (xy 104.827002 161.5495)
			)
		)
	)
	(zone
		(net 652)
		(net_name "/2xSFP+/KR to SFI #1/PRBSEN")
		(layer "B.Cu")
		(name "$teardrop_padvia$")
		(hatch none 0.1)
		(priority 30777)
		(attr
			(teardrop
				(type padvia)
			)
		)
		(connect_pads yes
			(clearance 0)
		)
		(min_thickness 0.0254)
		(filled_areas_thickness no)
		(fill yes
			(thermal_gap 0.5)
			(thermal_bridge_width 0.5)
			(island_removal_mode 1)
			(island_area_min 10)
		)
		(polygon
			(pts
				(xy 155.777515 140.099127) (xy 155.731819 140.046618) (xy 155.705231 140.000623) (xy 155.684847 139.914175)
				(xy 155.683011 139.89884) (xy 155.670677 139.816105) (xy 155.449293 139.859293) (xy 155.406105 140.080677)
				(xy 155.48884 140.093011) (xy 155.586119 140.113349) (xy 155.634159 140.140057) (xy 155.689127 140.187515)
			)
		)
	)
	(zone
		(net 221)
		(net_name "/Com Express 7 Interfaces/PCIe_{B1x4}.RX0-")
		(layer "B.Cu")
		(name "$teardrop_padvia$")
		(hatch none 0.1)
		(priority 30545)
		(attr
			(teardrop
				(type padvia)
			)
		)
		(connect_pads yes
			(clearance 0)
		)
		(min_thickness 0.0254)
		(filled_areas_thickness no)
		(fill yes
			(thermal_gap 0.5)
			(thermal_bridge_width 0.5)
			(island_removal_mode 1)
			(island_area_min 10)
		)
		(polygon
			(pts
				(xy 209.8685 158.882504) (xy 209.873895 159.044035) (xy 209.877445 159.128446) (xy 209.872823 159.23014)
				(xy 210.0935 159.251) (xy 210.256731 159.101147) (xy 210.188062 159.047007) (xy 210.171608 159.037116)
				(xy 210.132935 159.012616) (xy 210.100721 158.983109) (xy 210.078673 158.941953) (xy 210.0705 158.882504)
			)
		)
	)
	(zone
		(net 432)
		(net_name "/2xSFP+/10GKR_SFP0.RX+")
		(layer "B.Cu")
		(name "$teardrop_padvia$")
		(hatch none 0.1)
		(priority 30610)
		(attr
			(teardrop
				(type padvia)
			)
		)
		(connect_pads yes
			(clearance 0)
		)
		(min_thickness 0.0254)
		(filled_areas_thickness no)
		(fill yes
			(thermal_gap 0.5)
			(thermal_bridge_width 0.5)
			(island_removal_mode 1)
			(island_area_min 10)
		)
		(polygon
			(pts
				(xy 197.239958 158.99) (xy 197.415786 158.986973) (xy 197.594885 158.985677) (xy 197.601 158.765)
				(xy 197.412919 158.639997) (xy 197.372983 158.721498) (xy 197.35467 158.763754) (xy 197.331067 158.79824)
				(xy 197.295166 158.821481) (xy 197.239958 158.83)
			)
		)
	)
	(zone
		(net 1)
		(net_name "GND")
		(layer "B.Cu")
		(name "$teardrop_padvia$")
		(hatch none 0.1)
		(priority 30856)
		(attr
			(teardrop
				(type padvia)
			)
		)
		(connect_pads yes
			(clearance 0)
		)
		(min_thickness 0.0254)
		(filled_areas_thickness no)
		(fill yes
			(thermal_gap 0.5)
			(thermal_bridge_width 0.5)
			(island_removal_mode 1)
			(island_area_min 10)
		)
		(polygon
			(pts
				(xy 123.368 104.2) (xy 123.357885 104.200153) (xy 123.327169 104.19954) (xy 123.29468 104.191218)
				(xy 123.265526 104.167325) (xy 123.244809 104.12) (xy 123.012 104.3) (xy 123.244809 104.48) (xy 123.258168 104.444099)
				(xy 123.276399 104.420801) (xy 123.321725 104.401101) (xy 123.357885 104.399847) (xy 123.368 104.4)
			)
		)
	)
	(zone
		(net 966)
		(net_name "/PCIe redriver/PCIe_{O}_C.TX0-")
		(layer "B.Cu")
		(name "$teardrop_padvia$")
		(hatch none 0.1)
		(priority 30853)
		(attr
			(teardrop
				(type padvia)
			)
		)
		(connect_pads yes
			(clearance 0)
		)
		(min_thickness 0.0254)
		(filled_areas_thickness no)
		(fill yes
			(thermal_gap 0.5)
			(thermal_bridge_width 0.5)
			(island_removal_mode 1)
			(island_area_min 10)
		)
		(polygon
			(pts
				(xy 119.5565 149.5355) (xy 119.539344 149.424184) (xy 119.517876 149.300769) (xy 119.516111 149.230124)
				(xy 119.526 149.152787) (xy 119.401 149.047) (xy 119.336683 149.485138) (xy 119.362233 149.489636)
				(xy 119.368646 149.500596) (xy 119.360476 149.521294) (xy 119.3545 149.5355)
			)
		)
	)
	(zone
		(net 123)
		(net_name "/2xUSB3.0+RJ45/P1_D-")
		(layer "B.Cu")
		(name "$teardrop_padvia$")
		(hatch none 0.1)
		(priority 30132)
		(attr
			(teardrop
				(type padvia)
			)
		)
		(connect_pads yes
			(clearance 0)
		)
		(min_thickness 0.0254)
		(filled_areas_thickness no)
		(fill yes
			(thermal_gap 0.5)
			(thermal_bridge_width 0.5)
			(island_removal_mode 1)
			(island_area_min 10)
		)
		(polygon
			(pts
				(xy 105.85126 105.034445) (xy 105.806974 104.982539) (xy 105.766392 104.9169) (xy 105.736118 104.846919)
				(xy 105.713918 104.766209) (xy 105.701 104.633162) (xy 105.400293 104.714293) (xy 105.319162 105.015)
				(xy 105.475302 105.033039) (xy 105.608908 105.083558) (xy 105.714748 105.159673) (xy 105.720445 105.16526)
			)
		)
	)
	(zone
		(net 141)
		(net_name "/2xSFP+/KR to SFI #1/~{RESET}")
		(layer "B.Cu")
		(name "$teardrop_padvia$")
		(hatch none 0.1)
		(priority 30487)
		(attr
			(teardrop
				(type padvia)
			)
		)
		(connect_pads yes
			(clearance 0)
		)
		(min_thickness 0.0254)
		(filled_areas_thickness no)
		(fill yes
			(thermal_gap 0.5)
			(thermal_bridge_width 0.5)
			(island_removal_mode 1)
			(island_area_min 10)
		)
		(polygon
			(pts
				(xy 144.726819 135.594794) (xy 144.670821 135.677993) (xy 144.625418 135.718067) (xy 144.57029 135.75085)
				(xy 144.490781 135.774796) (xy 144.729293 136.060707) (xy 144.981798 135.783202) (xy 144.894811 135.763174)
				(xy 144.838188 135.738026) (xy 144.817724 135.718141) (xy 144.81206 135.695936) (xy 144.815206 135.683181)
			)
		)
	)
	(zone
		(net 295)
		(net_name "/2xUSB3.0+RJ45/GbE.MDI0+")
		(layer "B.Cu")
		(name "$teardrop_padvia$")
		(hatch none 0.1)
		(priority 30645)
		(attr
			(teardrop
				(type padvia)
			)
		)
		(connect_pads yes
			(clearance 0)
		)
		(min_thickness 0.0254)
		(filled_areas_thickness no)
		(fill yes
			(thermal_gap 0.5)
			(thermal_bridge_width 0.5)
			(island_removal_mode 1)
			(island_area_min 10)
		)
		(polygon
			(pts
				(xy 182.025 167.742084) (xy 182.029756 167.702162) (xy 182.04305 167.673745) (xy 182.087129 167.641329)
				(xy 182.132262 167.62605) (xy 182.178541 167.610756) (xy 182.225003 167.587081) (xy 182.1 167.399)
				(xy 181.879323 167.398242) (xy 181.877203 167.536699) (xy 181.875 167.742084)
			)
		)
	)
	(zone
		(net 162)
		(net_name "Net-(J2A-TX_{FAULT})")
		(layer "B.Cu")
		(name "$teardrop_padvia$")
		(hatch none 0.1)
		(priority 30427)
		(attr
			(teardrop
				(type padvia)
			)
		)
		(connect_pads yes
			(clearance 0)
		)
		(min_thickness 0.0254)
		(filled_areas_thickness no)
		(fill yes
			(thermal_gap 0.5)
			(thermal_bridge_width 0.5)
			(island_removal_mode 1)
			(island_area_min 10)
		)
		(polygon
			(pts
				(xy 142.9875 168.267) (xy 142.967727 168.326412) (xy 142.904453 168.382496) (xy 142.855828 168.404198)
				(xy 142.796469 168.418872) (xy 142.7845 168.420652) (xy 143.05 168.681) (xy 143.3155 168.420652)
				(xy 143.255362 168.407803) (xy 143.205478 168.387869) (xy 143.165358 168.361944) (xy 143.136345 168.332124)
				(xy 143.118854 168.300706) (xy 143.112521 168.268895) (xy 143.1125 168.267)
			)
		)
	)
	(zone
		(net 1)
		(net_name "GND")
		(layer "B.Cu")
		(name "$teardrop_padvia$")
		(hatch none 0.1)
		(priority 30878)
		(attr
			(teardrop
				(type padvia)
			)
		)
		(connect_pads yes
			(clearance 0)
		)
		(min_thickness 0.0254)
		(filled_areas_thickness no)
		(fill yes
			(thermal_gap 0.5)
			(thermal_bridge_width 0.5)
			(island_removal_mode 1)
			(island_area_min 10)
		)
		(polygon
			(pts
				(xy 104.028 165.6725) (xy 104.061863 165.678281) (xy 104.096484 165.698745) (xy 104.118306 165.72581)
				(xy 104.134 165.76515) (xy 104.137289 165.780711) (xy 104.384 165.61) (xy 104.137289 165.439289)
				(xy 104.1257 165.47951) (xy 104.108116 165.508984) (xy 104.060534 165.542173) (xy 104.028 165.5475)
			)
		)
	)
	(zone
		(net 355)
		(net_name "Net-(J12D-LPC_CLK{slash}ESPI_CK)")
		(layer "B.Cu")
		(name "$teardrop_padvia$")
		(hatch none 0.1)
		(priority 30099)
		(attr
			(teardrop
				(type padvia)
			)
		)
		(connect_pads yes
			(clearance 0)
		)
		(min_thickness 0.0254)
		(filled_areas_thickness no)
		(fill yes
			(thermal_gap 0.5)
			(thermal_bridge_width 0.5)
			(island_removal_mode 1)
			(island_area_min 10)
		)
		(polygon
			(pts
				(xy 181.682206 165.8125) (xy 181.764266 165.817315) (xy 181.829612 165.831019) (xy 181.922879 165.877576)
				(xy 182.001341 165.945786) (xy 182.062841 166.001942) (xy 182.141661 166.061801) (xy 182.351 165.75)
				(xy 182.141661 165.438199) (xy 182.021483 165.535219) (xy 182.001341 165.554214) (xy 181.942458 165.607366)
				(xy 181.878375 165.649592) (xy 181.795991 165.67745) (xy 181.682206 165.6875)
			)
		)
	)
	(zone
		(net 1)
		(net_name "GND")
		(layer "B.Cu")
		(name "$teardrop_padvia$")
		(hatch none 0.1)
		(priority 30288)
		(attr
			(teardrop
				(type padvia)
			)
		)
		(connect_pads yes
			(clearance 0)
		)
		(min_thickness 0.0254)
		(filled_areas_thickness no)
		(fill yes
			(thermal_gap 0.5)
			(thermal_bridge_width 0.5)
			(island_removal_mode 1)
			(island_area_min 10)
		)
		(polygon
			(pts
				(xy 99.5 84.022) (xy 99.492146 84.08028) (xy 99.457165 84.140227) (xy 99.426236 84.163238) (xy 99.383583 84.179809)
				(xy 99.368202 84.183202) (xy 99.62 84.461) (xy 99.871798 84.183202) (xy 99.817175 84.169765) (xy 99.774756 84.149986)
				(xy 99.720781 84.097058) (xy 99.700339 84.031941) (xy 99.7 84.022)
			)
		)
	)
	(zone
		(net 626)
		(net_name "/PCIe redriver/TX_FG0")
		(layer "B.Cu")
		(name "$teardrop_padvia$")
		(hatch none 0.1)
		(priority 30810)
		(attr
			(teardrop
				(type padvia)
			)
		)
		(connect_pads yes
			(clearance 0)
		)
		(min_thickness 0.0254)
		(filled_areas_thickness no)
		(fill yes
			(thermal_gap 0.5)
			(thermal_bridge_width 0.5)
			(island_removal_mode 1)
			(island_area_min 10)
		)
		(polygon
			(pts
				(xy 113.8385 150.389323) (xy 113.833692 150.457893) (xy 113.820035 150.508684) (xy 113.773533 150.583353)
				(xy 113.763378 150.596098) (xy 113.711919 150.664997) (xy 113.899 150.791) (xy 114.086081 150.664997)
				(xy 114.038023 150.599548) (xy 113.983689 150.515411) (xy 113.968742 150.462224) (xy 113.9635 150.389323)
			)
		)
	)
	(zone
		(net 719)
		(net_name "Net-(U40-~{I2C_{RESET}})")
		(layer "B.Cu")
		(name "$teardrop_padvia$")
		(hatch none 0.1)
		(priority 30643)
		(attr
			(teardrop
				(type padvia)
			)
		)
		(connect_pads yes
			(clearance 0)
		)
		(min_thickness 0.0254)
		(filled_areas_thickness no)
		(fill yes
			(thermal_gap 0.5)
			(thermal_bridge_width 0.5)
			(island_removal_mode 1)
			(island_area_min 10)
		)
		(polygon
			(pts
				(xy 194.530636 131.845744) (xy 194.507336 131.815691) (xy 194.498899 131.788269) (xy 194.512918 131.742305)
				(xy 194.558766 131.689444) (xy 194.605866 131.636975) (xy 194.6387 131.57369) (xy 194.423414 131.514369)
				(xy 194.23961 131.642649) (xy 194.306587 131.752978) (xy 194.355659 131.834149) (xy 194.442248 131.934132)
			)
		)
	)
	(zone
		(net 2)
		(net_name "+3V3")
		(layer "B.Cu")
		(name "$teardrop_padvia$")
		(hatch none 0.1)
		(priority 30233)
		(attr
			(teardrop
				(type padvia)
			)
		)
		(connect_pads yes
			(clearance 0)
		)
		(min_thickness 0.0254)
		(filled_areas_thickness no)
		(fill yes
			(thermal_gap 0.5)
			(thermal_bridge_width 0.5)
			(island_removal_mode 1)
			(island_area_min 10)
		)
		(polygon
			(pts
				(xy 105.333 169.81) (xy 105.31791 169.810337) (xy 105.277674 169.80976) (xy 105.23613 169.797946)
				(xy 105.200835 169.763367) (xy 105.179347 169.6945) (xy 104.919 169.96) (xy 105.179347 170.2255)
				(xy 105.190291 170.179062) (xy 105.207391 170.146865) (xy 105.251856 170.115422) (xy 105.31791 170.109663)
				(xy 105.333 170.11)
			)
		)
	)
	(zone
		(net 155)
		(net_name "Net-(J1A-LED_D2)")
		(layer "B.Cu")
		(name "$teardrop_padvia$")
		(hatch none 0.1)
		(priority 30333)
		(attr
			(teardrop
				(type padvia)
			)
		)
		(connect_pads yes
			(clearance 0)
		)
		(min_thickness 0.0254)
		(filled_areas_thickness no)
		(fill yes
			(thermal_gap 0.5)
			(thermal_bridge_width 0.5)
			(island_removal_mode 1)
			(island_area_min 10)
		)
		(polygon
			(pts
				(xy 122.8575 99.422) (xy 122.837531 99.484866) (xy 122.811079 99.516844) (xy 122.773668 99.545358)
				(xy 122.726473 99.567882) (xy 122.668833 99.583093) (xy 122.668202 99.583202) (xy 122.92 99.861)
				(xy 123.171798 99.583202) (xy 123.116365 99.568905) (xy 123.07048 99.547825) (xy 123.032799 99.52046)
				(xy 123.005566 99.489552) (xy 122.988528 99.456265) (xy 122.982511 99.423434) (xy 122.9825 99.422)
			)
		)
	)
	(zone
		(net 44)
		(net_name "/2xUSB3.0+RJ45/USBSS_1.TX+")
		(layer "B.Cu")
		(name "$teardrop_padvia$")
		(hatch none 0.1)
		(priority 30967)
		(attr
			(teardrop
				(type padvia)
			)
		)
		(connect_pads yes
			(clearance 0)
		)
		(min_thickness 0.0254)
		(filled_areas_thickness no)
		(fill yes
			(thermal_gap 0.5)
			(thermal_bridge_width 0.5)
			(island_removal_mode 1)
			(island_area_min 10)
		)
		(polygon
			(pts
				(xy 101 104.5025) (xy 101.065257 104.491205) (xy 101.146845 104.476572) (xy 101.191679 104.478439)
				(xy 101.238621 104.492) (xy 101.326 104.367) (xy 101.052976 104.289537) (xy 101.047871 104.316512)
				(xy 101.036582 104.325759) (xy 101.013291 104.321189) (xy 101 104.3175)
			)
		)
	)
	(zone
		(net 876)
		(net_name "Net-(J2B-TX_{FAULT})")
		(layer "B.Cu")
		(name "$teardrop_padvia$")
		(hatch none 0.1)
		(priority 30069)
		(attr
			(teardrop
				(type padvia)
			)
		)
		(connect_pads yes
			(clearance 0)
		)
		(min_thickness 0.0254)
		(filled_areas_thickness no)
		(fill yes
			(thermal_gap 0.5)
			(thermal_bridge_width 0.5)
			(island_removal_mode 1)
			(island_area_min 10)
		)
		(polygon
			(pts
				(xy 143.2625 165.675738) (xy 143.267324 165.588809) (xy 143.281091 165.518458) (xy 143.32811 165.417033)
				(xy 143.417951 165.314123) (xy 143.485747 165.242217) (xy 143.557532 165.148895) (xy 143.2 164.909)
				(xy 142.842468 165.148895) (xy 142.944948 165.275853) (xy 142.982049 165.314123) (xy 143.043795 165.380157)
				(xy 143.093069 165.452561) (xy 143.125696 165.546149) (xy 143.1375 165.675738)
			)
		)
	)
	(zone
		(net 680)
		(net_name "Net-(U45C-PRTAD3)")
		(layer "B.Cu")
		(name "$teardrop_padvia$")
		(hatch none 0.1)
		(priority 30820)
		(attr
			(teardrop
				(type padvia)
			)
		)
		(connect_pads yes
			(clearance 0)
		)
		(min_thickness 0.0254)
		(filled_areas_thickness no)
		(fill yes
			(thermal_gap 0.5)
			(thermal_bridge_width 0.5)
			(island_removal_mode 1)
			(island_area_min 10)
		)
		(polygon
			(pts
				(xy 130.209972 136.51836) (xy 130.231126 136.546262) (xy 130.237606 136.571695) (xy 130.220399 136.614244)
				(xy 130.171809 136.662514) (xy 130.102919 136.734997) (xy 130.290707 136.860707) (xy 130.477081 136.734997)
				(xy 130.419376 136.62356) (xy 130.413136 136.607691) (xy 130.375714 136.526403) (xy 130.29836 136.429972)
			)
		)
	)
	(zone
		(net 87)
		(net_name "/Com Express 7 Interfaces/PCIe_{B2Ax4}.RX1-")
		(layer "B.Cu")
		(name "$teardrop_padvia$")
		(hatch none 0.1)
		(priority 30550)
		(attr
			(teardrop
				(type padvia)
			)
		)
		(connect_pads yes
			(clearance 0)
		)
		(min_thickness 0.0254)
		(filled_areas_thickness no)
		(fill yes
			(thermal_gap 0.5)
			(thermal_bridge_width 0.5)
			(island_removal_mode 1)
			(island_area_min 10)
		)
		(polygon
			(pts
				(xy 293.543 75.019852) (xy 293.548395 75.181383) (xy 293.551945 75.265794) (xy 293.547323 75.367488)
				(xy 293.768 75.388348) (xy 293.931231 75.238495) (xy 293.862562 75.184355) (xy 293.846108 75.174464)
				(xy 293.807435 75.149964) (xy 293.775221 75.120457) (xy 293.753173 75.079301) (xy 293.745 75.019852)
			)
		)
	)
	(zone
		(net 960)
		(net_name "/PCIe redriver/PCIe_{I}_C.RX3+")
		(layer "B.Cu")
		(name "$teardrop_padvia$")
		(hatch none 0.1)
		(priority 30180)
		(attr
			(teardrop
				(type padvia)
			)
		)
		(connect_pads yes
			(clearance 0)
		)
		(min_thickness 0.0254)
		(filled_areas_thickness no)
		(fill yes
			(thermal_gap 0.5)
			(thermal_bridge_width 0.5)
			(island_removal_mode 1)
			(island_area_min 10)
		)
		(polygon
			(pts
				(xy 195.55477 141.50648) (xy 195.557828 141.542429) (xy 195.55035 141.579129) (xy 195.501529 141.6603)
				(xy 195.390089 141.770892) (xy 195.669336 141.910253) (xy 195.917356 141.705725) (xy 195.829271 141.630989)
				(xy 195.756038 141.522722) (xy 195.703932 141.388768) (xy 195.697605 141.363645)
			)
		)
	)
	(zone
		(net 355)
		(net_name "Net-(J12D-LPC_CLK{slash}ESPI_CK)")
		(layer "B.Cu")
		(name "$teardrop_padvia$")
		(hatch none 0.1)
		(priority 30743)
		(attr
			(teardrop
				(type padvia)
			)
		)
		(connect_pads yes
			(clearance 0)
		)
		(min_thickness 0.0254)
		(filled_areas_thickness no)
		(fill yes
			(thermal_gap 0.5)
			(thermal_bridge_width 0.5)
			(island_removal_mode 1)
			(island_area_min 10)
		)
		(polygon
			(pts
				(xy 181.350677 165.6875) (xy 181.281236 165.682682) (xy 181.229913 165.66896) (xy 181.154371 165.622246)
				(xy 181.142231 165.612701) (xy 181.075003 165.562919) (xy 180.949 165.75) (xy 181.075003 165.937081)
				(xy 181.142229 165.887299) (xy 181.225396 165.832894) (xy 181.278251 165.81781) (xy 181.350677 165.8125)
			)
		)
	)
	(zone
		(net 45)
		(net_name "/2xUSB3.0+RJ45/USBSS_2.TX+")
		(layer "B.Cu")
		(name "$teardrop_padvia$")
		(hatch none 0.1)
		(priority 31023)
		(attr
			(teardrop
				(type padvia)
			)
		)
		(connect_pads yes
			(clearance 0)
		)
		(min_thickness 0.0254)
		(filled_areas_thickness no)
		(fill yes
			(thermal_gap 0.5)
			(thermal_bridge_width 0.5)
			(island_removal_mode 1)
			(island_area_min 10)
		)
		(polygon
			(pts
				(xy 123.338 103.2095) (xy 123.319153 103.2144) (xy 123.285892 103.220518) (xy 123.271353 103.212159)
				(xy 123.261005 103.1895) (xy 123.012 103.302) (xy 123.261005 103.4145) (xy 123.270976 103.392283)
				(xy 123.284951 103.383669) (xy 123.319153 103.3896) (xy 123.338 103.3945)
			)
		)
	)
	(zone
		(net 218)
		(net_name "/Com Express 7 Interfaces/PCIe_{B1x4}.RX1+")
		(layer "B.Cu")
		(name "$teardrop_padvia$")
		(hatch none 0.1)
		(priority 30177)
		(attr
			(teardrop
				(type padvia)
			)
		)
		(connect_pads yes
			(clearance 0)
		)
		(min_thickness 0.0254)
		(filled_areas_thickness no)
		(fill yes
			(thermal_gap 0.5)
			(thermal_bridge_width 0.5)
			(island_removal_mode 1)
			(island_area_min 10)
		)
		(polygon
			(pts
				(xy 199.011981 140.435381) (xy 198.992614 140.427863) (xy 198.825527 140.352453) (xy 198.741272 140.294216)
				(xy 198.671565 140.217294) (xy 198.468064 140.466341) (xy 198.6082 140.744811) (xy 198.697143 140.646746)
				(xy 198.771407 140.58882) (xy 198.809211 140.573844) (xy 198.845079 140.571934) (xy 198.869146 140.578216)
			)
		)
	)
	(zone
		(net 206)
		(net_name "/Backplane/USB.D+")
		(layer "B.Cu")
		(name "$teardrop_padvia$")
		(hatch none 0.1)
		(priority 30954)
		(attr
			(teardrop
				(type padvia)
			)
		)
		(connect_pads yes
			(clearance 0)
		)
		(min_thickness 0.0254)
		(filled_areas_thickness no)
		(fill yes
			(thermal_gap 0.5)
			(thermal_bridge_width 0.5)
			(island_removal_mode 1)
			(island_area_min 10)
		)
		(polygon
			(pts
				(xy 314.04 166.3605) (xy 314.120309 166.344748) (xy 314.208167 166.325329) (xy 314.256805 166.323846)
				(xy 314.308351 166.333) (xy 314.366 166.208) (xy 314.090225 166.144366) (xy 314.085746 166.1728)
				(xy 314.074735 166.182653) (xy 314.052525 166.17878) (xy 314.04 166.1755)
			)
		)
	)
	(zone
		(net 714)
		(net_name "Net-(U39-I2C_{DONE})")
		(layer "B.Cu")
		(name "$teardrop_padvia$")
		(hatch none 0.1)
		(priority 30892)
		(attr
			(teardrop
				(type padvia)
			)
		)
		(connect_pads yes
			(clearance 0)
		)
		(min_thickness 0.0254)
		(filled_areas_thickness no)
		(fill yes
			(thermal_gap 0.5)
			(thermal_bridge_width 0.5)
			(island_removal_mode 1)
			(island_area_min 10)
		)
		(polygon
			(pts
				(xy 121.4625 149.5355) (xy 121.462407 149.529317) (xy 121.468026 149.490256) (xy 121.483003 149.472337)
				(xy 121.512655 149.459768) (xy 121.401 149.047) (xy 121.287659 149.457247) (xy 121.314517 149.468655)
				(xy 121.329575 149.484391) (xy 121.337599 149.529037) (xy 121.3375 149.5355)
			)
		)
	)
	(zone
		(net 2)
		(net_name "+3V3")
		(layer "B.Cu")
		(name "$teardrop_padvia$")
		(hatch none 0.1)
		(priority 30903)
		(attr
			(teardrop
				(type padvia)
			)
		)
		(connect_pads yes
			(clearance 0)
		)
		(min_thickness 0.0254)
		(filled_areas_thickness no)
		(fill yes
			(thermal_gap 0.5)
			(thermal_bridge_width 0.5)
			(island_removal_mode 1)
			(island_area_min 10)
		)
		(polygon
			(pts
				(xy 189.888032 136.570889) (xy 189.892569 136.575291) (xy 189.916553 136.607173) (xy 189.918879 136.630618)
				(xy 189.907119 136.660689) (xy 190.277647 136.872117) (xy 190.066219 136.501589) (xy 190.039271 136.512816)
				(xy 190.017613 136.512516) (xy 189.980821 136.487039) (xy 189.976419 136.482502)
			)
		)
	)
	(zone
		(net 172)
		(net_name "/2xSFP+/SFI0.TX+")
		(layer "B.Cu")
		(name "$teardrop_padvia$")
		(hatch none 0.1)
		(priority 30626)
		(attr
			(teardrop
				(type padvia)
			)
		)
		(connect_pads yes
			(clearance 0)
		)
		(min_thickness 0.0254)
		(filled_areas_thickness no)
		(fill yes
			(thermal_gap 0.5)
			(thermal_bridge_width 0.5)
			(island_removal_mode 1)
			(island_area_min 10)
		)
		(polygon
			(pts
				(xy 147.215 147.977084) (xy 147.219756 147.936299) (xy 147.233046 147.906971) (xy 147.277406 147.872311)
				(xy 147.320219 147.855729) (xy 147.405003 147.817081) (xy 147.28 147.629) (xy 147.059323 147.632143)
				(xy 147.057568 147.797771) (xy 147.055 147.977084)
			)
		)
	)
	(zone
		(net 88)
		(net_name "/Com Express 7 Interfaces/PCIe_{B2Ax4}.RX2-")
		(layer "B.Cu")
		(name "$teardrop_padvia$")
		(hatch none 0.1)
		(priority 30524)
		(attr
			(teardrop
				(type padvia)
			)
		)
		(connect_pads yes
			(clearance 0)
		)
		(min_thickness 0.0254)
		(filled_areas_thickness no)
		(fill yes
			(thermal_gap 0.5)
			(thermal_bridge_width 0.5)
			(island_removal_mode 1)
			(island_area_min 10)
		)
		(polygon
			(pts
				(xy 214.5705 161.867496) (xy 214.575235 161.82071) (xy 214.588379 161.785257) (xy 214.633387 161.73706)
				(xy 214.671608 161.712883) (xy 214.714774 161.685514) (xy 214.756731 161.648852) (xy 214.5935 161.499)
				(xy 214.372823 161.519859) (xy 214.377452 161.620536) (xy 214.374019 161.703908) (xy 214.373895 161.705963)
				(xy 214.3685 161.867496)
			)
		)
	)
	(zone
		(net 893)
		(net_name "Net-(J2B-TX_{DISABLE})")
		(layer "B.Cu")
		(name "$teardrop_padvia$")
		(hatch none 0.1)
		(priority 30716)
		(attr
			(teardrop
				(type padvia)
			)
		)
		(connect_pads yes
			(clearance 0)
		)
		(min_thickness 0.0254)
		(filled_areas_thickness no)
		(fill yes
			(thermal_gap 0.5)
			(thermal_bridge_width 0.5)
			(island_removal_mode 1)
			(island_area_min 10)
		)
		(polygon
			(pts
				(xy 138.1125 167.965677) (xy 138.117318 167.896236) (xy 138.13104 167.844912) (xy 138.177755 167.76937)
				(xy 138.187299 167.757229) (xy 138.237081 167.690003) (xy 138.05 167.564) (xy 137.862919 167.690003)
				(xy 137.912701 167.757231) (xy 137.967106 167.840397) (xy 137.98219 167.893251) (xy 137.9875 167.965677)
			)
		)
	)
	(zone
		(net 2)
		(net_name "+3V3")
		(layer "B.Cu")
		(name "$teardrop_padvia$")
		(hatch none 0.1)
		(priority 30697)
		(attr
			(teardrop
				(type padvia)
			)
		)
		(connect_pads yes
			(clearance 0)
		)
		(min_thickness 0.0254)
		(filled_areas_thickness no)
		(fill yes
			(thermal_gap 0.5)
			(thermal_bridge_width 0.5)
			(island_removal_mode 1)
			(island_area_min 10)
		)
		(polygon
			(pts
				(xy 122.1175 162.159323) (xy 122.112682 162.228763) (xy 122.09896 162.280087) (xy 122.052245 162.355628)
				(xy 122.042702 162.367768) (xy 121.992919 162.434997) (xy 122.18 162.561) (xy 122.367081 162.434997)
				(xy 122.317299 162.367769) (xy 122.262894 162.284603) (xy 122.24781 162.231748) (xy 122.2425 162.159323)
			)
		)
	)
	(zone
		(net 203)
		(net_name "/Backplane/PCIe_{REF}.CK+")
		(layer "B.Cu")
		(name "$teardrop_padvia$")
		(hatch none 0.1)
		(priority 30970)
		(attr
			(teardrop
				(type padvia)
			)
		)
		(connect_pads yes
			(clearance 0)
		)
		(min_thickness 0.0254)
		(filled_areas_thickness no)
		(fill yes
			(thermal_gap 0.5)
			(thermal_bridge_width 0.5)
			(island_removal_mode 1)
			(island_area_min 10)
		)
		(polygon
			(pts
				(xy 315.438008 164.666443) (xy 315.429825 164.672724) (xy 315.417807 164.67983) (xy 315.412 164.647749)
				(xy 315.136001 164.710013) (xy 315.19143 164.835) (xy 315.275765 164.826647) (xy 315.367441 164.850466)
				(xy 315.440808 164.868423)
			)
		)
	)
	(zone
		(net 2)
		(net_name "+3V3")
		(layer "B.Cu")
		(name "$teardrop_padvia$")
		(hatch none 0.1)
		(priority 30907)
		(attr
			(teardrop
				(type padvia)
			)
		)
		(connect_pads yes
			(clearance 0)
		)
		(min_thickness 0.0254)
		(filled_areas_thickness no)
		(fill yes
			(thermal_gap 0.5)
			(thermal_bridge_width 0.5)
			(island_removal_mode 1)
			(island_area_min 10)
		)
		(polygon
			(pts
				(xy 192.009353 134.449569) (xy 192.01389 134.453971) (xy 192.037874 134.485853) (xy 192.0402 134.509298)
				(xy 192.02844 134.539369) (xy 192.398968 134.750797) (xy 192.18754 134.380269) (xy 192.160592 134.391496)
				(xy 192.138934 134.391196) (xy 192.102142 134.365719) (xy 192.09774 134.361182)
			)
		)
	)
	(zone
		(net 964)
		(net_name "/PCIe redriver/PCIe_{O}_C.TX2-")
		(layer "B.Cu")
		(name "$teardrop_padvia$")
		(hatch none 0.1)
		(priority 30846)
		(attr
			(teardrop
				(type padvia)
			)
		)
		(connect_pads yes
			(clearance 0)
		)
		(min_thickness 0.0254)
		(filled_areas_thickness no)
		(fill yes
			(thermal_gap 0.5)
			(thermal_bridge_width 0.5)
			(island_removal_mode 1)
			(island_area_min 10)
		)
		(polygon
			(pts
				(xy 116.5575 149.5355) (xy 116.54007 149.423096) (xy 116.518317 149.299222) (xy 116.516358 149.228305)
				(xy 116.526 149.150651) (xy 116.401 149.047) (xy 116.337574 149.485315) (xy 116.363182 149.489774)
				(xy 116.369601 149.500719) (xy 116.361457 149.52134) (xy 116.3555 149.5355)
			)
		)
	)
	(zone
		(net 1)
		(net_name "GND")
		(layer "B.Cu")
		(name "$teardrop_padvia$")
		(hatch none 0.1)
		(priority 30219)
		(attr
			(teardrop
				(type padvia)
			)
		)
		(connect_pads yes
			(clearance 0)
		)
		(min_thickness 0.0254)
		(filled_areas_thickness no)
		(fill yes
			(thermal_gap 0.5)
			(thermal_bridge_width 0.5)
			(island_removal_mode 1)
			(island_area_min 10)
		)
		(polygon
			(pts
				(xy 124.181056 100.470556) (xy 124.103239 100.520409) (xy 123.981796 100.548529) (xy 123.907524 100.549743)
				(xy 123.827238 100.540492) (xy 123.824526 100.54) (xy 123.879293 100.860707) (xy 124.175 100.940474)
				(xy 124.171462 100.854034) (xy 124.177546 100.774401) (xy 124.192581 100.701862) (xy 124.215544 100.639048)
				(xy 124.269444 100.558944)
			)
		)
	)
	(zone
		(net 249)
		(net_name "/Com Express 7 Interfaces/PCIe_{B2Bx4}.TX2+")
		(layer "B.Cu")
		(name "$teardrop_padvia$")
		(hatch none 0.1)
		(priority 30300)
		(attr
			(teardrop
				(type padvia)
			)
		)
		(connect_pads yes
			(clearance 0)
		)
		(min_thickness 0.0254)
		(filled_areas_thickness no)
		(fill yes
			(thermal_gap 0.5)
			(thermal_bridge_width 0.5)
			(island_removal_mode 1)
			(island_area_min 10)
		)
		(polygon
			(pts
				(xy 175.39 98.461) (xy 175.404678 98.457463) (xy 175.434685 98.454192) (xy 175.445673 98.466143)
				(xy 175.45 98.495) (xy 176.201 98.36) (xy 175.45 98.225) (xy 175.445525 98.254204) (xy 175.434203 98.265997)
				(xy 175.404678 98.262537) (xy 175.39 98.259)
			)
		)
	)
	(zone
		(net 2)
		(net_name "+3V3")
		(layer "B.Cu")
		(name "$teardrop_padvia$")
		(hatch none 0.1)
		(priority 30798)
		(attr
			(teardrop
				(type padvia)
			)
		)
		(connect_pads yes
			(clearance 0)
		)
		(min_thickness 0.0254)
		(filled_areas_thickness no)
		(fill yes
			(thermal_gap 0.5)
			(thermal_bridge_width 0.5)
			(island_removal_mode 1)
			(island_area_min 10)
		)
		(polygon
			(pts
				(xy 120.4625 145.220677) (xy 120.467313 145.151677) (xy 120.481002 145.100623) (xy 120.527606 145.025522)
				(xy 120.537456 145.013077) (xy 120.588081 144.945003) (xy 120.401 144.819) (xy 120.213919 144.945003)
				(xy 120.262846 145.011356) (xy 120.317209 145.094999) (xy 120.332224 145.148018) (xy 120.3375 145.220677)
			)
		)
	)
	(zone
		(net 154)
		(net_name "Net-(J1A-LED_D1)")
		(layer "B.Cu")
		(name "$teardrop_padvia$")
		(hatch none 0.1)
		(priority 30346)
		(attr
			(teardrop
				(type padvia)
			)
		)
		(connect_pads yes
			(clearance 0)
		)
		(min_thickness 0.0254)
		(filled_areas_thickness no)
		(fill yes
			(thermal_gap 0.5)
			(thermal_bridge_width 0.5)
			(island_removal_mode 1)
			(island_area_min 10)
		)
		(polygon
			(pts
				(xy 122.8575 97.422) (xy 122.837531 97.484866) (xy 122.811079 97.516844) (xy 122.773668 97.545358)
				(xy 122.726473 97.567882) (xy 122.668833 97.583093) (xy 122.668202 97.583202) (xy 122.92 97.861)
				(xy 123.171798 97.583202) (xy 123.116365 97.568905) (xy 123.07048 97.547825) (xy 123.032799 97.52046)
				(xy 123.005566 97.489552) (xy 122.988528 97.456265) (xy 122.982511 97.423434) (xy 122.9825 97.422)
			)
		)
	)
	(zone
		(net 173)
		(net_name "/2xSFP+/SFI0.TX-")
		(layer "B.Cu")
		(name "$teardrop_padvia$")
		(hatch none 0.1)
		(priority 30058)
		(attr
			(teardrop
				(type padvia)
			)
		)
		(connect_pads yes
			(clearance 0)
		)
		(min_thickness 0.0254)
		(filled_areas_thickness no)
		(fill yes
			(thermal_gap 0.5)
			(thermal_bridge_width 0.5)
			(island_removal_mode 1)
			(island_area_min 10)
		)
		(polygon
			(pts
				(xy 147.705 158.553007) (xy 147.700187 158.628448) (xy 147.686495 158.690313) (xy 147.63921 158.780166)
				(xy 147.561095 158.853624) (xy 147.51608 158.88632) (xy 147.417957 158.961995) (xy 147.369144 159.010683)
				(xy 147.322546 159.071026) (xy 147.68 159.311) (xy 148.087287 159.191224) (xy 148.024795 159.033607)
				(xy 147.97569 158.946035) (xy 147.933519 158.871227) (xy 147.898233 158.788884) (xy 147.874003 158.68686)
				(xy 147.865 158.553007)
			)
		)
	)
	(zone
		(net 896)
		(net_name "Net-(J2B-RX_{LOS})")
		(layer "B.Cu")
		(name "$teardrop_padvia$")
		(hatch none 0.1)
		(priority 30075)
		(attr
			(teardrop
				(type padvia)
			)
		)
		(connect_pads yes
			(clearance 0)
		)
		(min_thickness 0.0254)
		(filled_areas_thickness no)
		(fill yes
			(thermal_gap 0.5)
			(thermal_bridge_width 0.5)
			(island_removal_mode 1)
			(island_area_min 10)
		)
		(polygon
			(pts
				(xy 143.020934 160.827454) (xy 143.08255 160.765601) (xy 143.246377 160.608329) (xy 143.438895 160.467532)
				(xy 143.200707 160.109293) (xy 142.778262 160.193889) (xy 142.81636 160.297862) (xy 142.906726 160.428221)
				(xy 142.962387 160.503236) (xy 142.996154 160.576522) (xy 142.999714 160.61417) (xy 142.991663 160.653369)
				(xy 142.969955 160.694781) (xy 142.932546 160.739066)
			)
		)
	)
	(zone
		(net 92)
		(net_name "/Com Express 7 Interfaces/PCIe_{B2Ax4}.RX2+")
		(layer "B.Cu")
		(name "$teardrop_padvia$")
		(hatch none 0.1)
		(priority 30532)
		(attr
			(teardrop
				(type padvia)
			)
		)
		(connect_pads yes
			(clearance 0)
		)
		(min_thickness 0.0254)
		(filled_areas_thickness no)
		(fill yes
			(thermal_gap 0.5)
			(thermal_bridge_width 0.5)
			(island_removal_mode 1)
			(island_area_min 10)
		)
		(polygon
			(pts
				(xy 214.1815 161.867496) (xy 214.176105 161.705964) (xy 214.172555 161.621553) (xy 214.177177 161.519859)
				(xy 213.9565 161.499) (xy 213.793268 161.648852) (xy 213.861936 161.702992) (xy 213.878392 161.712884)
				(xy 213.917064 161.737384) (xy 213.949279 161.76689) (xy 213.971327 161.808046) (xy 213.9795 161.867496)
			)
		)
	)
	(zone
		(net 121)
		(net_name "/2xSFP+/10GKR_SFP1.TX-")
		(layer "B.Cu")
		(name "$teardrop_padvia$")
		(hatch none 0.1)
		(priority 30634)
		(attr
			(teardrop
				(type padvia)
			)
		)
		(connect_pads yes
			(clearance 0)
		)
		(min_thickness 0.0254)
		(filled_areas_thickness no)
		(fill yes
			(thermal_gap 0.5)
			(thermal_bridge_width 0.5)
			(island_removal_mode 1)
			(island_area_min 10)
		)
		(polygon
			(pts
				(xy 137.905 147.272916) (xy 137.907568 147.452222) (xy 137.909323 147.617856) (xy 138.13 147.621)
				(xy 138.255003 147.432919) (xy 138.170218 147.39427) (xy 138.129402 147.378612) (xy 138.095942 147.357626)
				(xy 138.073315 147.324624) (xy 138.065 147.272916)
			)
		)
	)
	(zone
		(net 176)
		(net_name "Net-(J3-CC_{1})")
		(layer "B.Cu")
		(name "$teardrop_padvia$")
		(hatch none 0.1)
		(priority 30470)
		(attr
			(teardrop
				(type padvia)
			)
		)
		(connect_pads yes
			(clearance 0)
		)
		(min_thickness 0.0254)
		(filled_areas_thickness no)
		(fill yes
			(thermal_gap 0.5)
			(thermal_bridge_width 0.5)
			(island_removal_mode 1)
			(island_area_min 10)
		)
		(polygon
			(pts
				(xy 102.699323 86.91) (xy 102.777235 86.914713) (xy 102.83602 86.9277) (xy 102.927051 86.969802)
				(xy 103.012222 87.0125) (xy 103.101 86.81) (xy 103.012222 86.6075) (xy 102.92705 86.650199) (xy 102.834217 86.692867)
				(xy 102.776078 86.705444) (xy 102.699323 86.71)
			)
		)
	)
	(zone
		(net 161)
		(net_name "/2xUSB3.0+RJ45/USBSS_2.RX+")
		(layer "B.Cu")
		(name "$teardrop_padvia$")
		(hatch none 0.1)
		(priority 30591)
		(attr
			(teardrop
				(type padvia)
			)
		)
		(connect_pads yes
			(clearance 0)
		)
		(min_thickness 0.0254)
		(filled_areas_thickness no)
		(fill yes
			(thermal_gap 0.5)
			(thermal_bridge_width 0.5)
			(island_removal_mode 1)
			(island_area_min 10)
		)
		(polygon
			(pts
				(xy 127.9225 107.390416) (xy 127.926684 107.554858) (xy 127.926823 107.737562) (xy 128.1475 107.751)
				(xy 128.306688 107.597104) (xy 128.239162 107.548225) (xy 128.212819 107.534851) (xy 128.172556 107.513476)
				(xy 128.138998 107.486768) (xy 128.11602 107.447992) (xy 128.1075 107.390416)
			)
		)
	)
	(zone
		(net 673)
		(net_name "/2xSFP+/KR to SFI #2/PRBSEN")
		(layer "B.Cu")
		(name "$teardrop_padvia$")
		(hatch none 0.1)
		(priority 30451)
		(attr
			(teardrop
				(type padvia)
			)
		)
		(connect_pads yes
			(clearance 0)
		)
		(min_thickness 0.0254)
		(filled_areas_thickness no)
		(fill yes
			(thermal_gap 0.5)
			(thermal_bridge_width 0.5)
			(island_removal_mode 1)
			(island_area_min 10)
		)
		(polygon
			(pts
				(xy 138.847 138.4225) (xy 138.906412 138.442273) (xy 138.962497 138.505547) (xy 138.984199 138.554172)
				(xy 138.998873 138.613531) (xy 139.000653 138.6255) (xy 139.261 138.36) (xy 139.000653 138.0945)
				(xy 138.987804 138.154638) (xy 138.96787 138.204522) (xy 138.941945 138.244641) (xy 138.912125 138.273654)
				(xy 138.880707 138.291146) (xy 138.848896 138.297479) (xy 138.847 138.2975)
			)
		)
	)
	(zone
		(net 273)
		(net_name "/M.2 key M #2/PCIE_{REF}.CK+")
		(layer "B.Cu")
		(name "$teardrop_padvia$")
		(hatch none 0.1)
		(priority 30554)
		(attr
			(teardrop
				(type padvia)
			)
		)
		(connect_pads yes
			(clearance 0)
		)
		(min_thickness 0.0254)
		(filled_areas_thickness no)
		(fill yes
			(thermal_gap 0.5)
			(thermal_bridge_width 0.5)
			(island_removal_mode 1)
			(island_area_min 10)
		)
		(polygon
			(pts
				(xy 299.542 75.127139) (xy 299.547395 75.28867) (xy 299.550945 75.373081) (xy 299.546323 75.474775)
				(xy 299.767 75.495635) (xy 299.930231 75.345782) (xy 299.861562 75.291642) (xy 299.845108 75.281751)
				(xy 299.806435 75.257251) (xy 299.774221 75.227744) (xy 299.752173 75.186588) (xy 299.744 75.127139)
			)
		)
	)
	(zone
		(net 1)
		(net_name "GND")
		(layer "B.Cu")
		(name "$teardrop_padvia$")
		(hatch none 0.1)
		(priority 30669)
		(attr
			(teardrop
				(type padvia)
			)
		)
		(connect_pads yes
			(clearance 0)
		)
		(min_thickness 0.0254)
		(filled_areas_thickness no)
		(fill yes
			(thermal_gap 0.5)
			(thermal_bridge_width 0.5)
			(island_removal_mode 1)
			(island_area_min 10)
		)
		(polygon
			(pts
				(xy 143.093392 142.098219) (xy 143.002192 142.195799) (xy 142.943467 142.270905) (xy 142.937179 142.279414)
				(xy 142.870775 142.366738) (xy 143.044193 142.505405) (xy 143.265075 142.459592) (xy 143.23464 142.39069)
				(xy 143.198409 142.343462) (xy 143.169137 142.305756) (xy 143.150963 142.268726) (xy 143.152355 142.22985)
				(xy 143.181781 142.186608)
			)
		)
	)
	(zone
		(net 378)
		(net_name "/Com Express 7 Interfaces/USB1.D+")
		(layer "B.Cu")
		(name "$teardrop_padvia$")
		(hatch none 0.1)
		(priority 30604)
		(attr
			(teardrop
				(type padvia)
			)
		)
		(connect_pads yes
			(clearance 0)
		)
		(min_thickness 0.0254)
		(filled_areas_thickness no)
		(fill yes
			(thermal_gap 0.5)
			(thermal_bridge_width 0.5)
			(island_removal_mode 1)
			(island_area_min 10)
		)
		(polygon
			(pts
				(xy 204.7475 141.894916) (xy 204.753356 142.070057) (xy 204.756323 142.241365) (xy 204.977 142.251)
				(xy 205.102003 142.062919) (xy 205.03422 142.027253) (xy 204.994585 142.00792) (xy 204.962257 141.983824)
				(xy 204.94048 141.948358) (xy 204.9325 141.894916)
			)
		)
	)
	(zone
		(net 2)
		(net_name "+3V3")
		(layer "B.Cu")
		(name "$teardrop_padvia$")
		(hatch none 0.1)
		(priority 30796)
		(attr
			(teardrop
				(type padvia)
			)
		)
		(connect_pads yes
			(clearance 0)
		)
		(min_thickness 0.0254)
		(filled_areas_thickness no)
		(fill yes
			(thermal_gap 0.5)
			(thermal_bridge_width 0.5)
			(island_removal_mode 1)
			(island_area_min 10)
		)
		(polygon
			(pts
				(xy 117.4635 145.220677) (xy 117.468313 145.151677) (xy 117.482002 145.100623) (xy 117.528606 145.025522)
				(xy 117.538456 145.013077) (xy 117.589081 144.945003) (xy 117.402 144.819) (xy 117.214919 144.945003)
				(xy 117.263846 145.011356) (xy 117.318209 145.094999) (xy 117.333224 145.148018) (xy 117.3385 145.220677)
			)
		)
	)
	(zone
		(net 192)
		(net_name "/OCuLink/PCIe_{REF0}.CK+")
		(layer "B.Cu")
		(name "$teardrop_padvia$")
		(hatch none 0.1)
		(priority 30574)
		(attr
			(teardrop
				(type padvia)
			)
		)
		(connect_pads yes
			(clearance 0)
		)
		(min_thickness 0.0254)
		(filled_areas_thickness no)
		(fill yes
			(thermal_gap 0.5)
			(thermal_bridge_width 0.5)
			(island_removal_mode 1)
			(island_area_min 10)
		)
		(polygon
			(pts
				(xy 99.396202 161.4435) (xy 99.23467 161.448895) (xy 99.15026 161.452445) (xy 99.048566 161.447823)
				(xy 99.027706 161.6685) (xy 99.177558 161.831731) (xy 99.231698 161.763062) (xy 99.241589 161.746608)
				(xy 99.266089 161.707935) (xy 99.295596 161.675721) (xy 99.336752 161.653673) (xy 99.396202 161.6455)
			)
		)
	)
	(zone
		(net 1)
		(net_name "GND")
		(layer "B.Cu")
		(name "$teardrop_padvia$")
		(hatch none 0.1)
		(priority 30138)
		(attr
			(teardrop
				(type padvia)
			)
		)
		(connect_pads yes
			(clearance 0)
		)
		(min_thickness 0.0254)
		(filled_areas_thickness no)
		(fill yes
			(thermal_gap 0.5)
			(thermal_bridge_width 0.5)
			(island_removal_mode 1)
			(island_area_min 10)
		)
		(polygon
			(pts
				(xy 122.818698 137.755829) (xy 122.831958 137.768945) (xy 122.882378 137.821413) (xy 122.929857 137.888127)
				(xy 122.961646 137.973687) (xy 122.965 138.08269) (xy 123.260707 138.010707) (xy 123.324917 137.69)
				(xy 123.272052 137.692454) (xy 123.225344 137.685707) (xy 123.142275 137.648098) (xy 123.053513 137.567404)
				(xy 123.030829 137.543698)
			)
		)
	)
	(zone
		(net 897)
		(net_name "Net-(J2B-RS1)")
		(layer "B.Cu")
		(name "$teardrop_padvia$")
		(hatch none 0.1)
		(priority 30434)
		(attr
			(teardrop
				(type padvia)
			)
		)
		(connect_pads yes
			(clearance 0)
		)
		(min_thickness 0.0254)
		(filled_areas_thickness no)
		(fill yes
			(thermal_gap 0.5)
			(thermal_bridge_width 0.5)
			(island_removal_mode 1)
			(island_area_min 10)
		)
		(polygon
			(pts
				(xy 136.9875 168.267) (xy 136.967727 168.326412) (xy 136.904453 168.382496) (xy 136.855828 168.404198)
				(xy 136.796469 168.418872) (xy 136.7845 168.420652) (xy 137.05 168.681) (xy 137.3155 168.420652)
				(xy 137.255362 168.407803) (xy 137.205478 168.387869) (xy 137.165358 168.361944) (xy 137.136345 168.332124)
				(xy 137.118854 168.300706) (xy 137.112521 168.268895) (xy 137.1125 168.267)
			)
		)
	)
	(zone
		(net 532)
		(net_name "/Backplane/PCIe_{x2}.RX0+")
		(layer "B.Cu")
		(name "$teardrop_padvia$")
		(hatch none 0.1)
		(priority 30535)
		(attr
			(teardrop
				(type padvia)
			)
		)
		(connect_pads yes
			(clearance 0)
		)
		(min_thickness 0.0254)
		(filled_areas_thickness no)
		(fill yes
			(thermal_gap 0.5)
			(thermal_bridge_width 0.5)
			(island_removal_mode 1)
			(island_area_min 10)
		)
		(polygon
			(pts
				(xy 270.432504 158.1065) (xy 270.594035 158.101105) (xy 270.678445 158.097554) (xy 270.78014 158.102177)
				(xy 270.801 157.8815) (xy 270.651147 157.718268) (xy 270.597007 157.786935) (xy 270.587115 157.803393)
				(xy 270.562615 157.842065) (xy 270.533109 157.874279) (xy 270.491953 157.896327) (xy 270.432504 157.9045)
			)
		)
	)
	(zone
		(net 945)
		(net_name "/GPIO expander/GPIOEX5")
		(layer "B.Cu")
		(name "$teardrop_padvia$")
		(hatch none 0.1)
		(priority 30932)
		(attr
			(teardrop
				(type padvia)
			)
		)
		(connect_pads yes
			(clearance 0)
		)
		(min_thickness 0.0254)
		(filled_areas_thickness no)
		(fill yes
			(thermal_gap 0.5)
			(thermal_bridge_width 0.5)
			(island_removal_mode 1)
			(island_area_min 10)
		)
		(polygon
			(pts
				(xy 122.3255 147.5465) (xy 122.318892 147.546603) (xy 122.278514 147.541089) (xy 122.259695 147.526247)
				(xy 122.245997 147.496824) (xy 121.837 147.611) (xy 122.257194 147.717694) (xy 122.266166 147.691467)
				(xy 122.28013 147.677426) (xy 122.318231 147.671303) (xy 122.3255 147.6715)
			)
		)
	)
	(zone
		(net 2)
		(net_name "+3V3")
		(layer "B.Cu")
		(name "$teardrop_padvia$")
		(hatch none 0.1)
		(priority 30818)
		(attr
			(teardrop
				(type padvia)
			)
		)
		(connect_pads yes
			(clearance 0)
		)
		(min_thickness 0.0254)
		(filled_areas_thickness no)
		(fill yes
			(thermal_gap 0.5)
			(thermal_bridge_width 0.5)
			(island_removal_mode 1)
			(island_area_min 10)
		)
		(polygon
			(pts
				(xy 193.344395 140.204031) (xy 193.32322 140.176107) (xy 193.316749 140.150678) (xy 193.334006 140.108242)
				(xy 193.383078 140.059867) (xy 193.452961 139.986767) (xy 193.265173 139.861057) (xy 193.078799 139.986767)
				(xy 193.135545 140.096994) (xy 193.14242 140.11486) (xy 193.179175 140.196173) (xy 193.256008 140.292418)
			)
		)
	)
	(zone
		(net 53)
		(net_name "/2xSFP+/SH")
		(layer "B.Cu")
		(name "$teardrop_padvia$")
		(hatch none 0.1)
		(priority 30017)
		(attr
			(teardrop
				(type padvia)
			)
		)
		(connect_pads yes
			(clearance 0)
		)
		(min_thickness 0.0254)
		(filled_areas_thickness no)
		(fill yes
			(thermal_gap 0.5)
			(thermal_bridge_width 0.5)
			(island_removal_mode 1)
			(island_area_min 10)
		)
		(polygon
			(pts
				(xy 124.6 156.520589) (xy 124.604874 156.396824) (xy 124.618996 156.291865) (xy 124.640089 156.207229)
				(xy 124.668095 156.133643) (xy 124.746201 156.00343) (xy 124.860058 155.868796) (xy 124.962896 155.750401)
				(xy 125.073602 155.601678) (xy 124.45 155.184) (xy 123.826398 155.601678) (xy 123.970593 155.790228)
				(xy 124.039942 155.868797) (xy 124.144416 155.991075) (xy 124.226718 156.122489) (xy 124.257616 156.200049)
				(xy 124.280646 156.290005) (xy 124.295032 156.395728) (xy 124.3 156.520589)
			)
		)
	)
	(zone
		(net 969)
		(net_name "/M.2 key M #1/M2_3V3")
		(layer "B.Cu")
		(name "$teardrop_padvia$")
		(hatch none 0.1)
		(priority 30277)
		(attr
			(teardrop
				(type padvia)
			)
		)
		(connect_pads yes
			(clearance 0)
		)
		(min_thickness 0.0254)
		(filled_areas_thickness no)
		(fill yes
			(thermal_gap 0.5)
			(thermal_bridge_width 0.5)
			(island_removal_mode 1)
			(island_area_min 10)
		)
		(polygon
			(pts
				(xy 178.260677 96.96) (xy 178.103106 96.953069) (xy 177.989578 96.924549) (xy 177.947778 96.9075)
				(xy 177.859 97.11) (xy 177.947778 97.3125) (xy 178.043817 97.278118) (xy 178.145689 97.2629) (xy 178.260677 97.26)
			)
		)
	)
	(zone
		(net 206)
		(net_name "/Backplane/USB.D+")
		(layer "B.Cu")
		(name "$teardrop_padvia$")
		(hatch none 0.1)
		(priority 30049)
		(attr
			(teardrop
				(type padvia)
			)
		)
		(connect_pads yes
			(clearance 0)
		)
		(min_thickness 0.0254)
		(filled_areas_thickness no)
		(fill yes
			(thermal_gap 0.5)
			(thermal_bridge_width 0.5)
			(island_removal_mode 1)
			(island_area_min 10)
		)
		(polygon
			(pts
				(xy 317.863751 166.8125) (xy 318.257031 166.797058) (xy 318.701327 166.777406) (xy 318.963779 166.775825)
				(xy 319.259449 166.785) (xy 319.451 166.51) (xy 317.95 166.458932) (xy 317.950817 166.519448) (xy 317.942183 166.564613)
				(xy 317.927287 166.594774) (xy 317.907689 166.614309) (xy 317.863751 166.6275)
			)
		)
	)
	(zone
		(net 378)
		(net_name "/Com Express 7 Interfaces/USB1.D+")
		(layer "B.Cu")
		(name "$teardrop_padvia$")
		(hatch none 0.1)
		(priority 30579)
		(attr
			(teardrop
				(type padvia)
			)
		)
		(connect_pads yes
			(clearance 0)
		)
		(min_thickness 0.0254)
		(filled_areas_thickness no)
		(fill yes
			(thermal_gap 0.5)
			(thermal_bridge_width 0.5)
			(island_removal_mode 1)
			(island_area_min 10)
		)
		(polygon
			(pts
				(xy 159.009584 71.5175) (xy 158.964972 71.51276) (xy 158.931576 71.499582) (xy 158.88798 71.454799)
				(xy 158.865148 71.412179) (xy 158.83949 71.364337) (xy 158.802895 71.318311) (xy 158.649 71.4775)
				(xy 158.662438 71.698177) (xy 158.845142 71.698316) (xy 159.009584 71.7025)
			)
		)
	)
	(zone
		(net 313)
		(net_name "/2xUSB3.0+RJ45/USB_1.D+")
		(layer "B.Cu")
		(name "$teardrop_padvia$")
		(hatch none 0.1)
		(priority 30587)
		(attr
			(teardrop
				(type padvia)
			)
		)
		(connect_pads yes
			(clearance 0)
		)
		(min_thickness 0.0254)
		(filled_areas_thickness no)
		(fill yes
			(thermal_gap 0.5)
			(thermal_bridge_width 0.5)
			(island_removal_mode 1)
			(island_area_min 10)
		)
		(polygon
			(pts
				(xy 147.314679 115.126793) (xy 147.433916 115.240113) (xy 147.563205 115.369205) (xy 147.728749 115.222665)
				(xy 147.732491 115.001281) (xy 147.650181 115.014466) (xy 147.622096 115.023636) (xy 147.578512 115.036992)
				(xy 147.535897 115.041836) (xy 147.492231 115.030665) (xy 147.445494 114.995978)
			)
		)
	)
	(zone
		(net 957)
		(net_name "/PCIe redriver/PCIe_{I}_C.RX0+")
		(layer "B.Cu")
		(name "$teardrop_padvia$")
		(hatch none 0.1)
		(priority 30181)
		(attr
			(teardrop
				(type padvia)
			)
		)
		(connect_pads yes
			(clearance 0)
		)
		(min_thickness 0.0254)
		(filled_areas_thickness no)
		(fill yes
			(thermal_gap 0.5)
			(thermal_bridge_width 0.5)
			(island_removal_mode 1)
			(island_area_min 10)
		)
		(polygon
			(pts
				(xy 197.40032 136.988067) (xy 197.403377 137.024016) (xy 197.395899 137.060716) (xy 197.347077 137.141888)
				(xy 197.235638 137.252479) (xy 197.514884 137.391841) (xy 197.762905 137.187314) (xy 197.67482 137.112578)
				(xy 197.601587 137.004312) (xy 197.549481 136.870358) (xy 197.543154 136.845233)
			)
		)
	)
	(zone
		(net 288)
		(net_name "/2xUSB3.0+RJ45/~{GBE0_LINK_1000}")
		(layer "B.Cu")
		(name "$teardrop_padvia$")
		(hatch none 0.1)
		(priority 30602)
		(attr
			(teardrop
				(type padvia)
			)
		)
		(connect_pads yes
			(clearance 0)
		)
		(min_thickness 0.0254)
		(filled_areas_thickness no)
		(fill yes
			(thermal_gap 0.5)
			(thermal_bridge_width 0.5)
			(island_removal_mode 1)
			(island_area_min 10)
		)
		(polygon
			(pts
				(xy 124.328993 109.785605) (xy 124.259148 109.753257) (xy 124.221133 109.719015) (xy 124.187818 109.674647)
				(xy 124.163722 109.62496) (xy 124.149175 109.56838) (xy 124.147718 109.557027) (xy 123.879293 109.809293)
				(xy 124.163772 110.038946) (xy 124.172629 109.95966) (xy 124.190049 109.905329) (xy 124.20766 109.882403)
				(xy 124.229426 109.873385) (xy 124.240605 109.873993)
			)
		)
	)
	(zone
		(net 1)
		(net_name "GND")
		(layer "B.Cu")
		(name "$teardrop_padvia$")
		(hatch none 0.1)
		(priority 30394)
		(attr
			(teardrop
				(type padvia)
			)
		)
		(connect_pads yes
			(clearance 0)
		)
		(min_thickness 0.0254)
		(filled_areas_thickness no)
		(fill yes
			(thermal_gap 0.5)
			(thermal_bridge_width 0.5)
			(island_removal_mode 1)
			(island_area_min 10)
		)
		(polygon
			(pts
				(xy 199.201546 133.085066) (xy 199.141693 133.116435) (xy 199.099858 133.120831) (xy 199.052797 133.114755)
				(xy 199.007358 133.098853) (xy 198.960211 133.071703) (xy 198.941826 133.446184) (xy 199.316307 133.427799)
				(xy 199.285201 133.376232) (xy 199.265979 133.326887) (xy 199.257455 133.279726) (xy 199.259204 133.237695)
				(xy 199.270012 133.202253) (xy 199.28869 133.174722) (xy 199.289934 133.173454)
			)
		)
	)
	(zone
		(net 168)
		(net_name "Net-(J2A-RX_{LOS})")
		(layer "B.Cu")
		(name "$teardrop_padvia$")
		(hatch none 0.1)
		(priority 30142)
		(attr
			(teardrop
				(type padvia)
			)
		)
		(connect_pads yes
			(clearance 0)
		)
		(min_thickness 0.0254)
		(filled_areas_thickness no)
		(fill yes
			(thermal_gap 0.5)
			(thermal_bridge_width 0.5)
			(island_removal_mode 1)
			(island_area_min 10)
		)
		(polygon
			(pts
				(xy 144.823604 167.571993) (xy 144.86548 167.607108) (xy 144.905003 167.627589) (xy 144.977104 167.635258)
				(xy 145.071992 167.607694) (xy 145.166007 167.578405) (xy 145.218776 167.572533) (xy 145.276841 167.577794)
				(xy 145.350707 167.210707) (xy 144.982206 167.136841) (xy 144.975395 167.251619) (xy 144.979281 167.34037)
				(xy 144.982799 167.425694) (xy 144.977994 167.487822) (xy 144.970015 167.505586) (xy 144.957011 167.512032)
				(xy 144.911993 167.483604)
			)
		)
	)
	(zone
		(net 1)
		(net_name "GND")
		(layer "B.Cu")
		(name "$teardrop_padvia$")
		(hatch none 0.1)
		(priority 30293)
		(attr
			(teardrop
				(type padvia)
			)
		)
		(connect_pads yes
			(clearance 0)
		)
		(min_thickness 0.0254)
		(filled_areas_thickness no)
		(fill yes
			(thermal_gap 0.5)
			(thermal_bridge_width 0.5)
			(island_removal_mode 1)
			(island_area_min 10)
		)
		(polygon
			(pts
				(xy 152.547373 160.450496) (xy 152.539627 160.463304) (xy 152.530786 160.478366) (xy 152.518941 160.484633)
				(xy 152.502268 160.470966) (xy 152.478946 160.426228) (xy 152.249293 160.710707) (xy 152.566762 160.873777)
				(xy 152.585299 160.806869) (xy 152.637438 160.749085) (xy 152.699833 160.705913) (xy 152.759504 160.662627)
			)
		)
	)
	(zone
		(net 98)
		(net_name "/OCuLink/PCIe_{x4}.TX3-")
		(layer "B.Cu")
		(name "$teardrop_padvia$")
		(hatch none 0.1)
		(priority 30189)
		(attr
			(teardrop
				(type padvia)
			)
		)
		(connect_pads yes
			(clearance 0)
		)
		(min_thickness 0.0254)
		(filled_areas_thickness no)
		(fill yes
			(thermal_gap 0.5)
			(thermal_bridge_width 0.5)
			(island_removal_mode 1)
			(island_area_min 10)
		)
		(polygon
			(pts
				(xy 107.045071 158.7685) (xy 107.118327 158.74513) (xy 107.270463 158.700967) (xy 107.353293 158.690654)
				(xy 107.436769 158.697) (xy 107.414 158.377) (xy 107.118 158.272146) (xy 107.123839 158.397179)
				(xy 107.113687 158.486812) (xy 107.098361 158.525374) (xy 107.075399 158.551842) (xy 107.045071 158.5665)
			)
		)
	)
	(zone
		(net 960)
		(net_name "/PCIe redriver/PCIe_{I}_C.RX3+")
		(layer "B.Cu")
		(name "$teardrop_padvia$")
		(hatch none 0.1)
		(priority 30881)
		(attr
			(teardrop
				(type padvia)
			)
		)
		(connect_pads yes
			(clearance 0)
		)
		(min_thickness 0.0254)
		(filled_areas_thickness no)
		(fill yes
			(thermal_gap 0.5)
			(thermal_bridge_width 0.5)
			(island_removal_mode 1)
			(island_area_min 10)
		)
		(polygon
			(pts
				(xy 193.433111 139.177639) (xy 193.41342 139.168128) (xy 193.383772 139.152047) (xy 193.378684 139.137304)
				(xy 193.386799 139.115062) (xy 193.016272 138.903635) (xy 193.227699 139.274162) (xy 193.24955 139.266065)
				(xy 193.264175 139.270713) (xy 193.280765 139.300783) (xy 193.290276 139.320474)
			)
		)
	)
	(zone
		(net 1)
		(net_name "GND")
		(layer "B.Cu")
		(name "$teardrop_padvia$")
		(hatch none 0.1)
		(priority 30146)
		(attr
			(teardrop
				(type padvia)
			)
		)
		(connect_pads yes
			(clearance 0)
		)
		(min_thickness 0.0254)
		(filled_areas_thickness no)
		(fill yes
			(thermal_gap 0.5)
			(thermal_bridge_width 0.5)
			(island_removal_mode 1)
			(island_area_min 10)
		)
		(polygon
			(pts
				(xy 124.933472 149.18795) (xy 124.982738 149.146578) (xy 125.046173 149.110115) (xy 125.108896 149.087275)
				(xy 125.181243 149.073736) (xy 125.294244 149.075) (xy 125.220707 148.779293) (xy 124.9 148.716945)
				(xy 124.899773 148.838711) (xy 124.865341 148.94543) (xy 124.802211 149.035987) (xy 124.79205 149.046528)
			)
		)
	)
	(zone
		(net 653)
		(net_name "Net-(U43C-TESTEN)")
		(layer "B.Cu")
		(name "$teardrop_padvia$")
		(hatch none 0.1)
		(priority 30401)
		(attr
			(teardrop
				(type padvia)
			)
		)
		(connect_pads yes
			(clearance 0)
		)
		(min_thickness 0.0254)
		(filled_areas_thickness no)
		(fill yes
			(thermal_gap 0.5)
			(thermal_bridge_width 0.5)
			(island_removal_mode 1)
			(island_area_min 10)
		)
		(polygon
			(pts
				(xy 145.143 139.9975) (xy 145.083588 139.977727) (xy 145.027503 139.914453) (xy 145.005801 139.865828)
				(xy 144.991127 139.806468) (xy 144.989347 139.7945) (xy 144.729 140.06) (xy 144.989347 140.3255)
				(xy 145.002197 140.265361) (xy 145.022131 140.215477) (xy 145.048056 140.175358) (xy 145.077876 140.146345)
				(xy 145.109294 140.128854) (xy 145.141105 140.122521) (xy 145.143 140.1225)
			)
		)
	)
	(zone
		(net 428)
		(net_name "/2xSFP+/10GKR_SFP1.RX-")
		(layer "B.Cu")
		(name "$teardrop_padvia$")
		(hatch none 0.1)
		(priority 30827)
		(attr
			(teardrop
				(type padvia)
			)
		)
		(connect_pads yes
			(clearance 0)
		)
		(min_thickness 0.0254)
		(filled_areas_thickness no)
		(fill yes
			(thermal_gap 0.5)
			(thermal_bridge_width 0.5)
			(island_removal_mode 1)
			(island_area_min 10)
		)
		(polygon
			(pts
				(xy 195.450122 154.493285) (xy 195.429994 154.466464) (xy 195.423892 154.441792) (xy 195.439946 154.397284)
				(xy 195.460271 154.369325) (xy 195.488582 154.329137) (xy 195.507558 154.282014) (xy 195.286174 154.237412)
				(xy 195.123344 154.386666) (xy 195.279445 154.549084) (xy 195.336986 154.606421)
			)
		)
	)
	(zone
		(net 963)
		(net_name "/PCIe redriver/PCIe_{O}_C.TX0+")
		(layer "B.Cu")
		(name "$teardrop_padvia$")
		(hatch none 0.1)
		(priority 30831)
		(attr
			(teardrop
				(type padvia)
			)
		)
		(connect_pads yes
			(clearance 0)
		)
		(min_thickness 0.0254)
		(filled_areas_thickness no)
		(fill yes
			(thermal_gap 0.5)
			(thermal_bridge_width 0.5)
			(island_removal_mode 1)
			(island_area_min 10)
		)
		(polygon
			(pts
				(xy 119.9455 149.5355) (xy 119.939561 149.521386) (xy 119.931739 149.497504) (xy 119.939987 149.488876)
				(xy 119.963533 149.485493) (xy 119.901 149.047) (xy 119.776 149.14859) (xy 119.784887 149.276397)
				(xy 119.761205 149.422027) (xy 119.7435 149.5355)
			)
		)
	)
	(zone
		(net 204)
		(net_name "/Backplane/USB.D-")
		(layer "B.Cu")
		(name "$teardrop_padvia$")
		(hatch none 0.1)
		(priority 30956)
		(attr
			(teardrop
				(type padvia)
			)
		)
		(connect_pads yes
			(clearance 0)
		)
		(min_thickness 0.0254)
		(filled_areas_thickness no)
		(fill yes
			(thermal_gap 0.5)
			(thermal_bridge_width 0.5)
			(island_removal_mode 1)
			(island_area_min 10)
		)
		(polygon
			(pts
				(xy 315.462 166.5555) (xy 315.381692 166.571252) (xy 315.293833 166.590671) (xy 315.245195 166.592154)
				(xy 315.193649 166.583) (xy 315.136 166.708) (xy 315.411774 166.771633) (xy 315.416254 166.7432)
				(xy 315.427265 166.733347) (xy 315.449475 166.73722) (xy 315.462 166.7405)
			)
		)
	)
	(zone
		(net 242)
		(net_name "/Com Express 7 Interfaces/PCIe_{B2Bx4}.TX3+")
		(layer "B.Cu")
		(name "$teardrop_padvia$")
		(hatch none 0.1)
		(priority 30523)
		(attr
			(teardrop
				(type padvia)
			)
		)
		(connect_pads yes
			(clearance 0)
		)
		(min_thickness 0.0254)
		(filled_areas_thickness no)
		(fill yes
			(thermal_gap 0.5)
			(thermal_bridge_width 0.5)
			(island_removal_mode 1)
			(island_area_min 10)
		)
		(polygon
			(pts
				(xy 174.667496 95.3145) (xy 174.62071 95.309765) (xy 174.585258 95.296621) (xy 174.53706 95.251613)
				(xy 174.512884 95.213392) (xy 174.485514 95.170225) (xy 174.448852 95.128268) (xy 174.299 95.2915)
				(xy 174.31986 95.512177) (xy 174.420531 95.507548) (xy 174.503897 95.51098) (xy 174.505964 95.511105)
				(xy 174.667496 95.5165)
			)
		)
	)
	(zone
		(net 579)
		(net_name "/2xUSB3.0+RJ45/SH")
		(layer "B.Cu")
		(name "$teardrop_padvia$")
		(hatch none 0.1)
		(priority 30207)
		(attr
			(teardrop
				(type padvia)
			)
		)
		(connect_pads yes
			(clearance 0)
		)
		(min_thickness 0.0254)
		(filled_areas_thickness no)
		(fill yes
			(thermal_gap 0.5)
			(thermal_bridge_width 0.5)
			(island_removal_mode 1)
			(island_area_min 10)
		)
		(polygon
			(pts
				(xy 100.58 96.122) (xy 100.580338 96.13887) (xy 100.579759 96.183826) (xy 100.567941 96.231169)
				(xy 100.533362 96.273573) (xy 100.4645 96.303708) (xy 100.73 96.561) (xy 100.9955 96.303708) (xy 100.950731 96.288151)
				(xy 100.919115 96.267435) (xy 100.886381 96.216299) (xy 100.879662 96.13887) (xy 100.88 96.122)
			)
		)
	)
	(zone
		(net 961)
		(net_name "/PCIe redriver/PCIe_{O}_C.TX2+")
		(layer "B.Cu")
		(name "$teardrop_padvia$")
		(hatch none 0.1)
		(priority 30838)
		(attr
			(teardrop
				(type padvia)
			)
		)
		(connect_pads yes
			(clearance 0)
		)
		(min_thickness 0.0254)
		(filled_areas_thickness no)
		(fill yes
			(thermal_gap 0.5)
			(thermal_bridge_width 0.5)
			(island_removal_mode 1)
			(island_area_min 10)
		)
		(polygon
			(pts
				(xy 116.9465 149.5355) (xy 116.940542 149.52134) (xy 116.93269 149.497405) (xy 116.940913 149.488742)
				(xy 116.964425 149.485315) (xy 116.901 149.047) (xy 116.776 149.150651) (xy 116.78528 149.277829)
				(xy 116.76193 149.423096) (xy 116.7445 149.5355)
			)
		)
	)
	(zone
		(net 126)
		(net_name "/2xUSB3.0+RJ45/P2_D+")
		(layer "B.Cu")
		(name "$teardrop_padvia$")
		(hatch none 0.1)
		(priority 30025)
		(attr
			(teardrop
				(type padvia)
			)
		)
		(connect_pads yes
			(clearance 0)
		)
		(min_thickness 0.0254)
		(filled_areas_thickness no)
		(fill yes
			(thermal_gap 0.5)
			(thermal_bridge_width 0.5)
			(island_removal_mode 1)
			(island_area_min 10)
		)
		(polygon
			(pts
				(xy 111.15203 106.2725) (xy 111.041578 106.267641) (xy 110.948297 106.253631) (xy 110.872958 106.232633)
				(xy 110.807941 106.204876) (xy 110.692954 106.127075) (xy 110.586849 106.026814) (xy 110.473211 105.918327)
				(xy 110.32501 105.803758) (xy 109.949 106.365) (xy 110.32501 106.926242) (xy 110.488643 106.797839)
				(xy 110.586849 106.703186) (xy 110.689643 106.605736) (xy 110.802672 106.527844) (xy 110.870259 106.498323)
				(xy 110.949085 106.476201) (xy 111.042044 106.462315) (xy 111.15203 106.4575)
			)
		)
	)
	(zone
		(net 579)
		(net_name "/2xUSB3.0+RJ45/SH")
		(layer "B.Cu")
		(name "$teardrop_padvia$")
		(hatch none 0.1)
		(priority 30204)
		(attr
			(teardrop
				(type padvia)
			)
		)
		(connect_pads yes
			(clearance 0)
		)
		(min_thickness 0.0254)
		(filled_areas_thickness no)
		(fill yes
			(thermal_gap 0.5)
			(thermal_bridge_width 0.5)
			(island_removal_mode 1)
			(island_area_min 10)
		)
		(polygon
			(pts
				(xy 100.88 95.948) (xy 100.879662 95.93113) (xy 100.880241 95.886174) (xy 100.892059 95.838831)
				(xy 100.926638 95.796427) (xy 100.9955 95.766291) (xy 100.73 95.509) (xy 100.4645 95.766291) (xy 100.509269 95.781848)
				(xy 100.540885 95.802565) (xy 100.573619 95.853701) (xy 100.580338 95.93113) (xy 100.58 95.948)
			)
		)
	)
	(zone
		(net 65)
		(net_name "+12V")
		(layer "B.Cu")
		(name "$teardrop_padvia$")
		(hatch none 0.1)
		(priority 30731)
		(attr
			(teardrop
				(type padvia)
			)
		)
		(connect_pads yes
			(clearance 0)
		)
		(min_thickness 0.0254)
		(filled_areas_thickness no)
		(fill yes
			(thermal_gap 0.5)
			(thermal_bridge_width 0.5)
			(island_removal_mode 1)
			(island_area_min 10)
		)
		(polygon
			(pts
				(xy 287.5325 102.260677) (xy 287.537318 102.191236) (xy 287.55104 102.139912) (xy 287.597755 102.06437)
				(xy 287.607299 102.052229) (xy 287.657081 101.985003) (xy 287.47 101.859) (xy 287.282919 101.985003)
				(xy 287.332701 102.052231) (xy 287.387106 102.135397) (xy 287.40219 102.188251) (xy 287.4075 102.260677)
			)
		)
	)
	(zone
		(net 103)
		(net_name "/PCIe redriver/PCIe_{I}_C.RX1-")
		(layer "B.Cu")
		(name "$teardrop_padvia$")
		(hatch none 0.1)
		(priority 30193)
		(attr
			(teardrop
				(type padvia)
			)
		)
		(connect_pads yes
			(clearance 0)
		)
		(min_thickness 0.0254)
		(filled_areas_thickness no)
		(fill yes
			(thermal_gap 0.5)
			(thermal_bridge_width 0.5)
			(island_removal_mode 1)
			(island_area_min 10)
		)
		(polygon
			(pts
				(xy 197.951155 139.110095) (xy 198.036152 139.135755) (xy 198.131304 139.179978) (xy 198.196523 139.223476)
				(xy 198.255128 139.278386) (xy 198.293235 139.329846) (xy 198.497763 139.081826) (xy 198.358402 138.802579)
				(xy 198.272441 138.892522) (xy 198.199319 138.947934) (xy 198.157584 138.965643) (xy 198.117634 138.970447)
				(xy 198.09399 138.96726)
			)
		)
	)
	(zone
		(net 375)
		(net_name "/2xUSB3.0+RJ45/USB_2.D+")
		(layer "B.Cu")
		(name "$teardrop_padvia$")
		(hatch none 0.1)
		(priority 30590)
		(attr
			(teardrop
				(type padvia)
			)
		)
		(connect_pads yes
			(clearance 0)
		)
		(min_thickness 0.0254)
		(filled_areas_thickness no)
		(fill yes
			(thermal_gap 0.5)
			(thermal_bridge_width 0.5)
			(island_removal_mode 1)
			(island_area_min 10)
		)
		(polygon
			(pts
				(xy 133.123207 115.314679) (xy 133.009885 115.433917) (xy 132.880795 115.563204) (xy 133.027335 115.728749)
				(xy 133.248719 115.732491) (xy 133.235534 115.650181) (xy 133.226363 115.622097) (xy 133.213007 115.578512)
				(xy 133.208163 115.535897) (xy 133.219334 115.492231) (xy 133.254022 115.445494)
			)
		)
	)
	(zone
		(net 574)
		(net_name "Net-(U19-EN)")
		(layer "B.Cu")
		(name "$teardrop_padvia$")
		(hatch none 0.1)
		(priority 30402)
		(attr
			(teardrop
				(type padvia)
			)
		)
		(connect_pads yes
			(clearance 0)
		)
		(min_thickness 0.0254)
		(filled_areas_thickness no)
		(fill yes
			(thermal_gap 0.5)
			(thermal_bridge_width 0.5)
			(island_removal_mode 1)
			(island_area_min 10)
		)
		(polygon
			(pts
				(xy 309.887499 102.653) (xy 309.907272 102.593588) (xy 309.970546 102.537503) (xy 310.019171 102.515801)
				(xy 310.078531 102.501127) (xy 310.090499 102.499347) (xy 309.824999 102.239) (xy 309.559499 102.499347)
				(xy 309.619638 102.512197) (xy 309.669522 102.532131) (xy 309.709641 102.558056) (xy 309.738654 102.587876)
				(xy 309.756145 102.619294) (xy 309.762478 102.651105) (xy 309.762499 102.653)
			)
		)
	)
	(zone
		(net 1)
		(net_name "GND")
		(layer "B.Cu")
		(name "$teardrop_padvia$")
		(hatch none 0.1)
		(priority 30264)
		(attr
			(teardrop
				(type padvia)
			)
		)
		(connect_pads yes
			(clearance 0)
		)
		(min_thickness 0.0254)
		(filled_areas_thickness no)
		(fill yes
			(thermal_gap 0.5)
			(thermal_bridge_width 0.5)
			(island_removal_mode 1)
			(island_area_min 10)
		)
		(polygon
			(pts
				(xy 99.858677 160.45) (xy 99.701106 160.443069) (xy 99.587578 160.414549) (xy 99.545778 160.3975)
				(xy 99.457 160.6) (xy 99.545778 160.8025) (xy 99.641817 160.768118) (xy 99.743689 160.7529) (xy 99.858677 160.75)
			)
		)
	)
	(zone
		(net 203)
		(net_name "/Backplane/PCIe_{REF}.CK+")
		(layer "B.Cu")
		(name "$teardrop_padvia$")
		(hatch none 0.1)
		(priority 30489)
		(attr
			(teardrop
				(type padvia)
			)
		)
		(connect_pads yes
			(clearance 0)
		)
		(min_thickness 0.0254)
		(filled_areas_thickness no)
		(fill yes
			(thermal_gap 0.5)
			(thermal_bridge_width 0.5)
			(island_removal_mode 1)
			(island_area_min 10)
		)
		(polygon
			(pts
				(xy 312.268809 164.310908) (xy 312.239075 164.274477) (xy 312.223301 164.240114) (xy 312.221045 164.174209)
				(xy 312.230976 164.130087) (xy 312.242147 164.080211) (xy 312.245891 164.024618) (xy 312.024507 164.034079)
				(xy 311.883214 164.20487) (xy 311.957673 164.272783) (xy 312.014195 164.33416) (xy 312.015566 164.335707)
				(xy 312.125973 164.453744)
			)
		)
	)
	(zone
		(net 896)
		(net_name "Net-(J2B-RX_{LOS})")
		(layer "B.Cu")
		(name "$teardrop_padvia$")
		(hatch none 0.1)
		(priority 30430)
		(attr
			(teardrop
				(type padvia)
			)
		)
		(connect_pads yes
			(clearance 0)
		)
		(min_thickness 0.0254)
		(filled_areas_thickness no)
		(fill yes
			(thermal_gap 0.5)
			(thermal_bridge_width 0.5)
			(island_removal_mode 1)
			(island_area_min 10)
		)
		(polygon
			(pts
				(xy 139.9875 168.267) (xy 139.967727 168.326412) (xy 139.904453 168.382496) (xy 139.855828 168.404198)
				(xy 139.796469 168.418872) (xy 139.7845 168.420652) (xy 140.05 168.681) (xy 140.3155 168.420652)
				(xy 140.255362 168.407803) (xy 140.205478 168.387869) (xy 140.165358 168.361944) (xy 140.136345 168.332124)
				(xy 140.118854 168.300706) (xy 140.112521 168.268895) (xy 140.1125 168.267)
			)
		)
	)
	(zone
		(net 244)
		(net_name "/Com Express 7 Interfaces/PCIe_{B2Bx4}.RX2+")
		(layer "B.Cu")
		(name "$teardrop_padvia$")
		(hatch none 0.1)
		(priority 30307)
		(attr
			(teardrop
				(type padvia)
			)
		)
		(connect_pads yes
			(clearance 0)
		)
		(min_thickness 0.0254)
		(filled_areas_thickness no)
		(fill yes
			(thermal_gap 0.5)
			(thermal_bridge_width 0.5)
			(island_removal_mode 1)
			(island_area_min 10)
		)
		(polygon
			(pts
				(xy 175.39 96.961) (xy 175.404678 96.957463) (xy 175.434685 96.954192) (xy 175.445673 96.966143)
				(xy 175.45 96.995) (xy 176.201 96.86) (xy 175.45 96.725) (xy 175.445525 96.754204) (xy 175.434203 96.765997)
				(xy 175.404678 96.762537) (xy 175.39 96.759)
			)
		)
	)
	(zone
		(net 957)
		(net_name "/PCIe redriver/PCIe_{I}_C.RX0+")
		(layer "B.Cu")
		(name "$teardrop_padvia$")
		(hatch none 0.1)
		(priority 30880)
		(attr
			(teardrop
				(type padvia)
			)
		)
		(connect_pads yes
			(clearance 0)
		)
		(min_thickness 0.0254)
		(filled_areas_thickness no)
		(fill yes
			(thermal_gap 0.5)
			(thermal_bridge_width 0.5)
			(island_removal_mode 1)
			(island_area_min 10)
		)
		(polygon
			(pts
				(xy 196.615092 135.995659) (xy 196.595401 135.986148) (xy 196.565753 135.970067) (xy 196.560665 135.955324)
				(xy 196.56878 135.933082) (xy 196.198253 135.721655) (xy 196.40968 136.092182) (xy 196.431531 136.084085)
				(xy 196.446156 136.088733) (xy 196.462746 136.118803) (xy 196.472257 136.138494)
			)
		)
	)
	(zone
		(net 868)
		(net_name "/Backplane/PCIe_{x2}.TX1+")
		(layer "B.Cu")
		(name "$teardrop_padvia$")
		(hatch none 0.1)
		(priority 31003)
		(attr
			(teardrop
				(type padvia)
			)
		)
		(connect_pads yes
			(clearance 0)
		)
		(min_thickness 0.0254)
		(filled_areas_thickness no)
		(fill yes
			(thermal_gap 0.5)
			(thermal_bridge_width 0.5)
			(island_removal_mode 1)
			(island_area_min 10)
		)
		(polygon
			(pts
				(xy 314.69 161.307) (xy 314.669352 161.314199) (xy 314.637017 161.323792) (xy 314.622994 161.316965)
				(xy 314.613005 161.2955) (xy 314.364 161.408) (xy 314.613005 161.5205) (xy 314.62273 161.499324)
				(xy 314.636358 161.492269) (xy 314.669352 161.501801) (xy 314.69 161.509)
			)
		)
	)
	(zone
		(net 876)
		(net_name "Net-(J2B-TX_{FAULT})")
		(layer "B.Cu")
		(name "$teardrop_padvia$")
		(hatch none 0.1)
		(priority 30422)
		(attr
			(teardrop
				(type padvia)
			)
		)
		(connect_pads yes
			(clearance 0)
		)
		(min_thickness 0.0254)
		(filled_areas_thickness no)
		(fill yes
			(thermal_gap 0.5)
			(thermal_bridge_width 0.5)
			(island_removal_mode 1)
			(island_area_min 10)
		)
		(polygon
			(pts
				(xy 141.9875 168.267) (xy 141.967727 168.326412) (xy 141.904453 168.382496) (xy 141.855828 168.404198)
				(xy 141.796469 168.418872) (xy 141.7845 168.420652) (xy 142.05 168.681) (xy 142.3155 168.420652)
				(xy 142.255362 168.407803) (xy 142.205478 168.387869) (xy 142.165358 168.361944) (xy 142.136345 168.332124)
				(xy 142.118854 168.300706) (xy 142.112521 168.268895) (xy 142.1125 168.267)
			)
		)
	)
	(zone
		(net 78)
		(net_name "+1V8")
		(layer "B.Cu")
		(name "$teardrop_padvia$")
		(hatch none 0.1)
		(priority 30389)
		(attr
			(teardrop
				(type padvia)
			)
		)
		(connect_pads yes
			(clearance 0)
		)
		(min_thickness 0.0254)
		(filled_areas_thickness no)
		(fill yes
			(thermal_gap 0.5)
			(thermal_bridge_width 0.5)
			(island_removal_mode 1)
			(island_area_min 10)
		)
		(polygon
			(pts
				(xy 140.2825 139.798) (xy 140.302469 139.735134) (xy 140.328921 139.703156) (xy 140.366332 139.674642)
				(xy 140.413527 139.652118) (xy 140.471167 139.636907) (xy 140.471798 139.636798) (xy 140.22 139.359)
				(xy 139.968202 139.636798) (xy 140.023635 139.651095) (xy 140.06952 139.672175) (xy 140.107201 139.69954)
				(xy 140.134434 139.730448) (xy 140.151472 139.763735) (xy 140.157489 139.796566) (xy 140.1575 139.798)
			)
		)
	)
	(zone
		(net 200)
		(net_name "/OCuLink/~{PERST_D0}")
		(layer "B.Cu")
		(name "$teardrop_padvia$")
		(hatch none 0.1)
		(priority 31035)
		(attr
			(teardrop
				(type padvia)
			)
		)
		(connect_pads yes
			(clearance 0)
		)
		(min_thickness 0.0254)
		(filled_areas_thickness no)
		(fill yes
			(thermal_gap 0.5)
			(thermal_bridge_width 0.5)
			(island_removal_mode 1)
			(island_area_min 10)
		)
		(polygon
			(pts
				(xy 104.705002 162.0495) (xy 104.69868 162.049596) (xy 104.659177 162.044011) (xy 104.640955 162.029078)
				(xy 104.628007 161.9995) (xy 104.379002 162.112) (xy 104.628007 162.2245) (xy 104.639123 162.197506)
				(xy 104.65465 162.182405) (xy 104.69868 162.174404) (xy 104.705002 162.1745)
			)
		)
	)
	(zone
		(net 889)
		(net_name "/Power/PG_{3V3}")
		(layer "B.Cu")
		(name "$teardrop_padvia$")
		(hatch none 0.1)
		(priority 30425)
		(attr
			(teardrop
				(type padvia)
			)
		)
		(connect_pads yes
			(clearance 0)
		)
		(min_thickness 0.0254)
		(filled_areas_thickness no)
		(fill yes
			(thermal_gap 0.5)
			(thermal_bridge_width 0.5)
			(island_removal_mode 1)
			(island_area_min 10)
		)
		(polygon
			(pts
				(xy 312.962499 105.257) (xy 312.942726 105.316412) (xy 312.879452 105.372496) (xy 312.830827 105.394198)
				(xy 312.771468 105.408872) (xy 312.759499 105.410652) (xy 313.024999 105.671) (xy 313.290499 105.410652)
				(xy 313.230361 105.397803) (xy 313.180477 105.377869) (xy 313.140357 105.351944) (xy 313.111344 105.322124)
				(xy 313.093853 105.290706) (xy 313.08752 105.258895) (xy 313.087499 105.257)
			)
		)
	)
	(zone
		(net 351)
		(net_name "Net-(J12D-LPC_AD2{slash}ESPI_IO_2)")
		(layer "B.Cu")
		(name "$teardrop_padvia$")
		(hatch none 0.1)
		(priority 30102)
		(attr
			(teardrop
				(type padvia)
			)
		)
		(connect_pads yes
			(clearance 0)
		)
		(min_thickness 0.0254)
		(filled_areas_thickness no)
		(fill yes
			(thermal_gap 0.5)
			(thermal_bridge_width 0.5)
			(island_removal_mode 1)
			(island_area_min 10)
		)
		(polygon
			(pts
				(xy 176.917794 164.9875) (xy 176.835734 164.982685) (xy 176.770388 164.968981) (xy 176.677121 164.922424)
				(xy 176.598658 164.854214) (xy 176.537159 164.798058) (xy 176.458339 164.738199) (xy 176.249 165.05)
				(xy 176.458339 165.361801) (xy 176.578517 165.26478) (xy 176.598657 165.245787) (xy 176.657541 165.192634)
				(xy 176.721624 165.150409) (xy 176.804008 165.122551) (xy 176.917794 165.1125)
			)
		)
	)
	(zone
		(net 60)
		(net_name "/OCuLink/V_{ACT_RX}0")
		(layer "B.Cu")
		(name "$teardrop_padvia$")
		(hatch none 0.1)
		(priority 30077)
		(attr
			(teardrop
				(type padvia)
			)
		)
		(connect_pads yes
			(clearance 0)
		)
		(min_thickness 0.0254)
		(filled_areas_thickness no)
		(fill yes
			(thermal_gap 0.5)
			(thermal_bridge_width 0.5)
			(island_removal_mode 1)
			(island_area_min 10)
		)
		(polygon
			(pts
				(xy 104.1 169.42) (xy 104.106939 169.360279) (xy 104.135514 169.297956) (xy 104.165032 169.26657)
				(xy 104.206823 169.240086) (xy 104.303137 169.213137) (xy 103.95 168.759) (xy 103.596863 169.213137)
				(xy 103.65633 169.225794) (xy 103.703161 169.245189) (xy 103.764802 169.298393) (xy 103.794809 169.36783)
				(xy 103.8 169.42)
			)
		)
	)
	(zone
		(net 1)
		(net_name "GND")
		(layer "B.Cu")
		(name "$teardrop_padvia$")
		(hatch none 0.1)
		(priority 30291)
		(attr
			(teardrop
				(type padvia)
			)
		)
		(connect_pads yes
			(clearance 0)
		)
		(min_thickness 0.0254)
		(filled_areas_thickness no)
		(fill yes
			(thermal_gap 0.5)
			(thermal_bridge_width 0.5)
			(island_removal_mode 1)
			(island_area_min 10)
		)
		(polygon
			(pts
				(xy 125.282 148.238) (xy 125.28821 148.191789) (xy 125.311677 148.14339) (xy 125.339584 148.115034)
				(xy 125.37981 148.091988) (xy 125.433798 148.076798) (xy 125.182 147.799) (xy 124.930202 148.076798)
				(xy 124.979054 148.089931) (xy 125.016564 148.109335) (xy 125.063987 148.161945) (xy 125.081743 148.228446)
				(xy 125.082 148.238)
			)
		)
	)
	(zone
		(net 1)
		(net_name "GND")
		(layer "B.Cu")
		(hatch edge 0.5)
		(priority 43)
		(connect_pads yes
			(clearance 0.15)
		)
		(min_thickness 0.25)
		(filled_areas_thickness no)
		(fill yes
			(thermal_gap 0.5)
			(thermal_bridge_width 0.5)
		)
		(polygon
			(pts
				(xy 149.93 160.045) (xy 151.6 160.045) (xy 151.6 159.325) (xy 149.93 159.325)
			)
		)
	)
	(zone
		(net 484)
		(net_name "Net-(J12K-10G_PHY_CAP_01)")
		(layer "B.Cu")
		(name "$teardrop_padvia$")
		(hatch none 0.1)
		(priority 30676)
		(attr
			(teardrop
				(type padvia)
			)
		)
		(connect_pads yes
			(clearance 0)
		)
		(min_thickness 0.0254)
		(filled_areas_thickness no)
		(fill yes
			(thermal_gap 0.5)
			(thermal_bridge_width 0.5)
			(island_removal_mode 1)
			(island_area_min 10)
		)
		(polygon
			(pts
				(xy 192.844672 149.556285) (xy 192.822821 149.52767) (xy 192.816327 149.502109) (xy 192.834325 149.46172)
				(xy 192.894779 149.410683) (xy 192.944823 149.371426) (xy 192.987081 149.325003) (xy 192.799293 149.199293)
				(xy 192.612919 149.325003) (xy 192.654906 149.416211) (xy 192.665967 149.466731) (xy 192.688862 149.550241)
				(xy 192.714181 149.595178) (xy 192.756285 149.644672)
			)
		)
	)
	(zone
		(net 124)
		(net_name "/2xUSB3.0+RJ45/P1_D+")
		(layer "B.Cu")
		(name "$teardrop_padvia$")
		(hatch none 0.1)
		(priority 30594)
		(attr
			(teardrop
				(type padvia)
			)
		)
		(connect_pads yes
			(clearance 0)
		)
		(min_thickness 0.0254)
		(filled_areas_thickness no)
		(fill yes
			(thermal_gap 0.5)
			(thermal_bridge_width 0.5)
			(island_removal_mode 1)
			(island_area_min 10)
		)
		(polygon
			(pts
				(xy 104.847325 105.4625) (xy 104.682882 105.466684) (xy 104.500179 105.466823) (xy 104.486741 105.6875)
				(xy 104.640636 105.846688) (xy 104.689515 105.779162) (xy 104.702889 105.75282) (xy 104.724264 105.712557)
				(xy 104.750972 105.678998) (xy 104.789748 105.656021) (xy 104.847325 105.6475)
			)
		)
	)
	(zone
		(net 1)
		(net_name "GND")
		(layer "B.Cu")
		(name "$teardrop_padvia$")
		(hatch none 0.1)
		(priority 30473)
		(attr
			(teardrop
				(type padvia)
			)
		)
		(connect_pads yes
			(clearance 0)
		)
		(min_thickness 0.0254)
		(filled_areas_thickness no)
		(fill yes
			(thermal_gap 0.5)
			(thermal_bridge_width 0.5)
			(island_removal_mode 1)
			(island_area_min 10)
		)
		(polygon
			(pts
				(xy 99.7 84.210677) (xy 99.704713 84.132764) (xy 99.7177 84.07398) (xy 99.759802 83.982947) (xy 99.8025 83.897778)
				(xy 99.6 83.809) (xy 99.3975 83.897778) (xy 99.440198 83.982949) (xy 99.482867 84.075783) (xy 99.495444 84.133922)
				(xy 99.5 84.210677)
			)
		)
	)
	(zone
		(net 52)
		(net_name "+5V")
		(layer "B.Cu")
		(name "$teardrop_padvia$")
		(hatch none 0.1)
		(priority 30431)
		(attr
			(teardrop
				(type padvia)
			)
		)
		(connect_pads yes
			(clearance 0)
		)
		(min_thickness 0.0254)
		(filled_areas_thickness no)
		(fill yes
			(thermal_gap 0.5)
			(thermal_bridge_width 0.5)
			(island_removal_mode 1)
			(island_area_min 10)
		)
		(polygon
			(pts
				(xy 309.762499 100.867) (xy 309.742726 100.926412) (xy 309.679452 100.982496) (xy 309.630827 101.004198)
				(xy 309.571468 101.018872) (xy 309.559499 101.020652) (xy 309.824999 101.281) (xy 310.090499 101.020652)
				(xy 310.030361 101.007803) (xy 309.980477 100.987869) (xy 309.940357 100.961944) (xy 309.911344 100.932124)
				(xy 309.893853 100.900706) (xy 309.88752 100.868895) (xy 309.887499 100.867)
			)
		)
	)
	(zone
		(net 655)
		(net_name "Net-(U43C-PRTAD0)")
		(layer "B.Cu")
		(name "$teardrop_padvia$")
		(hatch none 0.1)
		(priority 30352)
		(attr
			(teardrop
				(type padvia)
			)
		)
		(connect_pads yes
			(clearance 0)
		)
		(min_thickness 0.0254)
		(filled_areas_thickness no)
		(fill yes
			(thermal_gap 0.5)
			(thermal_bridge_width 0.5)
			(island_removal_mode 1)
			(island_area_min 10)
		)
		(polygon
			(pts
				(xy 157.4825 141.798) (xy 157.502469 141.735134) (xy 157.528921 141.703156) (xy 157.566332 141.674642)
				(xy 157.613527 141.652118) (xy 157.671167 141.636907) (xy 157.671798 141.636798) (xy 157.42 141.359)
				(xy 157.168202 141.636798) (xy 157.223635 141.651095) (xy 157.26952 141.672175) (xy 157.307201 141.69954)
				(xy 157.334434 141.730448) (xy 157.351472 141.763735) (xy 157.357489 141.796566) (xy 157.3575 141.798)
			)
		)
	)
	(zone
		(net 1)
		(net_name "GND")
		(layer "B.Cu")
		(name "$teardrop_padvia$")
		(hatch none 0.1)
		(priority 30250)
		(attr
			(teardrop
				(type padvia)
			)
		)
		(connect_pads yes
			(clearance 0)
		)
		(min_thickness 0.0254)
		(filled_areas_thickness no)
		(fill yes
			(thermal_gap 0.5)
			(thermal_bridge_width 0.5)
			(island_removal_mode 1)
			(island_area_min 10)
		)
		(polygon
			(pts
				(xy 176.779323 104.01) (xy 176.9369 104.016932) (xy 177.050434 104.045456) (xy 177.092222 104.0625)
				(xy 177.181 103.86) (xy 177.092222 103.6575) (xy 176.996177 103.691883) (xy 176.894296 103.707101)
				(xy 176.779323 103.71)
			)
		)
	)
	(zone
		(net 433)
		(net_name "/2xSFP+/10GKR_SFP0.RX-")
		(layer "B.Cu")
		(name "$teardrop_padvia$")
		(hatch none 0.1)
		(priority 30608)
		(attr
			(teardrop
				(type padvia)
			)
		)
		(connect_pads yes
			(clearance 0)
		)
		(min_thickness 0.0254)
		(filled_areas_thickness no)
		(fill yes
			(thermal_gap 0.5)
			(thermal_bridge_width 0.5)
			(island_removal_mode 1)
			(island_area_min 10)
		)
		(polygon
			(pts
				(xy 197.239958 159.37) (xy 197.283018 159.374764) (xy 197.314472 159.388112) (xy 197.352895 159.432825)
				(xy 197.372983 159.478502) (xy 197.412919 159.560003) (xy 197.601 159.435) (xy 197.594885 159.214323)
				(xy 197.415789 159.213027) (xy 197.239958 159.21)
			)
		)
	)
	(zone
		(net 205)
		(net_name "/Backplane/PCIe_{REF}.CK-")
		(layer "B.Cu")
		(name "$teardrop_padvia$")
		(hatch none 0.1)
		(priority 30972)
		(attr
			(teardrop
				(type padvia)
			)
		)
		(connect_pads yes
			(clearance 0)
		)
		(min_thickness 0.0254)
		(filled_areas_thickness no)
		(fill yes
			(thermal_gap 0.5)
			(thermal_bridge_width 0.5)
			(island_removal_mode 1)
			(island_area_min 10)
		)
		(polygon
			(pts
				(xy 315.436125 165.05546) (xy 315.367843 165.072323) (xy 315.291221 165.093566) (xy 315.246554 165.095153)
				(xy 315.196789 165.085) (xy 315.136001 165.210023) (xy 315.411407 165.275478) (xy 315.415806 165.245958)
				(xy 315.425565 165.245693) (xy 315.431861 165.25116) (xy 315.440808 165.257404)
			)
		)
	)
	(zone
		(net 106)
		(net_name "/OCuLink/PCIe_{x4}.TX3+")
		(layer "B.Cu")
		(name "$teardrop_padvia$")
		(hatch none 0.1)
		(priority 30174)
		(attr
			(teardrop
				(type padvia)
			)
		)
		(connect_pads yes
			(clearance 0)
		)
		(min_thickness 0.0254)
		(filled_areas_thickness no)
		(fill yes
			(thermal_gap 0.5)
			(thermal_bridge_width 0.5)
			(island_removal_mode 1)
			(island_area_min 10)
		)
		(polygon
			(pts
				(xy 107.048621 159.1575) (xy 107.076112 159.17285) (xy 107.096919 159.196669) (xy 107.120457 159.27159)
				(xy 107.12101 159.419866) (xy 107.118 159.456387) (xy 107.414 159.355571) (xy 107.442221 159.035571)
				(xy 107.330981 159.039998) (xy 107.199034 159.011109) (xy 107.094025 158.972851) (xy 107.048621 158.9555)
			)
		)
	)
	(zone
		(net 173)
		(net_name "/2xSFP+/SFI0.TX-")
		(layer "B.Cu")
		(name "$teardrop_padvia$")
		(hatch none 0.1)
		(priority 30631)
		(attr
			(teardrop
				(type padvia)
			)
		)
		(connect_pads yes
			(clearance 0)
		)
		(min_thickness 0.0254)
		(filled_areas_thickness no)
		(fill yes
			(thermal_gap 0.5)
			(thermal_bridge_width 0.5)
			(island_removal_mode 1)
			(island_area_min 10)
		)
		(polygon
			(pts
				(xy 146.835 147.977084) (xy 146.832432 147.797777) (xy 146.830677 147.632143) (xy 146.61 147.629)
				(xy 146.484997 147.817081) (xy 146.569781 147.855729) (xy 146.610597 147.871388) (xy 146.644058 147.892373)
				(xy 146.666685 147.925376) (xy 146.675 147.977084)
			)
		)
	)
	(zone
		(net 867)
		(net_name "/Backplane/PCIe_{x2}.TX0-")
		(layer "B.Cu")
		(name "$teardrop_padvia$")
		(hatch none 0.1)
		(priority 31016)
		(attr
			(teardrop
				(type padvia)
			)
		)
		(connect_pads yes
			(clearance 0)
		)
		(min_thickness 0.0254)
		(filled_areas_thickness no)
		(fill yes
			(thermal_gap 0.5)
			(thermal_bridge_width 0.5)
			(island_removal_mode 1)
			(island_area_min 10)
		)
		(polygon
			(pts
				(xy 314.69 160.309) (xy 314.669352 160.316199) (xy 314.637017 160.325792) (xy 314.622994 160.318965)
				(xy 314.613005 160.2975) (xy 314.364 160.41) (xy 314.613005 160.5225) (xy 314.62273 160.501324)
				(xy 314.636358 160.494269) (xy 314.669352 160.503801) (xy 314.69 160.511)
			)
		)
	)
	(zone
		(net 889)
		(net_name "/Power/PG_{3V3}")
		(layer "B.Cu")
		(name "$teardrop_padvia$")
		(hatch none 0.1)
		(priority 30220)
		(attr
			(teardrop
				(type padvia)
			)
		)
		(connect_pads yes
			(clearance 0)
		)
		(min_thickness 0.0254)
		(filled_areas_thickness no)
		(fill yes
			(thermal_gap 0.5)
			(thermal_bridge_width 0.5)
			(island_removal_mode 1)
			(island_area_min 10)
		)
		(polygon
			(pts
				(xy 313.414443 105.971056) (xy 313.36459 105.893239) (xy 313.33647 105.771796) (xy 313.335256 105.697524)
				(xy 313.344507 105.617238) (xy 313.344999 105.614526) (xy 313.024292 105.669293) (xy 312.944525 105.965)
				(xy 313.030965 105.961462) (xy 313.110598 105.967546) (xy 313.183137 105.982581) (xy 313.245951 106.005544)
				(xy 313.326055 106.059444)
			)
		)
	)
	(zone
		(net 59)
		(net_name "/OCuLink/V_{ACT_TX}0")
		(layer "B.Cu")
		(name "$teardrop_padvia$")
		(hatch none 0.1)
		(priority 30080)
		(attr
			(teardrop
				(type padvia)
			)
		)
		(connect_pads yes
			(clearance 0)
		)
		(min_thickness 0.0254)
		(filled_areas_thickness no)
		(fill yes
			(thermal_gap 0.5)
			(thermal_bridge_width 0.5)
			(island_removal_mode 1)
			(island_area_min 10)
		)
		(polygon
			(pts
				(xy 103.81 156.2) (xy 103.803563 156.255253) (xy 103.778506 156.312785) (xy 103.750003 156.3456)
				(xy 103.709103 156.373876) (xy 103.660555 156.393575) (xy 103.599115 156.406567) (xy 103.596863 156.406863)
				(xy 103.95 156.861) (xy 104.303137 156.406863) (xy 104.246065 156.394305) (xy 104.201327 156.375031)
				(xy 104.142803 156.322023) (xy 104.114654 156.252194) (xy 104.11 156.2)
			)
		)
	)
	(zone
		(net 1)
		(net_name "GND")
		(layer "B.Cu")
		(name "$teardrop_padvia$")
		(hatch none 0.1)
		(priority 30457)
		(attr
			(teardrop
				(type padvia)
			)
		)
		(connect_pads yes
			(clearance 0)
		)
		(min_thickness 0.0254)
		(filled_areas_thickness no)
		(fill yes
			(thermal_gap 0.5)
			(thermal_bridge_width 0.5)
			(island_removal_mode 1)
			(island_area_min 10)
		)
		(polygon
			(pts
				(xy 143.357 142.1225) (xy 143.416412 142.142273) (xy 143.472497 142.205547) (xy 143.494199 142.254172)
				(xy 143.508873 142.313531) (xy 143.510653 142.3255) (xy 143.771 142.06) (xy 143.510653 141.7945)
				(xy 143.497804 141.854638) (xy 143.47787 141.904522) (xy 143.451945 141.944641) (xy 143.422125 141.973654)
				(xy 143.390707 141.991146) (xy 143.358896 141.997479) (xy 143.357 141.9975)
			)
		)
	)
	(zone
		(net 206)
		(net_name "/Backplane/USB.D+")
		(layer "B.Cu")
		(name "$teardrop_padvia$")
		(hatch none 0.1)
		(priority 30583)
		(attr
			(teardrop
				(type padvia)
			)
		)
		(connect_pads yes
			(clearance 0)
		)
		(min_thickness 0.0254)
		(filled_areas_thickness no)
		(fill yes
			(thermal_gap 0.5)
			(thermal_bridge_width 0.5)
			(island_removal_mode 1)
			(island_area_min 10)
		)
		(polygon
			(pts
				(xy 226.354022 145.204506) (xy 226.325828 145.169609) (xy 226.311532 145.136676) (xy 226.312371 145.074183)
				(xy 226.326363 145.027902) (xy 226.34205 144.975929) (xy 226.348719 144.917508) (xy 226.127335 144.921251)
				(xy 225.980795 145.086795) (xy 226.109886 145.216083) (xy 226.223207 145.335321)
			)
		)
	)
	(zone
		(net 1)
		(net_name "GND")
		(layer "B.Cu")
		(hatch edge 0.5)
		(priority 43)
		(connect_pads yes
			(clearance 0.15)
		)
		(min_thickness 0.25)
		(filled_areas_thickness no)
		(fill yes
			(thermal_gap 0.5)
			(thermal_bridge_width 0.5)
		)
		(polygon
			(pts
				(xy 136.9 164.11) (xy 136.9 161.06) (xy 135.81 161.06) (xy 135.810094 162.130094) (xy 136.18 162.45)
				(xy 136.18 164.11)
			)
		)
	)
	(zone
		(net 880)
		(net_name "/2xSFP+/SFI1.TX-")
		(layer "B.Cu")
		(name "$teardrop_padvia$")
		(hatch none 0.1)
		(priority 30062)
		(attr
			(teardrop
				(type padvia)
			)
		)
		(connect_pads yes
			(clearance 0)
		)
		(min_thickness 0.0254)
		(filled_areas_thickness no)
		(fill yes
			(thermal_gap 0.5)
			(thermal_bridge_width 0.5)
			(island_removal_mode 1)
			(island_area_min 10)
		)
		(polygon
			(pts
				(xy 139.494262 165.39) (xy 139.584366 165.394831) (xy 139.657051 165.408647) (xy 139.761568 165.455698)
				(xy 139.864552 165.540604) (xy 139.933613 165.601857) (xy 140.021105 165.667532) (xy 140.261 165.31)
				(xy 140.021105 164.952468) (xy 139.887383 165.058548) (xy 139.864551 165.079396) (xy 139.795571 165.139701)
				(xy 139.721036 165.187385) (xy 139.625685 165.218726) (xy 139.494262 165.23)
			)
		)
	)
	(zone
		(net 1)
		(net_name "GND")
		(layer "B.Cu")
		(name "$teardrop_padvia$")
		(hatch none 0.1)
		(priority 30246)
		(attr
			(teardrop
				(type padvia)
			)
		)
		(connect_pads yes
			(clearance 0)
		)
		(min_thickness 0.0254)
		(filled_areas_thickness no)
		(fill yes
			(thermal_gap 0.5)
			(thermal_bridge_width 0.5)
			(island_removal_mode 1)
			(island_area_min 10)
		)
		(polygon
			(pts
				(xy 176.779323 107.01) (xy 176.9369 107.016932) (xy 177.050434 107.045456) (xy 177.092222 107.0625)
				(xy 177.181 106.86) (xy 177.092222 106.6575) (xy 176.996177 106.691883) (xy 176.894296 106.707101)
				(xy 176.779323 106.71)
			)
		)
	)
	(zone
		(net 188)
		(net_name "/OCuLink/PCIe_{x4}.RX1+")
		(layer "B.Cu")
		(name "$teardrop_padvia$")
		(hatch none 0.1)
		(priority 30537)
		(attr
			(teardrop
				(type padvia)
			)
		)
		(connect_pads yes
			(clearance 0)
		)
		(min_thickness 0.0254)
		(filled_areas_thickness no)
		(fill yes
			(thermal_gap 0.5)
			(thermal_bridge_width 0.5)
			(island_removal_mode 1)
			(island_area_min 10)
		)
		(polygon
			(pts
				(xy 99.232504 149.2065) (xy 99.394035 149.201105) (xy 99.478445 149.197554) (xy 99.58014 149.202177)
				(xy 99.601 148.9815) (xy 99.451147 148.818268) (xy 99.397007 148.886935) (xy 99.387115 148.903393)
				(xy 99.362615 148.942065) (xy 99.333109 148.974279) (xy 99.291953 148.996327) (xy 99.232504 149.0045)
			)
		)
	)
	(zone
		(net 675)
		(net_name "Net-(U45C-GPI0)")
		(layer "B.Cu")
		(name "$teardrop_padvia$")
		(hatch none 0.1)
		(priority 30417)
		(attr
			(teardrop
				(type padvia)
			)
		)
		(connect_pads yes
			(clearance 0)
		)
		(min_thickness 0.0254)
		(filled_areas_thickness no)
		(fill yes
			(thermal_gap 0.5)
			(thermal_bridge_width 0.5)
			(island_removal_mode 1)
			(island_area_min 10)
		)
		(polygon
			(pts
				(xy 126.983 140.9975) (xy 126.923588 140.977727) (xy 126.867503 140.914453) (xy 126.845801 140.865828)
				(xy 126.831127 140.806468) (xy 126.829347 140.7945) (xy 126.569 141.06) (xy 126.829347 141.3255)
				(xy 126.842197 141.265361) (xy 126.862131 141.215477) (xy 126.888056 141.175358) (xy 126.917876 141.146345)
				(xy 126.949294 141.128854) (xy 126.981105 141.122521) (xy 126.983 141.1225)
			)
		)
	)
	(zone
		(net 969)
		(net_name "/M.2 key M #1/M2_3V3")
		(layer "B.Cu")
		(name "$teardrop_padvia$")
		(hatch none 0.1)
		(priority 30271)
		(attr
			(teardrop
				(type padvia)
			)
		)
		(connect_pads yes
			(clearance 0)
		)
		(min_thickness 0.0254)
		(filled_areas_thickness no)
		(fill yes
			(thermal_gap 0.5)
			(thermal_bridge_width 0.5)
			(island_removal_mode 1)
			(island_area_min 10)
		)
		(polygon
			(pts
				(xy 178.260676 109.96) (xy 178.103105 109.953069) (xy 177.989577 109.924549) (xy 177.947777 109.9075)
				(xy 177.858999 110.11) (xy 177.947777 110.3125) (xy 178.043816 110.278118) (xy 178.145688 110.2629)
				(xy 178.260676 110.26)
			)
		)
	)
	(zone
		(net 167)
		(net_name "Net-(J2A-RS0)")
		(layer "B.Cu")
		(name "$teardrop_padvia$")
		(hatch none 0.1)
		(priority 30072)
		(attr
			(teardrop
				(type padvia)
			)
		)
		(connect_pads yes
			(clearance 0)
		)
		(min_thickness 0.0254)
		(filled_areas_thickness no)
		(fill yes
			(thermal_gap 0.5)
			(thermal_bridge_width 0.5)
			(island_removal_mode 1)
			(island_area_min 10)
		)
		(polygon
			(pts
				(xy 145.632736 164.295652) (xy 145.697615 164.237595) (xy 145.757096 164.197584) (xy 145.862061 164.159114)
				(xy 145.998356 164.149873) (xy 146.09714 164.146966) (xy 146.213889 164.131738) (xy 146.130707 163.709293)
				(xy 145.708262 163.626111) (xy 145.690953 163.788348) (xy 145.690127 163.841644) (xy 145.687095 163.931998)
				(xy 145.67074 164.018037) (xy 145.627634 164.107285) (xy 145.544348 164.207264)
			)
		)
	)
	(zone
		(net 1)
		(net_name "GND")
		(layer "B.Cu")
		(name "$teardrop_padvia$")
		(hatch none 0.1)
		(priority 30921)
		(attr
			(teardrop
				(type padvia)
			)
		)
		(connect_pads yes
			(clearance 0)
		)
		(min_thickness 0.0254)
		(filled_areas_thickness no)
		(fill yes
			(thermal_gap 0.5)
			(thermal_bridge_width 0.5)
			(island_removal_mode 1)
			(island_area_min 10)
		)
		(polygon
			(pts
				(xy 190.577461 138.516141) (xy 190.573059 138.520678) (xy 190.541177 138.544662) (xy 190.517733 138.546988)
				(xy 190.487662 138.535228) (xy 190.276233 138.905756) (xy 190.64676 138.694328) (xy 190.635533 138.66738)
				(xy 190.635834 138.645722) (xy 190.661311 138.60893) (xy 190.665848 138.604528)
			)
		)
	)
	(zone
		(net 2)
		(net_name "+3V3")
		(layer "B.Cu")
		(name "$teardrop_padvia$")
		(hatch none 0.1)
		(priority 30807)
		(attr
			(teardrop
				(type padvia)
			)
		)
		(connect_pads yes
			(clearance 0)
		)
		(min_thickness 0.0254)
		(filled_areas_thickness no)
		(fill yes
			(thermal_gap 0.5)
			(thermal_bridge_width 0.5)
			(island_removal_mode 1)
			(island_area_min 10)
		)
		(polygon
			(pts
				(xy 194.243227 132.265441) (xy 194.19784 132.213247) (xy 194.171418 132.167467) (xy 194.151269 132.081408)
				(xy 194.149434 132.065644) (xy 194.137096 131.981712) (xy 193.915712 132.0249) (xy 193.872524 132.246284)
				(xy 193.954037 132.258605) (xy 194.051623 132.279309) (xy 194.09973 132.306182) (xy 194.154839 132.353829)
			)
		)
	)
	(zone
		(net 239)
		(net_name "/Com Express 7 Interfaces/PCIe_{B2Bx4}.RX3+")
		(layer "B.Cu")
		(name "$teardrop_padvia$")
		(hatch none 0.1)
		(priority 30303)
		(attr
			(teardrop
				(type padvia)
			)
		)
		(connect_pads yes
			(clearance 0)
		)
		(min_thickness 0.0254)
		(filled_areas_thickness no)
		(fill yes
			(thermal_gap 0.5)
			(thermal_bridge_width 0.5)
			(island_removal_mode 1)
			(island_area_min 10)
		)
		(polygon
			(pts
				(xy 175.39 93.961) (xy 175.404678 93.957463) (xy 175.434685 93.954192) (xy 175.445673 93.966143)
				(xy 175.45 93.995) (xy 176.201 93.86) (xy 175.45 93.725) (xy 175.445525 93.754204) (xy 175.434203 93.765997)
				(xy 175.404678 93.762537) (xy 175.39 93.759)
			)
		)
	)
	(zone
		(net 124)
		(net_name "/2xUSB3.0+RJ45/P1_D+")
		(layer "B.Cu")
		(name "$teardrop_padvia$")
		(hatch none 0.1)
		(priority 30135)
		(attr
			(teardrop
				(type padvia)
			)
		)
		(connect_pads yes
			(clearance 0)
		)
		(min_thickness 0.0254)
		(filled_areas_thickness no)
		(fill yes
			(thermal_gap 0.5)
			(thermal_bridge_width 0.5)
			(island_removal_mode 1)
			(island_area_min 10)
		)
		(polygon
			(pts
				(xy 105.720445 105.56474) (xy 105.668537 105.609027) (xy 105.602896 105.64961) (xy 105.532915 105.679883)
				(xy 105.452204 105.702083) (xy 105.319163 105.715) (xy 105.400293 106.015707) (xy 105.701 106.096838)
				(xy 105.719039 105.940698) (xy 105.769558 105.807091) (xy 105.845673 105.701252) (xy 105.85126 105.695555)
			)
		)
	)
	(zone
		(net 1)
		(net_name "GND")
		(layer "B.Cu")
		(name "$teardrop_padvia$")
		(hatch none 0.1)
		(priority 30471)
		(attr
			(teardrop
				(type padvia)
			)
		)
		(connect_pads yes
			(clearance 0)
		)
		(min_thickness 0.0254)
		(filled_areas_thickness no)
		(fill yes
			(thermal_gap 0.5)
			(thermal_bridge_width 0.5)
			(island_removal_mode 1)
			(island_area_min 10)
		)
		(polygon
			(pts
				(xy 101.874323 105.465) (xy 101.952235 105.469713) (xy 102.01102 105.4827) (xy 102.102051 105.524802)
				(xy 102.187222 105.5675) (xy 102.276 105.365) (xy 102.187222 105.1625) (xy 102.10205 105.205199)
				(xy 102.009217 105.247867) (xy 101.951078 105.260444) (xy 101.874323 105.265)
			)
		)
	)
	(zone
		(net 969)
		(net_name "/M.2 key M #1/M2_3V3")
		(layer "B.Cu")
		(name "$teardrop_padvia$")
		(hatch none 0.1)
		(priority 30266)
		(attr
			(teardrop
				(type padvia)
			)
		)
		(connect_pads yes
			(clearance 0)
		)
		(min_thickness 0.0254)
		(filled_areas_thickness no)
		(fill yes
			(thermal_gap 0.5)
			(thermal_bridge_width 0.5)
			(island_removal_mode 1)
			(island_area_min 10)
		)
		(polygon
			(pts
				(xy 178.260677 95.96) (xy 178.103106 95.953069) (xy 177.989578 95.924549) (xy 177.947778 95.9075)
				(xy 177.859 96.11) (xy 177.947778 96.3125) (xy 178.043817 96.278118) (xy 178.145689 96.2629) (xy 178.260677 96.26)
			)
		)
	)
	(zone
		(net 427)
		(net_name "/2xSFP+/10GKR_SFP1.RX+")
		(layer "B.Cu")
		(name "$teardrop_padvia$")
		(hatch none 0.1)
		(priority 30825)
		(attr
			(teardrop
				(type padvia)
			)
		)
		(connect_pads yes
			(clearance 0)
		)
		(min_thickness 0.0254)
		(filled_areas_thickness no)
		(fill yes
			(thermal_gap 0.5)
			(thermal_bridge_width 0.5)
			(island_removal_mode 1)
			(island_area_min 10)
		)
		(polygon
			(pts
				(xy 195.186427 154.859915) (xy 195.149792 154.783378) (xy 195.115016 154.730375) (xy 195.075974 154.683744)
				(xy 195.000378 154.587307) (xy 194.812737 154.710958) (xy 194.857014 154.932558) (xy 194.925908 154.906155)
				(xy 194.991216 154.883452) (xy 195.017645 154.89128) (xy 195.038613 154.921159)
			)
		)
	)
	(zone
		(net 57)
		(net_name "/USB-C console/FTDI_VCCIO")
		(layer "B.Cu")
		(name "$teardrop_padvia$")
		(hatch none 0.1)
		(priority 30235)
		(attr
			(teardrop
				(type padvia)
			)
		)
		(connect_pads yes
			(clearance 0)
		)
		(min_thickness 0.0254)
		(filled_areas_thickness no)
		(fill yes
			(thermal_gap 0.5)
			(thermal_bridge_width 0.5)
			(island_removal_mode 1)
			(island_area_min 10)
		)
		(polygon
			(pts
				(xy 112.55 70.753) (xy 112.549663 70.73791) (xy 112.55024 70.697674) (xy 112.562054 70.65613) (xy 112.596633 70.620835)
				(xy 112.6655 70.599347) (xy 112.4 70.339) (xy 112.1345 70.599347) (xy 112.180938 70.610291) (xy 112.213135 70.627391)
				(xy 112.244578 70.671856) (xy 112.250337 70.73791) (xy 112.25 70.753)
			)
		)
	)
	(zone
		(net 205)
		(net_name "/Backplane/PCIe_{REF}.CK-")
		(layer "B.Cu")
		(name "$teardrop_padvia$")
		(hatch none 0.1)
		(priority 30539)
		(attr
			(teardrop
				(type padvia)
			)
		)
		(connect_pads yes
			(clearance 0)
		)
		(min_thickness 0.0254)
		(filled_areas_thickness no)
		(fill yes
			(thermal_gap 0.5)
			(thermal_bridge_width 0.5)
			(island_removal_mode 1)
			(island_area_min 10)
		)
		(polygon
			(pts
				(xy 311.993744 164.585973) (xy 311.875707 164.475566) (xy 311.81351 164.41839) (xy 311.74487 164.343214)
				(xy 311.574079 164.484507) (xy 311.564619 164.705891) (xy 311.651457 164.695617) (xy 311.670087 164.690976)
				(xy 311.714757 164.680954) (xy 311.758399 164.679039) (xy 311.803091 164.692551) (xy 311.850908 164.728809)
			)
		)
	)
	(zone
		(net 711)
		(net_name "Net-(U37-SADR_{TRI})")
		(layer "B.Cu")
		(name "$teardrop_padvia$")
		(hatch none 0.1)
		(priority 30696)
		(attr
			(teardrop
				(type padvia)
			)
		)
		(connect_pads yes
			(clearance 0)
		)
		(min_thickness 0.0254)
		(filled_areas_thickness no)
		(fill yes
			(thermal_gap 0.5)
			(thermal_bridge_width 0.5)
			(island_removal_mode 1)
			(island_area_min 10)
		)
		(polygon
			(pts
				(xy 217.5175 125.199323) (xy 217.512682 125.268763) (xy 217.49896 125.320087) (xy 217.452245 125.395628)
				(xy 217.442702 125.407768) (xy 217.392919 125.474997) (xy 217.58 125.601) (xy 217.767081 125.474997)
				(xy 217.717299 125.407769) (xy 217.662894 125.324603) (xy 217.64781 125.271748) (xy 217.6425 125.199323)
			)
		)
	)
	(zone
		(net 169)
		(net_name "Net-(J2A-RS1)")
		(layer "B.Cu")
		(name "$teardrop_padvia$")
		(hatch none 0.1)
		(priority 30068)
		(attr
			(teardrop
				(type padvia)
			)
		)
		(connect_pads yes
			(clearance 0)
		)
		(min_thickness 0.0254)
		(filled_areas_thickness no)
		(fill yes
			(thermal_gap 0.5)
			(thermal_bridge_width 0.5)
			(island_removal_mode 1)
			(island_area_min 10)
		)
		(polygon
			(pts
				(xy 146.270175 165.991787) (xy 146.236196 165.950958) (xy 146.217891 165.912988) (xy 146.21324 165.880999)
				(xy 146.218225 165.850419) (xy 146.256628 165.785797) (xy 146.345172 165.699594) (xy 146.420541 165.629206)
				(xy 146.487532 165.548895) (xy 146.129293 165.309293) (xy 145.772468 165.548895) (xy 145.860437 165.683696)
				(xy 145.985141 165.864817) (xy 146.181787 166.080175)
			)
		)
	)
	(zone
		(net 81)
		(net_name "/Misc/FAN_12V")
		(layer "B.Cu")
		(name "$teardrop_padvia$")
		(hatch none 0.1)
		(priority 30056)
		(attr
			(teardrop
				(type padvia)
			)
		)
		(connect_pads yes
			(clearance 0)
		)
		(min_thickness 0.0254)
		(filled_areas_thickness no)
		(fill yes
			(thermal_gap 0.5)
			(thermal_bridge_width 0.5)
			(island_removal_mode 1)
			(island_area_min 10)
		)
		(polygon
			(pts
				(xy 249.845752 73.733594) (xy 249.911403 73.790823) (xy 249.985979 73.855229) (xy 250.056074 73.93492)
				(xy 250.10741 74.037136) (xy 250.121582 74.098953) (xy 250.12571 74.169116) (xy 250.526417 74.060707)
				(xy 250.534827 73.56) (xy 250.480712 73.569977) (xy 250.433185 73.569304) (xy 250.353602 73.542036)
				(xy 250.283485 73.482248) (xy 250.24109 73.430147) (xy 250.199304 73.380042)
			)
		)
	)
	(zone
		(net 195)
		(net_name "/OCuLink/PCIe_{x4}.RX2-")
		(layer "B.Cu")
		(name "$teardrop_padvia$")
		(hatch none 0.1)
		(priority 30849)
		(attr
			(teardrop
				(type padvia)
			)
		)
		(connect_pads yes
			(clearance 0)
		)
		(min_thickness 0.0254)
		(filled_areas_thickness no)
		(fill yes
			(thermal_gap 0.5)
			(thermal_bridge_width 0.5)
			(island_removal_mode 1)
			(island_area_min 10)
		)
		(polygon
			(pts
				(xy 191.589331 134.86959) (xy 191.681138 134.936747) (xy 191.784111 135.008958) (xy 191.835642 135.057719)
				(xy 191.883734 135.119446) (xy 192.045414 135.10435) (xy 191.780327 134.749565) (xy 191.759067 134.76452)
				(xy 191.746789 134.76132) (xy 191.737966 134.74098) (xy 191.732166 134.726755)
			)
		)
	)
	(zone
		(net 200)
		(net_name "/OCuLink/~{PERST_D0}")
		(layer "B.Cu")
		(name "$teardrop_padvia$")
		(hatch none 0.1)
		(priority 30737)
		(attr
			(teardrop
				(type padvia)
			)
		)
		(connect_pads yes
			(clearance 0)
		)
		(min_thickness 0.0254)
		(filled_areas_thickness no)
		(fill yes
			(thermal_gap 0.5)
			(thermal_bridge_width 0.5)
			(island_removal_mode 1)
			(island_area_min 10)
		)
		(polygon
			(pts
				(xy 120.750677 162.4975) (xy 120.681236 162.492682) (xy 120.629913 162.47896) (xy 120.554371 162.432246)
				(xy 120.542231 162.422701) (xy 120.475003 162.372919) (xy 120.349 162.56) (xy 120.475003 162.747081)
				(xy 120.542229 162.697299) (xy 120.625396 162.642894) (xy 120.678251 162.62781) (xy 120.750677 162.6225)
			)
		)
	)
	(zone
		(net 61)
		(net_name "/OCuLink/5V_CONN0")
		(layer "B.Cu")
		(name "$teardrop_padvia$")
		(hatch none 0.1)
		(priority 30229)
		(attr
			(teardrop
				(type padvia)
			)
		)
		(connect_pads yes
			(clearance 0)
		)
		(min_thickness 0.0254)
		(filled_areas_thickness no)
		(fill yes
			(thermal_gap 0.5)
			(thermal_bridge_width 0.5)
			(island_removal_mode 1)
			(island_area_min 10)
		)
		(polygon
			(pts
				(xy 103.79 154.059323) (xy 103.783155 154.240241) (xy 103.745356 154.377397) (xy 103.95 154.461)
				(xy 104.150214 154.366705) (xy 104.107474 154.254251) (xy 104.090968 154.121051) (xy 104.09 154.059323)
			)
		)
	)
	(zone
		(net 311)
		(net_name "Net-(J12D-~{THRMTRIP})")
		(layer "B.Cu")
		(name "$teardrop_padvia$")
		(hatch none 0.1)
		(priority 30771)
		(attr
			(teardrop
				(type padvia)
			)
		)
		(connect_pads yes
			(clearance 0)
		)
		(min_thickness 0.0254)
		(filled_areas_thickness no)
		(fill yes
			(thermal_gap 0.5)
			(thermal_bridge_width 0.5)
			(island_removal_mode 1)
			(island_area_min 10)
		)
		(polygon
			(pts
				(xy 192.760873 170.477515) (xy 192.813382 170.431819) (xy 192.859376 170.405231) (xy 192.945824 170.384847)
				(xy 192.96116 170.383011) (xy 193.043895 170.370677) (xy 193.000707 170.149293) (xy 192.779323 170.106105)
				(xy 192.766988 170.188841) (xy 192.746651 170.286119) (xy 192.719943 170.334159) (xy 192.672485 170.389127)
			)
		)
	)
	(zone
		(net 42)
		(net_name "/2xUSB3.0+RJ45/P1_VBUS")
		(layers "B.Cu" "In3.Cu")
		(hatch edge 0.5)
		(priority 8)
		(connect_pads yes
			(clearance 0.15)
		)
		(min_thickness 0.25)
		(filled_areas_thickness no)
		(fill yes
			(thermal_gap 0.5)
			(thermal_bridge_width 0.5)
			(smoothing fillet)
			(radius 0.2)
		)
		(polygon
			(pts
				(xy 112.55 87.31) (xy 109.05 90.81) (xy 109.05 93.86) (xy 107.45 95.46) (xy 107.45 102.56) (xy 105 102.56)
				(xy 105 94.201298) (xy 107.35 91.84054) (xy 107.35 89.16) (xy 109.3 87.21) (xy 109.3 86.11) (xy 112.55 86.11)
			)
		)
	)
	(zone
		(net 43)
		(net_name "/2xUSB3.0+RJ45/P2_VBUS")
		(layers "B.Cu" "In3.Cu")
		(hatch edge 0.5)
		(priority 8)
		(connect_pads yes
			(clearance 0.15)
		)
		(min_thickness 0.25)
		(filled_areas_thickness no)
		(fill yes
			(thermal_gap 0.5)
			(thermal_bridge_width 0.5)
			(smoothing fillet)
			(radius 0.2)
		)
		(polygon
			(pts
				(xy 109.6 102.66) (xy 109.05 102.11) (xy 109.05 101.41) (xy 108.2 100.56) (xy 107.75 100.56) (xy 107.75 95.56)
				(xy 109.3 94.01) (xy 109.3 90.96) (xy 112.55 90.96) (xy 112.55 94.26) (xy 110.65 96.16) (xy 110.65 102.66)
			)
		)
	)
	(zone
		(net 0)
		(net_name "")
		(layer "In1.Cu")
		(hatch edge 0.5)
		(connect_pads
			(clearance 0)
		)
		(min_thickness 0.25)
		(filled_areas_thickness no)
		(keepout
			(tracks not_allowed)
			(vias allowed)
			(pads allowed)
			(copperpour not_allowed)
			(footprints allowed)
		)
		(placement
			(enabled no)
			(sheetname "")
		)
		(fill
			(thermal_gap 0.5)
			(thermal_bridge_width 0.5)
		)
		(polygon
			(pts
				(xy 155.2 146.7) (xy 156.7 146.7) (xy 156.7 148.55) (xy 155.2 148.55)
			)
		)
	)
	(zone
		(net 0)
		(net_name "")
		(layer "In1.Cu")
		(hatch edge 0.5)
		(connect_pads
			(clearance 0)
		)
		(min_thickness 0.25)
		(filled_areas_thickness no)
		(keepout
			(tracks not_allowed)
			(vias allowed)
			(pads allowed)
			(copperpour not_allowed)
			(footprints allowed)
		)
		(placement
			(enabled no)
			(sheetname "")
		)
		(fill
			(thermal_gap 0.5)
			(thermal_bridge_width 0.5)
		)
		(polygon
			(pts
				(xy 131.05 146.725) (xy 132.55 146.725) (xy 132.55 148.575) (xy 131.05 148.575)
			)
		)
	)
	(zone
		(net 0)
		(net_name "")
		(layer "In1.Cu")
		(hatch edge 0.5)
		(connect_pads
			(clearance 0)
		)
		(min_thickness 0.25)
		(filled_areas_thickness no)
		(keepout
			(tracks not_allowed)
			(vias allowed)
			(pads allowed)
			(copperpour not_allowed)
			(footprints allowed)
		)
		(placement
			(enabled no)
			(sheetname "")
		)
		(fill
			(thermal_gap 0.5)
			(thermal_bridge_width 0.5)
		)
		(polygon
			(pts
				(xy 149.2 146.725) (xy 150.7 146.725) (xy 150.7 148.575) (xy 149.2 148.575)
			)
		)
	)
	(zone
		(net 0)
		(net_name "")
		(layer "In1.Cu")
		(hatch edge 0.5)
		(connect_pads
			(clearance 0)
		)
		(min_thickness 0.25)
		(filled_areas_thickness no)
		(keepout
			(tracks not_allowed)
			(vias allowed)
			(pads allowed)
			(copperpour not_allowed)
			(footprints allowed)
		)
		(placement
			(enabled no)
			(sheetname "")
		)
		(fill
			(thermal_gap 0.5)
			(thermal_bridge_width 0.5)
		)
		(polygon
			(pts
				(xy 128.05 146.7) (xy 129.55 146.7) (xy 129.55 148.55) (xy 128.05 148.55)
			)
		)
	)
	(zone
		(net 0)
		(net_name "")
		(layer "In1.Cu")
		(hatch edge 0.5)
		(connect_pads
			(clearance 0)
		)
		(min_thickness 0.25)
		(filled_areas_thickness no)
		(keepout
			(tracks not_allowed)
			(vias allowed)
			(pads allowed)
			(copperpour not_allowed)
			(footprints allowed)
		)
		(placement
			(enabled no)
			(sheetname "")
		)
		(fill
			(thermal_gap 0.5)
			(thermal_bridge_width 0.5)
		)
		(polygon
			(pts
				(xy 134.05 146.7) (xy 135.55 146.7) (xy 135.55 148.55) (xy 134.05 148.55)
			)
		)
	)
	(zone
		(net 0)
		(net_name "")
		(layer "In1.Cu")
		(hatch edge 0.5)
		(connect_pads
			(clearance 0)
		)
		(min_thickness 0.25)
		(filled_areas_thickness no)
		(keepout
			(tracks not_allowed)
			(vias allowed)
			(pads allowed)
			(copperpour not_allowed)
			(footprints allowed)
		)
		(placement
			(enabled no)
			(sheetname "")
		)
		(fill
			(thermal_gap 0.5)
			(thermal_bridge_width 0.5)
		)
		(polygon
			(pts
				(xy 152.2 146.7) (xy 153.7 146.7) (xy 153.7 148.55) (xy 152.2 148.55)
			)
		)
	)
	(zone
		(net 0)
		(net_name "")
		(layer "In1.Cu")
		(hatch edge 0.5)
		(connect_pads
			(clearance 0)
		)
		(min_thickness 0.25)
		(filled_areas_thickness no)
		(keepout
			(tracks not_allowed)
			(vias allowed)
			(pads allowed)
			(copperpour not_allowed)
			(footprints allowed)
		)
		(placement
			(enabled no)
			(sheetname "")
		)
		(fill
			(thermal_gap 0.5)
			(thermal_bridge_width 0.5)
		)
		(polygon
			(pts
				(xy 146.2 146.7) (xy 147.7 146.7) (xy 147.7 148.55) (xy 146.2 148.55)
			)
		)
	)
	(zone
		(net 0)
		(net_name "")
		(layer "In1.Cu")
		(hatch edge 0.5)
		(connect_pads
			(clearance 0)
		)
		(min_thickness 0.25)
		(filled_areas_thickness no)
		(keepout
			(tracks not_allowed)
			(vias allowed)
			(pads allowed)
			(copperpour not_allowed)
			(footprints allowed)
		)
		(placement
			(enabled no)
			(sheetname "")
		)
		(fill
			(thermal_gap 0.5)
			(thermal_bridge_width 0.5)
		)
		(polygon
			(pts
				(xy 137.05 146.7) (xy 138.55 146.7) (xy 138.55 148.55) (xy 137.05 148.55)
			)
		)
	)
	(zone
		(net 1)
		(net_name "GND")
		(layers "In1.Cu" "In4.Cu" "In6.Cu")
		(hatch edge 0.5)
		(connect_pads
			(clearance 0.15)
		)
		(min_thickness 0.15)
		(filled_areas_thickness no)
		(fill yes
			(thermal_gap 0.2)
			(thermal_bridge_width 0.5)
		)
		(polygon
			(pts
				(xy 94.25 172.01) (xy 322.3 172.01) (xy 322.3 67.61) (xy 94.25 67.61)
			)
		)
	)
	(zone
		(net 434)
		(net_name "/Com Express 7 MGMT/~{TYPE1}")
		(layer "In2.Cu")
		(name "$teardrop_padvia$")
		(hatch none 0.1)
		(priority 30066)
		(attr
			(teardrop
				(type padvia)
			)
		)
		(connect_pads yes
			(clearance 0)
		)
		(min_thickness 0.0254)
		(filled_areas_thickness no)
		(fill yes
			(thermal_gap 0.5)
			(thermal_bridge_width 0.5)
			(island_removal_mode 1)
			(island_area_min 10)
		)
		(polygon
			(pts
				(xy 221.149323 149.1875) (xy 221.218764 149.192318) (xy 221.270088 149.20604) (xy 221.345629 149.252755)
				(xy 221.357769 149.262299) (xy 221.424997 149.312081) (xy 221.551 149.125) (xy 221.424997 148.937919)
				(xy 221.357768 148.987702) (xy 221.274602 149.042106) (xy 221.221748 149.05719) (xy 221.149323 149.0625)
			)
		)
	)
	(zone
		(net 431)
		(net_name "/2xSFP+/MOD0_ABS")
		(layer "In2.Cu")
		(name "$teardrop_padvia$")
		(hatch none 0.1)
		(priority 30069)
		(attr
			(teardrop
				(type padvia)
			)
		)
		(connect_pads yes
			(clearance 0)
		)
		(min_thickness 0.0254)
		(filled_areas_thickness no)
		(fill yes
			(thermal_gap 0.5)
			(thermal_bridge_width 0.5)
			(island_removal_mode 1)
			(island_area_min 10)
		)
		(polygon
			(pts
				(xy 200.649323 154.4625) (xy 200.718764 154.467318) (xy 200.770088 154.48104) (xy 200.845629 154.527755)
				(xy 200.857769 154.537299) (xy 200.924997 154.587081) (xy 201.051 154.4) (xy 200.924997 154.212919)
				(xy 200.857768 154.262702) (xy 200.774602 154.317106) (xy 200.721748 154.33219) (xy 200.649323 154.3375)
			)
		)
	)
	(zone
		(net 58)
		(net_name "/USB-C console/VBUS_FTDI")
		(layer "In2.Cu")
		(name "$teardrop_padvia$")
		(hatch none 0.1)
		(priority 30005)
		(attr
			(teardrop
				(type padvia)
			)
		)
		(connect_pads yes
			(clearance 0)
		)
		(min_thickness 0.0254)
		(filled_areas_thickness no)
		(fill yes
			(thermal_gap 0.5)
			(thermal_bridge_width 0.5)
			(island_removal_mode 1)
			(island_area_min 10)
		)
		(polygon
			(pts
				(xy 115.235676 77.575) (xy 115.078105 77.568069) (xy 114.964577 77.539549) (xy 114.922777 77.5225)
				(xy 114.833999 77.725) (xy 114.922777 77.9275) (xy 115.018816 77.893118) (xy 115.120688 77.8779)
				(xy 115.235676 77.875)
			)
		)
	)
	(zone
		(net 358)
		(net_name "/Com Express 7 MGMT/SMBus.SDA")
		(layer "In2.Cu")
		(name "$teardrop_padvia$")
		(hatch none 0.1)
		(priority 30031)
		(attr
			(teardrop
				(type padvia)
			)
		)
		(connect_pads yes
			(clearance 0)
		)
		(min_thickness 0.0254)
		(filled_areas_thickness no)
		(fill yes
			(thermal_gap 0.5)
			(thermal_bridge_width 0.5)
			(island_removal_mode 1)
			(island_area_min 10)
		)
		(polygon
			(pts
				(xy 182.084617 164.273005) (xy 182.10801 164.303148) (xy 182.116615 164.33072) (xy 182.103032 164.377333)
				(xy 182.059794 164.429461) (xy 182.014792 164.482091) (xy 181.983762 164.545386) (xy 182.200707 164.600707)
				(xy 182.381592 164.469508) (xy 182.31348 164.364554) (xy 182.26135 164.284507) (xy 182.173005 164.184617)
			)
		)
	)
	(zone
		(net 208)
		(net_name "/Backplane/UART.RX")
		(layer "In2.Cu")
		(name "$teardrop_padvia$")
		(hatch none 0.1)
		(priority 30150)
		(attr
			(teardrop
				(type padvia)
			)
		)
		(connect_pads yes
			(clearance 0)
		)
		(min_thickness 0.0254)
		(filled_areas_thickness no)
		(fill yes
			(thermal_gap 0.5)
			(thermal_bridge_width 0.5)
			(island_removal_mode 1)
			(island_area_min 10)
		)
		(polygon
			(pts
				(xy 231.439127 169.972485) (xy 231.386618 170.018181) (xy 231.340623 170.044768) (xy 231.254174 170.065152)
				(xy 231.238841 170.066988) (xy 231.156105 170.079323) (xy 231.199293 170.300707) (xy 231.420677 170.343895)
				(xy 231.433011 170.26116) (xy 231.453349 170.163881) (xy 231.480057 170.115841) (xy 231.527515 170.060873)
			)
		)
	)
	(zone
		(net 945)
		(net_name "/GPIO expander/GPIOEX5")
		(layer "In2.Cu")
		(name "$teardrop_padvia$")
		(hatch none 0.1)
		(priority 30023)
		(attr
			(teardrop
				(type padvia)
			)
		)
		(connect_pads yes
			(clearance 0)
		)
		(min_thickness 0.0254)
		(filled_areas_thickness no)
		(fill yes
			(thermal_gap 0.5)
			(thermal_bridge_width 0.5)
			(island_removal_mode 1)
			(island_area_min 10)
		)
		(polygon
			(pts
				(xy 122.738344 147.333268) (xy 122.677793 147.387276) (xy 122.626348 147.421208) (xy 122.553003 147.453988)
				(xy 122.439381 147.50696) (xy 122.549293 147.700707) (xy 122.770677 147.739967) (xy 122.773267 147.643214)
				(xy 122.769561 147.61252) (xy 122.764731 147.565678) (xy 122.767762 147.52011) (xy 122.785985 147.473031)
				(xy 122.826732 147.421656)
			)
		)
	)
	(zone
		(net 53)
		(net_name "/2xSFP+/SH")
		(layer "In2.Cu")
		(name "$teardrop_padvia$")
		(hatch none 0.1)
		(priority 30002)
		(attr
			(teardrop
				(type padvia)
			)
		)
		(connect_pads yes
			(clearance 0)
		)
		(min_thickness 0.0254)
		(filled_areas_thickness no)
		(fill yes
			(thermal_gap 0.5)
			(thermal_bridge_width 0.5)
			(island_removal_mode 1)
			(island_area_min 10)
		)
		(polygon
			(pts
				(xy 152.2 159.645589) (xy 152.204874 159.521824) (xy 152.218996 159.416865) (xy 152.240089 159.332229)
				(xy 152.268095 159.258643) (xy 152.346201 159.12843) (xy 152.460058 158.993796) (xy 152.562896 158.875401)
				(xy 152.673602 158.726678) (xy 152.05 158.309) (xy 151.426398 158.726678) (xy 151.570593 158.915228)
				(xy 151.639942 158.993797) (xy 151.744416 159.116075) (xy 151.826718 159.247489) (xy 151.857616 159.325049)
				(xy 151.880646 159.415005) (xy 151.895032 159.520728) (xy 151.9 159.645589)
			)
		)
	)
	(zone
		(net 372)
		(net_name "/Com Express 7 MGMT/I2C.SDA")
		(layer "In2.Cu")
		(name "$teardrop_padvia$")
		(hatch none 0.1)
		(priority 30156)
		(attr
			(teardrop
				(type padvia)
			)
		)
		(connect_pads yes
			(clearance 0)
		)
		(min_thickness 0.0254)
		(filled_areas_thickness no)
		(fill yes
			(thermal_gap 0.5)
			(thermal_bridge_width 0.5)
			(island_removal_mode 1)
			(island_area_min 10)
		)
		(polygon
			(pts
				(xy 239.822485 154.310873) (xy 239.868181 154.363382) (xy 239.894768 154.409376) (xy 239.915152 154.495825)
				(xy 239.916988 154.511158) (xy 239.929323 154.593895) (xy 240.150707 154.550707) (xy 240.193895 154.329323)
				(xy 240.111158 154.316988) (xy 240.01388 154.296651) (xy 239.96584 154.269943) (xy 239.910873 154.222485)
			)
		)
	)
	(zone
		(net 2)
		(net_name "+3V3")
		(layer "In2.Cu")
		(name "$teardrop_padvia$")
		(hatch none 0.1)
		(priority 30076)
		(attr
			(teardrop
				(type padvia)
			)
		)
		(connect_pads yes
			(clearance 0)
		)
		(min_thickness 0.0254)
		(filled_areas_thickness no)
		(fill yes
			(thermal_gap 0.5)
			(thermal_bridge_width 0.5)
			(island_removal_mode 1)
			(island_area_min 10)
		)
		(polygon
			(pts
				(xy 173.299323 156.6125) (xy 173.368764 156.617318) (xy 173.420088 156.63104) (xy 173.495629 156.677755)
				(xy 173.507769 156.687299) (xy 173.574997 156.737081) (xy 173.701 156.55) (xy 173.574997 156.362919)
				(xy 173.507768 156.412702) (xy 173.424602 156.467106) (xy 173.371748 156.48219) (xy 173.299323 156.4875)
			)
		)
	)
	(zone
		(net 528)
		(net_name "/Backplane/~{PERST}")
		(layer "In2.Cu")
		(name "$teardrop_padvia$")
		(hatch none 0.1)
		(priority 30171)
		(attr
			(teardrop
				(type padvia)
			)
		)
		(connect_pads yes
			(clearance 0)
		)
		(min_thickness 0.0254)
		(filled_areas_thickness no)
		(fill yes
			(thermal_gap 0.5)
			(thermal_bridge_width 0.5)
			(island_removal_mode 1)
			(island_area_min 10)
		)
		(polygon
			(pts
				(xy 158.310873 153.087515) (xy 158.363382 153.041819) (xy 158.409376 153.015231) (xy 158.495824 152.994847)
				(xy 158.51116 152.993011) (xy 158.593895 152.980677) (xy 158.550707 152.759293) (xy 158.329323 152.716105)
				(xy 158.316988 152.798841) (xy 158.296651 152.896119) (xy 158.269943 152.944159) (xy 158.222485 152.999127)
			)
		)
	)
	(zone
		(net 935)
		(net_name "Net-(D13-C)")
		(layer "In2.Cu")
		(name "$teardrop_padvia$")
		(hatch none 0.1)
		(priority 30093)
		(attr
			(teardrop
				(type padvia)
			)
		)
		(connect_pads yes
			(clearance 0)
		)
		(min_thickness 0.0254)
		(filled_areas_thickness no)
		(fill yes
			(thermal_gap 0.5)
			(thermal_bridge_width 0.5)
			(island_removal_mode 1)
			(island_area_min 10)
		)
		(polygon
			(pts
				(xy 176.6625 89.160677) (xy 176.667318 89.091236) (xy 176.68104 89.039912) (xy 176.727755 88.96437)
				(xy 176.737299 88.952229) (xy 176.787081 88.885003) (xy 176.6 88.759) (xy 176.412919 88.885003)
				(xy 176.462701 88.952231) (xy 176.517106 89.035397) (xy 176.53219 89.088251) (xy 176.5375 89.160677)
			)
		)
	)
	(zone
		(net 359)
		(net_name "/Com Express 7 MGMT/SMBus.~{INT}")
		(layer "In2.Cu")
		(name "$teardrop_padvia$")
		(hatch none 0.1)
		(priority 30040)
		(attr
			(teardrop
				(type padvia)
			)
		)
		(connect_pads yes
			(clearance 0)
		)
		(min_thickness 0.0254)
		(filled_areas_thickness no)
		(fill yes
			(thermal_gap 0.5)
			(thermal_bridge_width 0.5)
			(island_removal_mode 1)
			(island_area_min 10)
		)
		(polygon
			(pts
				(xy 185.455328 158.543715) (xy 185.50193 158.583773) (xy 185.544419 158.60874) (xy 185.633268 158.634032)
				(xy 185.699644 158.64988) (xy 185.774997 158.687081) (xy 185.900707 158.500707) (xy 185.774997 158.312919)
				(xy 185.715239 158.371151) (xy 185.689315 158.405222) (xy 185.656146 158.447678) (xy 185.622824 158.476625)
				(xy 185.586347 158.482397) (xy 185.543715 158.455328)
			)
		)
	)
	(zone
		(net 365)
		(net_name "/Com Express 7 MGMT/PWR_OK")
		(layer "In2.Cu")
		(name "$teardrop_padvia$")
		(hatch none 0.1)
		(priority 30210)
		(attr
			(teardrop
				(type padvia)
			)
		)
		(connect_pads yes
			(clearance 0)
		)
		(min_thickness 0.0254)
		(filled_areas_thickness no)
		(fill yes
			(thermal_gap 0.5)
			(thermal_bridge_width 0.5)
			(island_removal_mode 1)
			(island_area_min 10)
		)
		(polygon
			(pts
				(xy 187.84164 158.469972) (xy 187.813738 158.491126) (xy 187.788305 158.497606) (xy 187.745755 158.480399)
				(xy 187.697485 158.431809) (xy 187.625003 158.362919) (xy 187.499293 158.550707) (xy 187.625003 158.737081)
				(xy 187.736439 158.679376) (xy 187.752309 158.673136) (xy 187.833597 158.635714) (xy 187.930028 158.55836)
			)
		)
	)
	(zone
		(net 136)
		(net_name "/Com Express 7 MGMT/~{TYPE0}")
		(layer "In2.Cu")
		(name "$teardrop_padvia$")
		(hatch none 0.1)
		(priority 30129)
		(attr
			(teardrop
				(type padvia)
			)
		)
		(connect_pads yes
			(clearance 0)
		)
		(min_thickness 0.0254)
		(filled_areas_thickness no)
		(fill yes
			(thermal_gap 0.5)
			(thermal_bridge_width 0.5)
			(island_removal_mode 1)
			(island_area_min 10)
		)
		(polygon
			(pts
				(xy 202.814127 155.047485) (xy 202.761618 155.093181) (xy 202.715623 155.119768) (xy 202.629174 155.140152)
				(xy 202.613841 155.141988) (xy 202.531105 155.154323) (xy 202.574293 155.375707) (xy 202.795677 155.418895)
				(xy 202.808011 155.33616) (xy 202.828349 155.238881) (xy 202.855057 155.190841) (xy 202.902515 155.135873)
			)
		)
	)
	(zone
		(net 747)
		(net_name "Net-(U45C-PRBS_{PASS})")
		(layer "In2.Cu")
		(name "$teardrop_padvia$")
		(hatch none 0.1)
		(priority 30128)
		(attr
			(teardrop
				(type padvia)
			)
		)
		(connect_pads yes
			(clearance 0)
		)
		(min_thickness 0.0254)
		(filled_areas_thickness no)
		(fill yes
			(thermal_gap 0.5)
			(thermal_bridge_width 0.5)
			(island_removal_mode 1)
			(island_area_min 10)
		)
		(polygon
			(pts
				(xy 130.529127 139.532485) (xy 130.476618 139.578181) (xy 130.430623 139.604768) (xy 130.344174 139.625152)
				(xy 130.328841 139.626988) (xy 130.246105 139.639323) (xy 130.289293 139.860707) (xy 130.510677 139.903895)
				(xy 130.523011 139.82116) (xy 130.543349 139.723881) (xy 130.570057 139.675841) (xy 130.617515 139.620873)
			)
		)
	)
	(zone
		(net 53)
		(net_name "/2xSFP+/SH")
		(layer "In2.Cu")
		(name "$teardrop_padvia$")
		(hatch none 0.1)
		(priority 30001)
		(attr
			(teardrop
				(type padvia)
			)
		)
		(connect_pads yes
			(clearance 0)
		)
		(min_thickness 0.0254)
		(filled_areas_thickness no)
		(fill yes
			(thermal_gap 0.5)
			(thermal_bridge_width 0.5)
			(island_removal_mode 1)
			(island_area_min 10)
		)
		(polygon
			(pts
				(xy 151.9 164.974411) (xy 151.895126 165.098176) (xy 151.881004 165.203134) (xy 151.859911 165.28777)
				(xy 151.831905 165.361356) (xy 151.753799 165.491569) (xy 151.639943 165.626202) (xy 151.537104 165.744597)
				(xy 151.426398 165.893322) (xy 152.05 166.311) (xy 152.673602 165.893322) (xy 152.529406 165.704772)
				(xy 152.460057 165.626203) (xy 152.355583 165.503925) (xy 152.273282 165.372511) (xy 152.242384 165.294951)
				(xy 152.219354 165.204995) (xy 152.204968 165.099272) (xy 152.2 164.974411)
			)
		)
	)
	(zone
		(net 491)
		(net_name "/2xSFP+/MDIO0.MDIO")
		(layer "In2.Cu")
		(name "$teardrop_padvia$")
		(hatch none 0.1)
		(priority 30032)
		(attr
			(teardrop
				(type padvia)
			)
		)
		(connect_pads yes
			(clearance 0)
		)
		(min_thickness 0.0254)
		(filled_areas_thickness no)
		(fill yes
			(thermal_gap 0.5)
			(thermal_bridge_width 0.5)
			(island_removal_mode 1)
			(island_area_min 10)
		)
		(polygon
			(pts
				(xy 143.902057 152.109554) (xy 143.718876 152.30903) (xy 143.670319 152.366596) (xy 143.838293 152.510707)
				(xy 144.059677 152.466105) (xy 144.029631 152.395341) (xy 144.000927 152.35458) (xy 143.974341 152.316593)
				(xy 143.958314 152.279446) (xy 143.960974 152.240707) (xy 143.990446 152.197943)
			)
		)
	)
	(zone
		(net 344)
		(net_name "/Com Express 7 MGMT/SER0.TX")
		(layer "In2.Cu")
		(name "$teardrop_padvia$")
		(hatch none 0.1)
		(priority 30199)
		(attr
			(teardrop
				(type padvia)
			)
		)
		(connect_pads yes
			(clearance 0)
		)
		(min_thickness 0.0254)
		(filled_areas_thickness no)
		(fill yes
			(thermal_gap 0.5)
			(thermal_bridge_width 0.5)
			(island_removal_mode 1)
			(island_area_min 10)
		)
		(polygon
			(pts
				(xy 164.127515 106.139127) (xy 164.081819 106.086618) (xy 164.055231 106.040623) (xy 164.034847 105.954175)
				(xy 164.033011 105.93884) (xy 164.020677 105.856105) (xy 163.799293 105.899293) (xy 163.756105 106.120677)
				(xy 163.83884 106.133011) (xy 163.936119 106.153349) (xy 163.984159 106.180057) (xy 164.039127 106.227515)
			)
		)
	)
	(zone
		(net 528)
		(net_name "/Backplane/~{PERST}")
		(layer "In2.Cu")
		(name "$teardrop_padvia$")
		(hatch none 0.1)
		(priority 30120)
		(attr
			(teardrop
				(type padvia)
			)
		)
		(connect_pads yes
			(clearance 0)
		)
		(min_thickness 0.0254)
		(filled_areas_thickness no)
		(fill yes
			(thermal_gap 0.5)
			(thermal_bridge_width 0.5)
			(island_removal_mode 1)
			(island_area_min 10)
		)
		(polygon
			(pts
				(xy 143.370677 83.9975) (xy 143.301236 83.992682) (xy 143.249913 83.97896) (xy 143.174371 83.932246)
				(xy 143.162231 83.922701) (xy 143.095003 83.872919) (xy 142.969 84.06) (xy 143.095003 84.247081)
				(xy 143.162229 84.197299) (xy 143.245396 84.142894) (xy 143.298251 84.12781) (xy 143.370677 84.1225)
			)
		)
	)
	(zone
		(net 579)
		(net_name "/2xUSB3.0+RJ45/SH")
		(layer "In2.Cu")
		(hatch edge 0.5)
		(priority 20)
		(connect_pads
			(clearance 0.3)
		)
		(min_thickness 0.25)
		(filled_areas_thickness no)
		(fill yes
			(thermal_gap 0.2)
			(thermal_bridge_width 0.5)
			(smoothing fillet)
			(radius 0.5)
		)
		(polygon
			(pts
				(xy 117.3 116.31) (xy 117.3 114.01) (xy 113.6 110.31) (xy 106.35 110.31) (xy 105.6 109.56) (xy 105.6 101.21)
				(xy 106.35 100.46) (xy 113.55 100.46) (xy 117.3 96.71) (xy 117.3 94.41) (xy 101.45 94.41) (xy 101.45 116.31)
			)
		)
	)
	(zone
		(net 382)
		(net_name "Net-(J12D-~{CB_RESET})")
		(layer "In2.Cu")
		(name "$teardrop_padvia$")
		(hatch none 0.1)
		(priority 30193)
		(attr
			(teardrop
				(type padvia)
			)
		)
		(connect_pads yes
			(clearance 0)
		)
		(min_thickness 0.0254)
		(filled_areas_thickness no)
		(fill yes
			(thermal_gap 0.5)
			(thermal_bridge_width 0.5)
			(island_removal_mode 1)
			(island_area_min 10)
		)
		(polygon
			(pts
				(xy 203.527515 165.589127) (xy 203.481819 165.536618) (xy 203.455231 165.490623) (xy 203.434847 165.404175)
				(xy 203.433011 165.38884) (xy 203.420677 165.306105) (xy 203.199293 165.349293) (xy 203.156105 165.570677)
				(xy 203.23884 165.583011) (xy 203.336119 165.603349) (xy 203.384159 165.630057) (xy 203.439127 165.677515)
			)
		)
	)
	(zone
		(net 397)
		(net_name "/Com Express 7 MGMT/SPI.~{CS}")
		(layer "In2.Cu")
		(name "$teardrop_padvia$")
		(hatch none 0.1)
		(priority 30105)
		(attr
			(teardrop
				(type padvia)
			)
		)
		(connect_pads yes
			(clearance 0)
		)
		(min_thickness 0.0254)
		(filled_areas_thickness no)
		(fill yes
			(thermal_gap 0.5)
			(thermal_bridge_width 0.5)
			(island_removal_mode 1)
			(island_area_min 10)
		)
		(polygon
			(pts
				(xy 224.450677 164.2875) (xy 224.381236 164.282682) (xy 224.329913 164.26896) (xy 224.254371 164.222246)
				(xy 224.242231 164.212701) (xy 224.175003 164.162919) (xy 224.049 164.35) (xy 224.175003 164.537081)
				(xy 224.242229 164.487299) (xy 224.325396 164.432894) (xy 224.378251 164.41781) (xy 224.450677 164.4125)
			)
		)
	)
	(zone
		(net 491)
		(net_name "/2xSFP+/MDIO0.MDIO")
		(layer "In2.Cu")
		(name "$teardrop_padvia$")
		(hatch none 0.1)
		(priority 30170)
		(attr
			(teardrop
				(type padvia)
			)
		)
		(connect_pads yes
			(clearance 0)
		)
		(min_thickness 0.0254)
		(filled_areas_thickness no)
		(fill yes
			(thermal_gap 0.5)
			(thermal_bridge_width 0.5)
			(island_removal_mode 1)
			(island_area_min 10)
		)
		(polygon
			(pts
				(xy 194.710873 148.052515) (xy 194.763382 148.006819) (xy 194.809376 147.980231) (xy 194.895824 147.959847)
				(xy 194.91116 147.958011) (xy 194.993895 147.945677) (xy 194.950707 147.724293) (xy 194.729323 147.681105)
				(xy 194.716988 147.763841) (xy 194.696651 147.861119) (xy 194.669943 147.909159) (xy 194.622485 147.964127)
			)
		)
	)
	(zone
		(net 490)
		(net_name "/2xSFP+/MDIO1.MDIO")
		(layer "In2.Cu")
		(name "$teardrop_padvia$")
		(hatch none 0.1)
		(priority 30117)
		(attr
			(teardrop
				(type padvia)
			)
		)
		(connect_pads yes
			(clearance 0)
		)
		(min_thickness 0.0254)
		(filled_areas_thickness no)
		(fill yes
			(thermal_gap 0.5)
			(thermal_bridge_width 0.5)
			(island_removal_mode 1)
			(island_area_min 10)
		)
		(polygon
			(pts
				(xy 139.475677 153.4375) (xy 139.406236 153.432682) (xy 139.354913 153.41896) (xy 139.279371 153.372246)
				(xy 139.267231 153.362701) (xy 139.200003 153.312919) (xy 139.074 153.5) (xy 139.200003 153.687081)
				(xy 139.267229 153.637299) (xy 139.350396 153.582894) (xy 139.403251 153.56781) (xy 139.475677 153.5625)
			)
		)
	)
	(zone
		(net 359)
		(net_name "/Com Express 7 MGMT/SMBus.~{INT}")
		(layer "In2.Cu")
		(name "$teardrop_padvia$")
		(hatch none 0.1)
		(priority 30176)
		(attr
			(teardrop
				(type padvia)
			)
		)
		(connect_pads yes
			(clearance 0)
		)
		(min_thickness 0.0254)
		(filled_areas_thickness no)
		(fill yes
			(thermal_gap 0.5)
			(thermal_bridge_width 0.5)
			(island_removal_mode 1)
			(island_area_min 10)
		)
		(polygon
			(pts
				(xy 183.760873 145.827515) (xy 183.813382 145.781819) (xy 183.859376 145.755231) (xy 183.945824 145.734847)
				(xy 183.96116 145.733011) (xy 184.043895 145.720677) (xy 184.000707 145.499293) (xy 183.779323 145.456105)
				(xy 183.766988 145.538841) (xy 183.746651 145.636119) (xy 183.719943 145.684159) (xy 183.672485 145.739127)
			)
		)
	)
	(zone
		(net 314)
		(net_name "/2xUSB3.0+RJ45/FLG_1")
		(layer "In2.Cu")
		(name "$teardrop_padvia$")
		(hatch none 0.1)
		(priority 30126)
		(attr
			(teardrop
				(type padvia)
			)
		)
		(connect_pads yes
			(clearance 0)
		)
		(min_thickness 0.0254)
		(filled_areas_thickness no)
		(fill yes
			(thermal_gap 0.5)
			(thermal_bridge_width 0.5)
			(island_removal_mode 1)
			(island_area_min 10)
		)
		(polygon
			(pts
				(xy 197.839127 167.072485) (xy 197.786618 167.118181) (xy 197.740623 167.144768) (xy 197.654174 167.165152)
				(xy 197.638841 167.166988) (xy 197.556105 167.179323) (xy 197.599293 167.400707) (xy 197.820677 167.443895)
				(xy 197.833011 167.36116) (xy 197.853349 167.263881) (xy 197.880057 167.215841) (xy 197.927515 167.160873)
			)
		)
	)
	(zone
		(net 531)
		(net_name "/Com Express 7 Interfaces/SD_CD")
		(layer "In2.Cu")
		(name "$teardrop_padvia$")
		(hatch none 0.1)
		(priority 30163)
		(attr
			(teardrop
				(type padvia)
			)
		)
		(connect_pads yes
			(clearance 0)
		)
		(min_thickness 0.0254)
		(filled_areas_thickness no)
		(fill yes
			(thermal_gap 0.5)
			(thermal_bridge_width 0.5)
			(island_removal_mode 1)
			(island_area_min 10)
		)
		(polygon
			(pts
				(xy 206.697485 163.935873) (xy 206.743181 163.988382) (xy 206.769768 164.034376) (xy 206.790152 164.120825)
				(xy 206.791988 164.136158) (xy 206.804323 164.218895) (xy 207.025707 164.175707) (xy 207.068895 163.954323)
				(xy 206.986158 163.941988) (xy 206.88888 163.921651) (xy 206.84084 163.894943) (xy 206.785873 163.847485)
			)
		)
	)
	(zone
		(net 288)
		(net_name "/2xUSB3.0+RJ45/~{GBE0_LINK_1000}")
		(layer "In2.Cu")
		(name "$teardrop_padvia$")
		(hatch none 0.1)
		(priority 30123)
		(attr
			(teardrop
				(type padvia)
			)
		)
		(connect_pads yes
			(clearance 0)
		)
		(min_thickness 0.0254)
		(filled_areas_thickness no)
		(fill yes
			(thermal_gap 0.5)
			(thermal_bridge_width 0.5)
			(island_removal_mode 1)
			(island_area_min 10)
		)
		(polygon
			(pts
				(xy 145.600677 152.2375) (xy 145.531236 152.232682) (xy 145.479913 152.21896) (xy 145.404371 152.172246)
				(xy 145.392231 152.162701) (xy 145.325003 152.112919) (xy 145.199 152.3) (xy 145.325003 152.487081)
				(xy 145.392229 152.437299) (xy 145.475396 152.382894) (xy 145.528251 152.36781) (xy 145.600677 152.3625)
			)
		)
	)
	(zone
		(net 288)
		(net_name "/2xUSB3.0+RJ45/~{GBE0_LINK_1000}")
		(layer "In2.Cu")
		(name "$teardrop_padvia$")
		(hatch none 0.1)
		(priority 30161)
		(attr
			(teardrop
				(type padvia)
			)
		)
		(connect_pads yes
			(clearance 0)
		)
		(min_thickness 0.0254)
		(filled_areas_thickness no)
		(fill yes
			(thermal_gap 0.5)
			(thermal_bridge_width 0.5)
			(island_removal_mode 1)
			(island_area_min 10)
		)
		(polygon
			(pts
				(xy 177.672485 169.760873) (xy 177.718181 169.813382) (xy 177.744768 169.859376) (xy 177.765152 169.945825)
				(xy 177.766988 169.961158) (xy 177.779323 170.043895) (xy 178.000707 170.000707) (xy 178.043895 169.779323)
				(xy 177.961158 169.766988) (xy 177.86388 169.746651) (xy 177.81584 169.719943) (xy 177.760873 169.672485)
			)
		)
	)
	(zone
		(net 429)
		(net_name "/2xSFP+/MDIO1.MDC")
		(layer "In2.Cu")
		(name "$teardrop_padvia$")
		(hatch none 0.1)
		(priority 30104)
		(attr
			(teardrop
				(type padvia)
			)
		)
		(connect_pads yes
			(clearance 0)
		)
		(min_thickness 0.0254)
		(filled_areas_thickness no)
		(fill yes
			(thermal_gap 0.5)
			(thermal_bridge_width 0.5)
			(island_removal_mode 1)
			(island_area_min 10)
		)
		(polygon
			(pts
				(xy 198.600677 154.8875) (xy 198.531236 154.882682) (xy 198.479913 154.86896) (xy 198.404371 154.822246)
				(xy 198.392231 154.812701) (xy 198.325003 154.762919) (xy 198.199 154.95) (xy 198.325003 155.137081)
				(xy 198.392229 155.087299) (xy 198.475396 155.032894) (xy 198.528251 155.01781) (xy 198.600677 155.0125)
			)
		)
	)
	(zone
		(net 430)
		(net_name "/2xSFP+/MDIO0.MDC")
		(layer "In2.Cu")
		(name "$teardrop_padvia$")
		(hatch none 0.1)
		(priority 30070)
		(attr
			(teardrop
				(type padvia)
			)
		)
		(connect_pads yes
			(clearance 0)
		)
		(min_thickness 0.0254)
		(filled_areas_thickness no)
		(fill yes
			(thermal_gap 0.5)
			(thermal_bridge_width 0.5)
			(island_removal_mode 1)
			(island_area_min 10)
		)
		(polygon
			(pts
				(xy 200.699323 153.7625) (xy 200.768764 153.767318) (xy 200.820088 153.78104) (xy 200.895629 153.827755)
				(xy 200.907769 153.837299) (xy 200.974997 153.887081) (xy 201.101 153.7) (xy 200.974997 153.512919)
				(xy 200.907768 153.562702) (xy 200.824602 153.617106) (xy 200.771748 153.63219) (xy 200.699323 153.6375)
			)
		)
	)
	(zone
		(net 288)
		(net_name "/2xUSB3.0+RJ45/~{GBE0_LINK_1000}")
		(layer "In2.Cu")
		(name "$teardrop_padvia$")
		(hatch none 0.1)
		(priority 30116)
		(attr
			(teardrop
				(type padvia)
			)
		)
		(connect_pads yes
			(clearance 0)
		)
		(min_thickness 0.0254)
		(filled_areas_thickness no)
		(fill yes
			(thermal_gap 0.5)
			(thermal_bridge_width 0.5)
			(island_removal_mode 1)
			(island_area_min 10)
		)
		(polygon
			(pts
				(xy 126.900677 111.1375) (xy 126.831236 111.132682) (xy 126.779913 111.11896) (xy 126.704371 111.072246)
				(xy 126.692231 111.062701) (xy 126.625003 111.012919) (xy 126.499 111.2) (xy 126.625003 111.387081)
				(xy 126.692229 111.337299) (xy 126.775396 111.282894) (xy 126.828251 111.26781) (xy 126.900677 111.2625)
			)
		)
	)
	(zone
		(net 945)
		(net_name "/GPIO expander/GPIOEX5")
		(layer "In2.Cu")
		(name "$teardrop_padvia$")
		(hatch none 0.1)
		(priority 30179)
		(attr
			(teardrop
				(type padvia)
			)
		)
		(connect_pads yes
			(clearance 0)
		)
		(min_thickness 0.0254)
		(filled_areas_thickness no)
		(fill yes
			(thermal_gap 0.5)
			(thermal_bridge_width 0.5)
			(island_removal_mode 1)
			(island_area_min 10)
		)
		(polygon
			(pts
				(xy 197.460873 132.527515) (xy 197.513382 132.481819) (xy 197.559376 132.455231) (xy 197.645824 132.434847)
				(xy 197.66116 132.433011) (xy 197.743895 132.420677) (xy 197.700707 132.199293) (xy 197.479323 132.156105)
				(xy 197.466988 132.238841) (xy 197.446651 132.336119) (xy 197.419943 132.384159) (xy 197.372485 132.439127)
			)
		)
	)
	(zone
		(net 372)
		(net_name "/Com Express 7 MGMT/I2C.SDA")
		(layer "In2.Cu")
		(name "$teardrop_padvia$")
		(hatch none 0.1)
		(priority 30144)
		(attr
			(teardrop
				(type padvia)
			)
		)
		(connect_pads yes
			(clearance 0)
		)
		(min_thickness 0.0254)
		(filled_areas_thickness no)
		(fill yes
			(thermal_gap 0.5)
			(thermal_bridge_width 0.5)
			(island_removal_mode 1)
			(island_area_min 10)
		)
		(polygon
			(pts
				(xy 193.264127 161.422485) (xy 193.211618 161.468181) (xy 193.165623 161.494768) (xy 193.079174 161.515152)
				(xy 193.063841 161.516988) (xy 192.981105 161.529323) (xy 193.024293 161.750707) (xy 193.245677 161.793895)
				(xy 193.258011 161.71116) (xy 193.278349 161.613881) (xy 193.305057 161.565841) (xy 193.352515 161.510873)
			)
		)
	)
	(zone
		(net 357)
		(net_name "/Com Express 7 MGMT/SMBus.SCL")
		(layer "In2.Cu")
		(name "$teardrop_padvia$")
		(hatch none 0.1)
		(priority 30146)
		(attr
			(teardrop
				(type padvia)
			)
		)
		(connect_pads yes
			(clearance 0)
		)
		(min_thickness 0.0254)
		(filled_areas_thickness no)
		(fill yes
			(thermal_gap 0.5)
			(thermal_bridge_width 0.5)
			(island_removal_mode 1)
			(island_area_min 10)
		)
		(polygon
			(pts
				(xy 121.339127 152.397485) (xy 121.286618 152.443181) (xy 121.240623 152.469768) (xy 121.154174 152.490152)
				(xy 121.138841 152.491988) (xy 121.056105 152.504323) (xy 121.099293 152.725707) (xy 121.320677 152.768895)
				(xy 121.333011 152.68616) (xy 121.353349 152.588881) (xy 121.380057 152.540841) (xy 121.427515 152.485873)
			)
		)
	)
	(zone
		(net 338)
		(net_name "/Com Express 7 MGMT/SPI.MISO")
		(layer "In2.Cu")
		(name "$teardrop_padvia$")
		(hatch none 0.1)
		(priority 30033)
		(attr
			(teardrop
				(type padvia)
			)
		)
		(connect_pads yes
			(clearance 0)
		)
		(min_thickness 0.0254)
		(filled_areas_thickness no)
		(fill yes
			(thermal_gap 0.5)
			(thermal_bridge_width 0.5)
			(island_removal_mode 1)
			(island_area_min 10)
		)
		(polygon
			(pts
				(xy 221.435 166.899323) (xy 221.430171 166.969836) (xy 221.416371 167.021853) (xy 221.360434 167.11016)
				(xy 221.312919 167.174997) (xy 221.5 167.301) (xy 221.687081 167.174997) (xy 221.639567 167.110162)
				(xy 221.585196 167.025715) (xy 221.570243 166.972386) (xy 221.565 166.899323)
			)
		)
	)
	(zone
		(net 530)
		(net_name "/M.2 key M #2/~{CLKREQ}")
		(layer "In2.Cu")
		(name "$teardrop_padvia$")
		(hatch none 0.1)
		(priority 30062)
		(attr
			(teardrop
				(type padvia)
			)
		)
		(connect_pads yes
			(clearance 0)
		)
		(min_thickness 0.0254)
		(filled_areas_thickness no)
		(fill yes
			(thermal_gap 0.5)
			(thermal_bridge_width 0.5)
			(island_removal_mode 1)
			(island_area_min 10)
		)
		(polygon
			(pts
				(xy 298.799323 83.5925) (xy 298.868764 83.597318) (xy 298.920088 83.61104) (xy 298.995629 83.657755)
				(xy 299.007769 83.667299) (xy 299.074997 83.717081) (xy 299.201 83.53) (xy 299.074997 83.342919)
				(xy 299.007768 83.392702) (xy 298.924602 83.447106) (xy 298.871748 83.46219) (xy 298.799323 83.4675)
			)
		)
	)
	(zone
		(net 207)
		(net_name "/Backplane/UART.TX")
		(layer "In2.Cu")
		(name "$teardrop_padvia$")
		(hatch none 0.1)
		(priority 30109)
		(attr
			(teardrop
				(type padvia)
			)
		)
		(connect_pads yes
			(clearance 0)
		)
		(min_thickness 0.0254)
		(filled_areas_thickness no)
		(fill yes
			(thermal_gap 0.5)
			(thermal_bridge_width 0.5)
			(island_removal_mode 1)
			(island_area_min 10)
		)
		(polygon
			(pts
				(xy 231.600677 170.8375) (xy 231.531236 170.832682) (xy 231.479913 170.81896) (xy 231.404371 170.772246)
				(xy 231.392231 170.762701) (xy 231.325003 170.712919) (xy 231.199 170.9) (xy 231.325003 171.087081)
				(xy 231.392229 171.037299) (xy 231.475396 170.982894) (xy 231.528251 170.96781) (xy 231.600677 170.9625)
			)
		)
	)
	(zone
		(net 358)
		(net_name "/Com Express 7 MGMT/SMBus.SDA")
		(layer "In2.Cu")
		(name "$teardrop_padvia$")
		(hatch none 0.1)
		(priority 30173)
		(attr
			(teardrop
				(type padvia)
			)
		)
		(connect_pads yes
			(clearance 0)
		)
		(min_thickness 0.0254)
		(filled_areas_thickness no)
		(fill yes
			(thermal_gap 0.5)
			(thermal_bridge_width 0.5)
			(island_removal_mode 1)
			(island_area_min 10)
		)
		(polygon
			(pts
				(xy 120.385873 152.552515) (xy 120.438382 152.506819) (xy 120.484376 152.480231) (xy 120.570824 152.459847)
				(xy 120.58616 152.458011) (xy 120.668895 152.445677) (xy 120.625707 152.224293) (xy 120.404323 152.181105)
				(xy 120.391988 152.263841) (xy 120.371651 152.361119) (xy 120.344943 152.409159) (xy 120.297485 152.464127)
			)
		)
	)
	(zone
		(net 530)
		(net_name "/M.2 key M #2/~{CLKREQ}")
		(layer "In2.Cu")
		(name "$teardrop_padvia$")
		(hatch none 0.1)
		(priority 30149)
		(attr
			(teardrop
				(type padvia)
			)
		)
		(connect_pads yes
			(clearance 0)
		)
		(min_thickness 0.0254)
		(filled_areas_thickness no)
		(fill yes
			(thermal_gap 0.5)
			(thermal_bridge_width 0.5)
			(island_removal_mode 1)
			(island_area_min 10)
		)
		(polygon
			(pts
				(xy 223.399127 127.872485) (xy 223.346618 127.918181) (xy 223.300623 127.944768) (xy 223.214174 127.965152)
				(xy 223.198841 127.966988) (xy 223.116105 127.979323) (xy 223.159293 128.200707) (xy 223.380677 128.243895)
				(xy 223.393011 128.16116) (xy 223.413349 128.063881) (xy 223.440057 128.015841) (xy 223.487515 127.960873)
			)
		)
	)
	(zone
		(net 385)
		(net_name "/Com Express 7 Interfaces/SDIO.CMD")
		(layer "In2.Cu")
		(name "$teardrop_padvia$")
		(hatch none 0.1)
		(priority 30018)
		(attr
			(teardrop
				(type padvia)
			)
		)
		(connect_pads yes
			(clearance 0)
		)
		(min_thickness 0.0254)
		(filled_areas_thickness no)
		(fill yes
			(thermal_gap 0.5)
			(thermal_bridge_width 0.5)
			(island_removal_mode 1)
			(island_area_min 10)
		)
		(polygon
			(pts
				(xy 165.261879 161.77148) (xy 165.306901 161.823136) (xy 165.334795 161.869182) (xy 165.363406 161.966971)
				(xy 165.394742 162.08112) (xy 165.600707 162.000707) (xy 165.68112 161.794742) (xy 165.566971 161.763406)
				(xy 165.474573 161.7373) (xy 165.426086 161.709044) (xy 165.37148 161.661879)
			)
		)
	)
	(zone
		(net 208)
		(net_name "/Backplane/UART.RX")
		(layer "In2.Cu")
		(name "$teardrop_padvia$")
		(hatch none 0.1)
		(priority 30082)
		(attr
			(teardrop
				(type padvia)
			)
		)
		(connect_pads yes
			(clearance 0)
		)
		(min_thickness 0.0254)
		(filled_areas_thickness no)
		(fill yes
			(thermal_gap 0.5)
			(thermal_bridge_width 0.5)
			(island_removal_mode 1)
			(island_area_min 10)
		)
		(polygon
			(pts
				(xy 312.099323 169.2475) (xy 312.168764 169.252318) (xy 312.220088 169.26604) (xy 312.295629 169.312755)
				(xy 312.307769 169.322299) (xy 312.374997 169.372081) (xy 312.501 169.185) (xy 312.374997 168.997919)
				(xy 312.307768 169.047702) (xy 312.224602 169.102106) (xy 312.171748 169.11719) (xy 312.099323 169.1225)
			)
		)
	)
	(zone
		(net 303)
		(net_name "/Com Express 7 MGMT/~{SUS_S5}")
		(layer "In2.Cu")
		(name "$teardrop_padvia$")
		(hatch none 0.1)
		(priority 30045)
		(attr
			(teardrop
				(type padvia)
			)
		)
		(connect_pads yes
			(clearance 0)
		)
		(min_thickness 0.0254)
		(filled_areas_thickness no)
		(fill yes
			(thermal_gap 0.5)
			(thermal_bridge_width 0.5)
			(island_removal_mode 1)
			(island_area_min 10)
		)
		(polygon
			(pts
				(xy 245.7375 132.433322) (xy 245.732682 132.502762) (xy 245.71896 132.554086) (xy 245.672245 132.629627)
				(xy 245.662702 132.641767) (xy 245.612919 132.708996) (xy 245.8 132.834999) (xy 245.987081 132.708996)
				(xy 245.937299 132.641768) (xy 245.882894 132.558602) (xy 245.86781 132.505747) (xy 245.8625 132.433322)
			)
		)
	)
	(zone
		(net 526)
		(net_name "/Backplane/~{PRSNT}")
		(layer "In2.Cu")
		(name "$teardrop_padvia$")
		(hatch none 0.1)
		(priority 30196)
		(attr
			(teardrop
				(type padvia)
			)
		)
		(connect_pads yes
			(clearance 0)
		)
		(min_thickness 0.0254)
		(filled_areas_thickness no)
		(fill yes
			(thermal_gap 0.5)
			(thermal_bridge_width 0.5)
			(island_removal_mode 1)
			(island_area_min 10)
		)
		(polygon
			(pts
				(xy 130.477515 90.229127) (xy 130.431819 90.176618) (xy 130.405231 90.130623) (xy 130.384847 90.044175)
				(xy 130.383011 90.02884) (xy 130.370677 89.946105) (xy 130.149293 89.989293) (xy 130.106105 90.210677)
				(xy 130.18884 90.223011) (xy 130.286119 90.243349) (xy 130.334159 90.270057) (xy 130.389127 90.317515)
			)
		)
	)
	(zone
		(net 595)
		(net_name "/Misc/PWM_{SRCSEL}")
		(layer "In2.Cu")
		(name "$teardrop_padvia$")
		(hatch none 0.1)
		(priority 30191)
		(attr
			(teardrop
				(type padvia)
			)
		)
		(connect_pads yes
			(clearance 0)
		)
		(min_thickness 0.0254)
		(filled_areas_thickness no)
		(fill yes
			(thermal_gap 0.5)
			(thermal_bridge_width 0.5)
			(island_removal_mode 1)
			(island_area_min 10)
		)
		(polygon
			(pts
				(xy 257.878222 77.424127) (xy 257.832526 77.371618) (xy 257.805938 77.325623) (xy 257.785554 77.239175)
				(xy 257.783718 77.22384) (xy 257.771384 77.141105) (xy 257.55 77.184293) (xy 257.506812 77.405677)
				(xy 257.589547 77.418011) (xy 257.686826 77.438349) (xy 257.734866 77.465057) (xy 257.789834 77.512515)
			)
		)
	)
	(zone
		(net 422)
		(net_name "/2xSFP+/I2C_{LED}.SDA")
		(layer "In2.Cu")
		(name "$teardrop_padvia$")
		(hatch none 0.1)
		(priority 30206)
		(attr
			(teardrop
				(type padvia)
			)
		)
		(connect_pads yes
			(clearance 0)
		)
		(min_thickness 0.0254)
		(filled_areas_thickness no)
		(fill yes
			(thermal_gap 0.5)
			(thermal_bridge_width 0.5)
			(island_removal_mode 1)
			(island_area_min 10)
		)
		(polygon
			(pts
				(xy 176.902515 154.189127) (xy 176.856819 154.136618) (xy 176.830231 154.090623) (xy 176.809847 154.004175)
				(xy 176.808011 153.98884) (xy 176.795677 153.906105) (xy 176.574293 153.949293) (xy 176.531105 154.170677)
				(xy 176.61384 154.183011) (xy 176.711119 154.203349) (xy 176.759159 154.230057) (xy 176.814127 154.277515)
			)
		)
	)
	(zone
		(net 314)
		(net_name "/2xUSB3.0+RJ45/FLG_1")
		(layer "In2.Cu")
		(name "$teardrop_padvia$")
		(hatch none 0.1)
		(priority 30209)
		(attr
			(teardrop
				(type padvia)
			)
		)
		(connect_pads yes
			(clearance 0)
		)
		(min_thickness 0.0254)
		(filled_areas_thickness no)
		(fill yes
			(thermal_gap 0.5)
			(thermal_bridge_width 0.5)
			(island_removal_mode 1)
			(island_area_min 10)
		)
		(polygon
			(pts
				(xy 165.8125 159.147123) (xy 165.817272 159.112385) (xy 165.83068 159.089833) (xy 165.87286 159.072104)
				(xy 165.94204 159.072773) (xy 166.043895 159.070677) (xy 166 158.849) (xy 165.779323 158.806105)
				(xy 165.74162 158.923191) (xy 165.733216 158.941868) (xy 165.701383 159.02506) (xy 165.6875 159.147123)
			)
		)
	)
	(zone
		(net 315)
		(net_name "Net-(J12H-VCC_RTC)")
		(layer "In2.Cu")
		(name "$teardrop_padvia$")
		(hatch none 0.1)
		(priority 30026)
		(attr
			(teardrop
				(type padvia)
			)
		)
		(connect_pads yes
			(clearance 0)
		)
		(min_thickness 0.0254)
		(filled_areas_thickness no)
		(fill yes
			(thermal_gap 0.5)
			(thermal_bridge_width 0.5)
			(island_removal_mode 1)
			(island_area_min 10)
		)
		(polygon
			(pts
				(xy 218.435873 146.702515) (xy 218.480832 146.664265) (xy 218.521702 146.642073) (xy 218.598807 146.628696)
				(xy 218.629365 146.628759) (xy 218.743895 146.620677) (xy 218.700707 146.399293) (xy 218.501832 146.301761)
				(xy 218.457732 146.42244) (xy 218.425637 146.511845) (xy 218.395453 146.559655) (xy 218.347485 146.614127)
			)
		)
	)
	(zone
		(net 142)
		(net_name "/2xSFP+/PHY0_{RESET}")
		(layer "In2.Cu")
		(name "$teardrop_padvia$")
		(hatch none 0.1)
		(priority 30127)
		(attr
			(teardrop
				(type padvia)
			)
		)
		(connect_pads yes
			(clearance 0)
		)
		(min_thickness 0.0254)
		(filled_areas_thickness no)
		(fill yes
			(thermal_gap 0.5)
			(thermal_bridge_width 0.5)
			(island_removal_mode 1)
			(island_area_min 10)
		)
		(polygon
			(pts
				(xy 161.289127 152.872485) (xy 161.236618 152.918181) (xy 161.190623 152.944768) (xy 161.104174 152.965152)
				(xy 161.088841 152.966988) (xy 161.006105 152.979323) (xy 161.049293 153.200707) (xy 161.270677 153.243895)
				(xy 161.283011 153.16116) (xy 161.303349 153.063881) (xy 161.330057 153.015841) (xy 161.377515 152.960873)
			)
		)
	)
	(zone
		(net 341)
		(net_name "/Com Express 7 MGMT/SPI.MOSI")
		(layer "In2.Cu")
		(name "$teardrop_padvia$")
		(hatch none 0.1)
		(priority 30035)
		(attr
			(teardrop
				(type padvia)
			)
		)
		(connect_pads yes
			(clearance 0)
		)
		(min_thickness 0.0254)
		(filled_areas_thickness no)
		(fill yes
			(thermal_gap 0.5)
			(thermal_bridge_width 0.5)
			(island_removal_mode 1)
			(island_area_min 10)
		)
		(polygon
			(pts
				(xy 223.400677 166.835) (xy 223.330164 166.830171) (xy 223.278146 166.816371) (xy 223.189838 166.760433)
				(xy 223.125003 166.712919) (xy 222.999 166.9) (xy 223.125003 167.087081) (xy 223.189837 167.039568)
				(xy 223.274284 166.985196) (xy 223.327613 166.970243) (xy 223.400677 166.965)
			)
		)
	)
	(zone
		(net 529)
		(net_name "/M.2 key M #1/~{CLKREQ}")
		(layer "In2.Cu")
		(name "$teardrop_padvia$")
		(hatch none 0.1)
		(priority 30205)
		(attr
			(teardrop
				(type padvia)
			)
		)
		(connect_pads yes
			(clearance 0)
		)
		(min_thickness 0.0254)
		(filled_areas_thickness no)
		(fill yes
			(thermal_gap 0.5)
			(thermal_bridge_width 0.5)
			(island_removal_mode 1)
			(island_area_min 10)
		)
		(polygon
			(pts
				(xy 178.05733 106.094757) (xy 178.011634 106.042248) (xy 177.985046 105.996253) (xy 177.964662 105.909805)
				(xy 177.962826 105.89447) (xy 177.950492 105.811735) (xy 177.729108 105.854923) (xy 177.68592 106.076307)
				(xy 177.768655 106.088641) (xy 177.865934 106.108979) (xy 177.913974 106.135687) (xy 177.968942 106.183145)
			)
		)
	)
	(zone
		(net 207)
		(net_name "/Backplane/UART.TX")
		(layer "In2.Cu")
		(name "$teardrop_padvia$")
		(hatch none 0.1)
		(priority 30189)
		(attr
			(teardrop
				(type padvia)
			)
		)
		(connect_pads yes
			(clearance 0)
		)
		(min_thickness 0.0254)
		(filled_areas_thickness no)
		(fill yes
			(thermal_gap 0.5)
			(thermal_bridge_width 0.5)
			(island_removal_mode 1)
			(island_area_min 10)
		)
		(polygon
			(pts
				(xy 313.060873 169.537515) (xy 313.113382 169.491819) (xy 313.159376 169.465231) (xy 313.245824 169.444847)
				(xy 313.26116 169.443011) (xy 313.343895 169.430677) (xy 313.300707 169.209293) (xy 313.079323 169.166105)
				(xy 313.066988 169.248841) (xy 313.046651 169.346119) (xy 313.019943 169.394159) (xy 312.972485 169.449127)
			)
		)
	)
	(zone
		(net 945)
		(net_name "/GPIO expander/GPIOEX5")
		(layer "In2.Cu")
		(name "$teardrop_padvia$")
		(hatch none 0.1)
		(priority 30059)
		(attr
			(teardrop
				(type padvia)
			)
		)
		(connect_pads yes
			(clearance 0)
		)
		(min_thickness 0.0254)
		(filled_areas_thickness no)
		(fill yes
			(thermal_gap 0.5)
			(thermal_bridge_width 0.5)
			(island_removal_mode 1)
			(island_area_min 10)
		)
		(polygon
			(pts
				(xy 122.7875 160.159323) (xy 122.782682 160.228763) (xy 122.76896 160.280087) (xy 122.722245 160.355628)
				(xy 122.712702 160.367768) (xy 122.662919 160.434997) (xy 122.85 160.561) (xy 123.037081 160.434997)
				(xy 122.987299 160.367769) (xy 122.932894 160.284603) (xy 122.91781 160.231748) (xy 122.9125 160.159323)
			)
		)
	)
	(zone
		(net 339)
		(net_name "/Com Express 7 Interfaces/SDIO.CLK")
		(layer "In2.Cu")
		(name "$teardrop_padvia$")
		(hatch none 0.1)
		(priority 30017)
		(attr
			(teardrop
				(type padvia)
			)
		)
		(connect_pads yes
			(clearance 0)
		)
		(min_thickness 0.0254)
		(filled_areas_thickness no)
		(fill yes
			(thermal_gap 0.5)
			(thermal_bridge_width 0.5)
			(island_removal_mode 1)
			(island_area_min 10)
		)
		(polygon
			(pts
				(xy 221.661879 169.67148) (xy 221.706901 169.723136) (xy 221.734795 169.769182) (xy 221.763406 169.866971)
				(xy 221.794742 169.98112) (xy 222.000707 169.900707) (xy 222.08112 169.694742) (xy 221.966971 169.663406)
				(xy 221.874573 169.6373) (xy 221.826086 169.609044) (xy 221.77148 169.561879)
			)
		)
	)
	(zone
		(net 315)
		(net_name "Net-(J12H-VCC_RTC)")
		(layer "In2.Cu")
		(name "$teardrop_padvia$")
		(hatch none 0.1)
		(priority 30180)
		(attr
			(teardrop
				(type padvia)
			)
		)
		(connect_pads yes
			(clearance 0)
		)
		(min_thickness 0.0254)
		(filled_areas_thickness no)
		(fill yes
			(thermal_gap 0.5)
			(thermal_bridge_width 0.5)
			(island_removal_mode 1)
			(island_area_min 10)
		)
		(polygon
			(pts
				(xy 218.719873 83.178515) (xy 218.772382 83.132819) (xy 218.818376 83.106231) (xy 218.904824 83.085847)
				(xy 218.92016 83.084011) (xy 219.002895 83.071677) (xy 218.959707 82.850293) (xy 218.738323 82.807105)
				(xy 218.725988 82.889841) (xy 218.705651 82.987119) (xy 218.678943 83.035159) (xy 218.631485 83.090127)
			)
		)
	)
	(zone
		(net 528)
		(net_name "/Backplane/~{PERST}")
		(layer "In2.Cu")
		(name "$teardrop_padvia$")
		(hatch none 0.1)
		(priority 30081)
		(attr
			(teardrop
				(type padvia)
			)
		)
		(connect_pads yes
			(clearance 0)
		)
		(min_thickness 0.0254)
		(filled_areas_thickness no)
		(fill yes
			(thermal_gap 0.5)
			(thermal_bridge_width 0.5)
			(island_removal_mode 1)
			(island_area_min 10)
		)
		(polygon
			(pts
				(xy 308.349323 156.7725) (xy 308.418764 156.777318) (xy 308.470088 156.79104) (xy 308.545629 156.837755)
				(xy 308.557769 156.847299) (xy 308.624997 156.897081) (xy 308.751 156.71) (xy 308.624997 156.522919)
				(xy 308.557768 156.572702) (xy 308.474602 156.627106) (xy 308.421748 156.64219) (xy 308.349323 156.6475)
			)
		)
	)
	(zone
		(net 528)
		(net_name "/Backplane/~{PERST}")
		(layer "In2.Cu")
		(name "$teardrop_padvia$")
		(hatch none 0.1)
		(priority 30025)
		(attr
			(teardrop
				(type padvia)
			)
		)
		(connect_pads yes
			(clearance 0)
		)
		(min_thickness 0.0254)
		(filled_areas_thickness no)
		(fill yes
			(thermal_gap 0.5)
			(thermal_bridge_width 0.5)
			(island_removal_mode 1)
			(island_area_min 10)
		)
		(polygon
			(pts
				(xy 296.985873 84.862515) (xy 297.040694 84.814284) (xy 297.088784 84.78404) (xy 297.177562 84.752265)
				(xy 297.298238 84.708167) (xy 297.200707 84.509293) (xy 296.979323 84.466105) (xy 296.97124 84.580636)
				(xy 296.962848 84.674051) (xy 296.940833 84.721503) (xy 296.897485 84.774127)
			)
		)
	)
	(zone
		(net 358)
		(net_name "/Com Express 7 MGMT/SMBus.SDA")
		(layer "In2.Cu")
		(name "$teardrop_padvia$")
		(hatch none 0.1)
		(priority 30139)
		(attr
			(teardrop
				(type padvia)
			)
		)
		(connect_pads yes
			(clearance 0)
		)
		(min_thickness 0.0254)
		(filled_areas_thickness no)
		(fill yes
			(thermal_gap 0.5)
			(thermal_bridge_width 0.5)
			(island_removal_mode 1)
			(island_area_min 10)
		)
		(polygon
			(pts
				(xy 120.864127 151.897485) (xy 120.811618 151.943181) (xy 120.765623 151.969768) (xy 120.679174 151.990152)
				(xy 120.663841 151.991988) (xy 120.581105 152.004323) (xy 120.624293 152.225707) (xy 120.845677 152.268895)
				(xy 120.858011 152.18616) (xy 120.878349 152.088881) (xy 120.905057 152.040841) (xy 120.952515 151.985873)
			)
		)
	)
	(zone
		(net 296)
		(net_name "/2xUSB3.0+RJ45/GbE.CTREF")
		(layer "In2.Cu")
		(name "$teardrop_padvia$")
		(hatch none 0.1)
		(priority 30010)
		(attr
			(teardrop
				(type padvia)
			)
		)
		(connect_pads yes
			(clearance 0)
		)
		(min_thickness 0.0254)
		(filled_areas_thickness no)
		(fill yes
			(thermal_gap 0.5)
			(thermal_bridge_width 0.5)
			(island_removal_mode 1)
			(island_area_min 10)
		)
		(polygon
			(pts
				(xy 135.4 118.999323) (xy 135.395287 119.077234) (xy 135.3823 119.136018) (xy 135.340199 119.227048)
				(xy 135.2975 119.312221) (xy 135.5 119.401) (xy 135.7025 119.312221) (xy 135.659801 119.22705) (xy 135.617133 119.134217)
				(xy 135.604556 119.076078) (xy 135.6 118.999323)
			)
		)
	)
	(zone
		(net 291)
		(net_name "/2xUSB3.0+RJ45/~{GBE0_LINK}")
		(layer "In2.Cu")
		(name "$teardrop_padvia$")
		(hatch none 0.1)
		(priority 30177)
		(attr
			(teardrop
				(type padvia)
			)
		)
		(connect_pads yes
			(clearance 0)
		)
		(min_thickness 0.0254)
		(filled_areas_thickness no)
		(fill yes
			(thermal_gap 0.5)
			(thermal_bridge_width 0.5)
			(island_removal_mode 1)
			(island_area_min 10)
		)
		(polygon
			(pts
				(xy 179.260873 170.327515) (xy 179.313382 170.281819) (xy 179.359376 170.255231) (xy 179.445824 170.234847)
				(xy 179.46116 170.233011) (xy 179.543895 170.220677) (xy 179.500707 169.999293) (xy 179.279323 169.956105)
				(xy 179.266988 170.038841) (xy 179.246651 170.136119) (xy 179.219943 170.184159) (xy 179.172485 170.239127)
			)
		)
	)
	(zone
		(net 526)
		(net_name "/Backplane/~{PRSNT}")
		(layer "In2.Cu")
		(name "$teardrop_padvia$")
		(hatch none 0.1)
		(priority 30194)
		(attr
			(teardrop
				(type padvia)
			)
		)
		(connect_pads yes
			(clearance 0)
		)
		(min_thickness 0.0254)
		(filled_areas_thickness no)
		(fill yes
			(thermal_gap 0.5)
			(thermal_bridge_width 0.5)
			(island_removal_mode 1)
			(island_area_min 10)
		)
		(polygon
			(pts
				(xy 164.277515 112.289127) (xy 164.231819 112.236618) (xy 164.205231 112.190623) (xy 164.184847 112.104175)
				(xy 164.183011 112.08884) (xy 164.170677 112.006105) (xy 163.949293 112.049293) (xy 163.906105 112.270677)
				(xy 163.98884 112.283011) (xy 164.086119 112.303349) (xy 164.134159 112.330057) (xy 164.189127 112.377515)
			)
		)
	)
	(zone
		(net 323)
		(net_name "/Com Express 7 Interfaces/SDIO.DAT2")
		(layer "In2.Cu")
		(name "$teardrop_padvia$")
		(hatch none 0.1)
		(priority 30021)
		(attr
			(teardrop
				(type padvia)
			)
		)
		(connect_pads yes
			(clearance 0)
		)
		(min_thickness 0.0254)
		(filled_areas_thickness no)
		(fill yes
			(thermal_gap 0.5)
			(thermal_bridge_width 0.5)
			(island_removal_mode 1)
			(island_area_min 10)
		)
		(polygon
			(pts
				(xy 165.663121 163.92852) (xy 165.618098 163.876863) (xy 165.590204 163.830817) (xy 165.561593 163.733028)
				(xy 165.530257 163.618879) (xy 165.324293 163.699293) (xy 165.243879 163.905257) (xy 165.358028 163.936593)
				(xy 165.450426 163.962699) (xy 165.498913 163.990955) (xy 165.55352 164.038121)
			)
		)
	)
	(zone
		(net 400)
		(net_name "/Com Express 7 MGMT/FAN_PWM")
		(layer "In2.Cu")
		(name "$teardrop_padvia$")
		(hatch none 0.1)
		(priority 30185)
		(attr
			(teardrop
				(type padvia)
			)
		)
		(connect_pads yes
			(clearance 0)
		)
		(min_thickness 0.0254)
		(filled_areas_thickness no)
		(fill yes
			(thermal_gap 0.5)
			(thermal_bridge_width 0.5)
			(island_removal_mode 1)
			(island_area_min 10)
		)
		(polygon
			(pts
				(xy 233.831581 79.399515) (xy 233.88409 79.353819) (xy 233.930084 79.327231) (xy 234.016532 79.306847)
				(xy 234.031868 79.305011) (xy 234.114603 79.292677) (xy 234.071415 79.071293) (xy 233.850031 79.028105)
				(xy 233.837696 79.110841) (xy 233.817359 79.208119) (xy 233.790651 79.256159) (xy 233.743193 79.311127)
			)
		)
	)
	(zone
		(net 310)
		(net_name "/Com Express 7 MGMT/~{BIOS_DIS0}")
		(layer "In2.Cu")
		(name "$teardrop_padvia$")
		(hatch none 0.1)
		(priority 30039)
		(attr
			(teardrop
				(type padvia)
			)
		)
		(connect_pads yes
			(clearance 0)
		)
		(min_thickness 0.0254)
		(filled_areas_thickness no)
		(fill yes
			(thermal_gap 0.5)
			(thermal_bridge_width 0.5)
			(island_removal_mode 1)
			(island_area_min 10)
		)
		(polygon
			(pts
				(xy 189.306285 158.405328) (xy 189.27767 158.427179) (xy 189.252109 158.433673) (xy 189.21172 158.415674)
				(xy 189.160683 158.355221) (xy 189.121427 158.305177) (xy 189.075003 158.262919) (xy 188.949293 158.450707)
				(xy 189.075003 158.637081) (xy 189.166211 158.595094) (xy 189.216732 158.584032) (xy 189.300241 158.561137)
				(xy 189.345178 158.535819) (xy 189.394672 158.493715)
			)
		)
	)
	(zone
		(net 315)
		(net_name "Net-(J12H-VCC_RTC)")
		(layer "In2.Cu")
		(name "$teardrop_padvia$")
		(hatch none 0.1)
		(priority 30054)
		(attr
			(teardrop
				(type padvia)
			)
		)
		(connect_pads yes
			(clearance 0)
		)
		(min_thickness 0.0254)
		(filled_areas_thickness no)
		(fill yes
			(thermal_gap 0.5)
			(thermal_bridge_width 0.5)
			(island_removal_mode 1)
			(island_area_min 10)
		)
		(polygon
			(pts
				(xy 219.7375 142.499323) (xy 219.732682 142.568763) (xy 219.71896 142.620087) (xy 219.672245 142.695628)
				(xy 219.662702 142.707768) (xy 219.612919 142.774997) (xy 219.8 142.901) (xy 219.987081 142.774997)
				(xy 219.937299 142.707769) (xy 219.882894 142.624603) (xy 219.86781 142.571748) (xy 219.8625 142.499323)
			)
		)
	)
	(zone
		(net 400)
		(net_name "/Com Express 7 MGMT/FAN_PWM")
		(layer "In2.Cu")
		(name "$teardrop_padvia$")
		(hatch none 0.1)
		(priority 30200)
		(attr
			(teardrop
				(type padvia)
			)
		)
		(connect_pads yes
			(clearance 0)
		)
		(min_thickness 0.0254)
		(filled_areas_thickness no)
		(fill yes
			(thermal_gap 0.5)
			(thermal_bridge_width 0.5)
			(island_removal_mode 1)
			(island_area_min 10)
		)
		(polygon
			(pts
				(xy 226.427515 162.239127) (xy 226.381819 162.186618) (xy 226.355231 162.140623) (xy 226.334847 162.054175)
				(xy 226.333011 162.03884) (xy 226.320677 161.956105) (xy 226.099293 161.999293) (xy 226.056105 162.220677)
				(xy 226.13884 162.233011) (xy 226.236119 162.253349) (xy 226.284159 162.280057) (xy 226.339127 162.327515)
			)
		)
	)
	(zone
		(net 747)
		(net_name "Net-(U45C-PRBS_{PASS})")
		(layer "In2.Cu")
		(name "$teardrop_padvia$")
		(hatch none 0.1)
		(priority 30096)
		(attr
			(teardrop
				(type padvia)
			)
		)
		(connect_pads yes
			(clearance 0)
		)
		(min_thickness 0.0254)
		(filled_areas_thickness no)
		(fill yes
			(thermal_gap 0.5)
			(thermal_bridge_width 0.5)
			(island_removal_mode 1)
			(island_area_min 10)
		)
		(polygon
			(pts
				(xy 131.1025 130.540677) (xy 131.107318 130.471236) (xy 131.12104 130.419912) (xy 131.167755 130.34437)
				(xy 131.177299 130.332229) (xy 131.227081 130.265003) (xy 131.04 130.139) (xy 130.852919 130.265003)
				(xy 130.902701 130.332231) (xy 130.957106 130.415397) (xy 130.97219 130.468251) (xy 130.9775 130.540677)
			)
		)
	)
	(zone
		(net 874)
		(net_name "/2xSFP+/SDA1")
		(layer "In2.Cu")
		(name "$teardrop_padvia$")
		(hatch none 0.1)
		(priority 30085)
		(attr
			(teardrop
				(type padvia)
			)
		)
		(connect_pads yes
			(clearance 0)
		)
		(min_thickness 0.0254)
		(filled_areas_thickness no)
		(fill yes
			(thermal_gap 0.5)
			(thermal_bridge_width 0.5)
			(island_removal_mode 1)
			(island_area_min 10)
		)
		(polygon
			(pts
				(xy 176.399323 144.3625) (xy 176.468764 144.367318) (xy 176.520088 144.38104) (xy 176.595629 144.427755)
				(xy 176.607769 144.437299) (xy 176.674997 144.487081) (xy 176.801 144.3) (xy 176.674997 144.112919)
				(xy 176.607768 144.162702) (xy 176.524602 144.217106) (xy 176.471748 144.23219) (xy 176.399323 144.2375)
			)
		)
	)
	(zone
		(net 365)
		(net_name "/Com Express 7 MGMT/PWR_OK")
		(layer "In2.Cu")
		(name "$teardrop_padvia$")
		(hatch none 0.1)
		(priority 30187)
		(attr
			(teardrop
				(type padvia)
			)
		)
		(connect_pads yes
			(clearance 0)
		)
		(min_thickness 0.0254)
		(filled_areas_thickness no)
		(fill yes
			(thermal_gap 0.5)
			(thermal_bridge_width 0.5)
			(island_removal_mode 1)
			(island_area_min 10)
		)
		(polygon
			(pts
				(xy 202.710873 112.377515) (xy 202.763382 112.331819) (xy 202.809376 112.305231) (xy 202.895824 112.284847)
				(xy 202.91116 112.283011) (xy 202.993895 112.270677) (xy 202.950707 112.049293) (xy 202.729323 112.006105)
				(xy 202.716988 112.088841) (xy 202.696651 112.186119) (xy 202.669943 112.234159) (xy 202.622485 112.289127)
			)
		)
	)
	(zone
		(net 541)
		(net_name "Net-(Q9-B)")
		(layer "In2.Cu")
		(name "$teardrop_padvia$")
		(hatch none 0.1)
		(priority 30159)
		(attr
			(teardrop
				(type padvia)
			)
		)
		(connect_pads yes
			(clearance 0)
		)
		(min_thickness 0.0254)
		(filled_areas_thickness no)
		(fill yes
			(thermal_gap 0.5)
			(thermal_bridge_width 0.5)
			(island_removal_mode 1)
			(island_area_min 10)
		)
		(polygon
			(pts
				(xy 121.472485 142.570873) (xy 121.518181 142.623382) (xy 121.544768 142.669376) (xy 121.565152 142.755825)
				(xy 121.566988 142.771158) (xy 121.579323 142.853895) (xy 121.800707 142.810707) (xy 121.843895 142.589323)
				(xy 121.761158 142.576988) (xy 121.66388 142.556651) (xy 121.61584 142.529943) (xy 121.560873 142.482485)
			)
		)
	)
	(zone
		(net 340)
		(net_name "/Com Express 7 MGMT/SPI.CLK")
		(layer "In2.Cu")
		(name "$teardrop_padvia$")
		(hatch none 0.1)
		(priority 30034)
		(attr
			(teardrop
				(type padvia)
			)
		)
		(connect_pads yes
			(clearance 0)
		)
		(min_thickness 0.0254)
		(filled_areas_thickness no)
		(fill yes
			(thermal_gap 0.5)
			(thermal_bridge_width 0.5)
			(island_removal_mode 1)
			(island_area_min 10)
		)
		(polygon
			(pts
				(xy 222.435 166.899323) (xy 222.430171 166.969836) (xy 222.416371 167.021853) (xy 222.360434 167.11016)
				(xy 222.312919 167.174997) (xy 222.5 167.301) (xy 222.687081 167.174997) (xy 222.639567 167.110162)
				(xy 222.585196 167.025715) (xy 222.570243 166.972386) (xy 222.565 166.899323)
			)
		)
	)
	(zone
		(net 526)
		(net_name "/Backplane/~{PRSNT}")
		(layer "In2.Cu")
		(name "$teardrop_padvia$")
		(hatch none 0.1)
		(priority 30060)
		(attr
			(teardrop
				(type padvia)
			)
		)
		(connect_pads yes
			(clearance 0)
		)
		(min_thickness 0.0254)
		(filled_areas_thickness no)
		(fill yes
			(thermal_gap 0.5)
			(thermal_bridge_width 0.5)
			(island_removal_mode 1)
			(island_area_min 10)
		)
		(polygon
			(pts
				(xy 199.899323 121.8125) (xy 199.968764 121.817318) (xy 200.020088 121.83104) (xy 200.095629 121.877755)
				(xy 200.107769 121.887299) (xy 200.174997 121.937081) (xy 200.301 121.75) (xy 200.174997 121.562919)
				(xy 200.107768 121.612702) (xy 200.024602 121.667106) (xy 199.971748 121.68219) (xy 199.899323 121.6875)
			)
		)
	)
	(zone
		(net 930)
		(net_name "Net-(D5-C)")
		(layer "In2.Cu")
		(name "$teardrop_padvia$")
		(hatch none 0.1)
		(priority 30048)
		(attr
			(teardrop
				(type padvia)
			)
		)
		(connect_pads yes
			(clearance 0)
		)
		(min_thickness 0.0254)
		(filled_areas_thickness no)
		(fill yes
			(thermal_gap 0.5)
			(thermal_bridge_width 0.5)
			(island_removal_mode 1)
			(island_area_min 10)
		)
		(polygon
			(pts
				(xy 154.7565 166.959323) (xy 154.751682 167.028763) (xy 154.73796 167.080087) (xy 154.691245 167.155628)
				(xy 154.681702 167.167768) (xy 154.631919 167.234997) (xy 154.819 167.361) (xy 155.006081 167.234997)
				(xy 154.956299 167.167769) (xy 154.901894 167.084603) (xy 154.88681 167.031748) (xy 154.8815 166.959323)
			)
		)
	)
	(zone
		(net 340)
		(net_name "/Com Express 7 MGMT/SPI.CLK")
		(layer "In2.Cu")
		(name "$teardrop_padvia$")
		(hatch none 0.1)
		(priority 30037)
		(attr
			(teardrop
				(type padvia)
			)
		)
		(connect_pads yes
			(clearance 0)
		)
		(min_thickness 0.0254)
		(filled_areas_thickness no)
		(fill yes
			(thermal_gap 0.5)
			(thermal_bridge_width 0.5)
			(island_removal_mode 1)
			(island_area_min 10)
		)
		(polygon
			(pts
				(xy 248.037359 160.970717) (xy 247.984084 161.017163) (xy 247.937543 161.044186) (xy 247.835547 161.067075)
				(xy 247.756105 161.079323) (xy 247.799293 161.300707) (xy 248.020677 161.343895) (xy 248.032924 161.264454)
				(xy 248.054191 161.166294) (xy 248.081327 161.118012) (xy 248.129283 161.062641)
			)
		)
	)
	(zone
		(net 344)
		(net_name "/Com Express 7 MGMT/SER0.TX")
		(layer "In2.Cu")
		(name "$teardrop_padvia$")
		(hatch none 0.1)
		(priority 30166)
		(attr
			(teardrop
				(type padvia)
			)
		)
		(connect_pads yes
			(clearance 0)
		)
		(min_thickness 0.0254)
		(filled_areas_thickness no)
		(fill yes
			(thermal_gap 0.5)
			(thermal_bridge_width 0.5)
			(island_removal_mode 1)
			(island_area_min 10)
		)
		(polygon
			(pts
				(xy 216.372485 145.010873) (xy 216.418181 145.063382) (xy 216.444768 145.109376) (xy 216.465152 145.195825)
				(xy 216.466988 145.211158) (xy 216.479323 145.293895) (xy 216.700707 145.250707) (xy 216.743895 145.029323)
				(xy 216.661158 145.016988) (xy 216.56388 144.996651) (xy 216.51584 144.969943) (xy 216.460873 144.922485)
			)
		)
	)
	(zone
		(net 310)
		(net_name "/Com Express 7 MGMT/~{BIOS_DIS0}")
		(layer "In2.Cu")
		(name "$teardrop_padvia$")
		(hatch none 0.1)
		(priority 30130)
		(attr
			(teardrop
				(type padvia)
			)
		)
		(connect_pads yes
			(clearance 0)
		)
		(min_thickness 0.0254)
		(filled_areas_thickness no)
		(fill yes
			(thermal_gap 0.5)
			(thermal_bridge_width 0.5)
			(island_removal_mode 1)
			(island_area_min 10)
		)
		(polygon
			(pts
				(xy 218.039127 142.522485) (xy 217.986618 142.568181) (xy 217.940623 142.594768) (xy 217.854174 142.615152)
				(xy 217.838841 142.616988) (xy 217.756105 142.629323) (xy 217.799293 142.850707) (xy 218.020677 142.893895)
				(xy 218.033011 142.81116) (xy 218.053349 142.713881) (xy 218.080057 142.665841) (xy 218.127515 142.610873)
			)
		)
	)
	(zone
		(net 528)
		(net_name "/Backplane/~{PERST}")
		(layer "In2.Cu")
		(name "$teardrop_padvia$")
		(hatch none 0.1)
		(priority 30078)
		(attr
			(teardrop
				(type padvia)
			)
		)
		(connect_pads yes
			(clearance 0)
		)
		(min_thickness 0.0254)
		(filled_areas_thickness no)
		(fill yes
			(thermal_gap 0.5)
			(thermal_bridge_width 0.5)
			(island_removal_mode 1)
			(island_area_min 10)
		)
		(polygon
			(pts
				(xy 281.999323 103.2475) (xy 282.068764 103.252318) (xy 282.120088 103.26604) (xy 282.195629 103.312755)
				(xy 282.207769 103.322299) (xy 282.274997 103.372081) (xy 282.401 103.185) (xy 282.274997 102.997919)
				(xy 282.207768 103.047702) (xy 282.124602 103.102106) (xy 282.071748 103.11719) (xy 281.999323 103.1225)
			)
		)
	)
	(zone
		(net 429)
		(net_name "/2xSFP+/MDIO1.MDC")
		(layer "In2.Cu")
		(name "$teardrop_padvia$")
		(hatch none 0.1)
		(priority 30124)
		(attr
			(teardrop
				(type padvia)
			)
		)
		(connect_pads yes
			(clearance 0)
		)
		(min_thickness 0.0254)
		(filled_areas_thickness no)
		(fill yes
			(thermal_gap 0.5)
			(thermal_bridge_width 0.5)
			(island_removal_mode 1)
			(island_area_min 10)
		)
		(polygon
			(pts
				(xy 167.500677 142.7625) (xy 167.431236 142.757682) (xy 167.379913 142.74396) (xy 167.304371 142.697246)
				(xy 167.292231 142.687701) (xy 167.225003 142.637919) (xy 167.099 142.825) (xy 167.225003 143.012081)
				(xy 167.292229 142.962299) (xy 167.375396 142.907894) (xy 167.428251 142.89281) (xy 167.500677 142.8875)
			)
		)
	)
	(zone
		(net 333)
		(net_name "/Com Express 7 Interfaces/SDIO.DAT3")
		(layer "In2.Cu")
		(name "$teardrop_padvia$")
		(hatch none 0.1)
		(priority 30022)
		(attr
			(teardrop
				(type padvia)
			)
		)
		(connect_pads yes
			(clearance 0)
		)
		(min_thickness 0.0254)
		(filled_areas_thickness no)
		(fill yes
			(thermal_gap 0.5)
			(thermal_bridge_width 0.5)
			(island_removal_mode 1)
			(island_area_min 10)
		)
		(polygon
			(pts
				(xy 166.313121 162.90352) (xy 166.268098 162.851863) (xy 166.240204 162.805817) (xy 166.211593 162.708028)
				(xy 166.180257 162.593879) (xy 165.974293 162.674293) (xy 165.893879 162.880257) (xy 166.008028 162.911593)
				(xy 166.100426 162.937699) (xy 166.148913 162.965955) (xy 166.20352 163.013121)
			)
		)
	)
	(zone
		(net 288)
		(net_name "/2xUSB3.0+RJ45/~{GBE0_LINK_1000}")
		(layer "In2.Cu")
		(name "$teardrop_padvia$")
		(hatch none 0.1)
		(priority 30053)
		(attr
			(teardrop
				(type padvia)
			)
		)
		(connect_pads yes
			(clearance 0)
		)
		(min_thickness 0.0254)
		(filled_areas_thickness no)
		(fill yes
			(thermal_gap 0.5)
			(thermal_bridge_width 0.5)
			(island_removal_mode 1)
			(island_area_min 10)
		)
		(polygon
			(pts
				(xy 145.9375 149.199323) (xy 145.932682 149.268763) (xy 145.91896 149.320087) (xy 145.872245 149.395628)
				(xy 145.862702 149.407768) (xy 145.812919 149.474997) (xy 146 149.601) (xy 146.187081 149.474997)
				(xy 146.137299 149.407769) (xy 146.082894 149.324603) (xy 146.06781 149.271748) (xy 146.0625 149.199323)
			)
		)
	)
	(zone
		(net 382)
		(net_name "Net-(J12D-~{CB_RESET})")
		(layer "In2.Cu")
		(name "$teardrop_padvia$")
		(hatch none 0.1)
		(priority 30084)
		(attr
			(teardrop
				(type padvia)
			)
		)
		(connect_pads yes
			(clearance 0)
		)
		(min_thickness 0.0254)
		(filled_areas_thickness no)
		(fill yes
			(thermal_gap 0.5)
			(thermal_bridge_width 0.5)
			(island_removal_mode 1)
			(island_area_min 10)
		)
		(polygon
			(pts
				(xy 285.699323 153.3625) (xy 285.768764 153.367318) (xy 285.820088 153.38104) (xy 285.895629 153.427755)
				(xy 285.907769 153.437299) (xy 285.974997 153.487081) (xy 286.101 153.3) (xy 285.974997 153.112919)
				(xy 285.907768 153.162702) (xy 285.824602 153.217106) (xy 285.771748 153.23219) (xy 285.699323 153.2375)
			)
		)
	)
	(zone
		(net 135)
		(net_name "Net-(D19-Pad3)")
		(layer "In2.Cu")
		(name "$teardrop_padvia$")
		(hatch none 0.1)
		(priority 30006)
		(attr
			(teardrop
				(type padvia)
			)
		)
		(connect_pads yes
			(clearance 0)
		)
		(min_thickness 0.0254)
		(filled_areas_thickness no)
		(fill yes
			(thermal_gap 0.5)
			(thermal_bridge_width 0.5)
			(island_removal_mode 1)
			(island_area_min 10)
		)
		(polygon
			(pts
				(xy 308.560613 74.632745) (xy 308.667133 74.749068) (xy 308.727244 74.849517) (xy 308.744742 74.89112)
				(xy 308.950707 74.810707) (xy 309.03112 74.604742) (xy 308.938895 74.561142) (xy 308.856097 74.499865)
				(xy 308.772745 74.420613)
			)
		)
	)
	(zone
		(net 142)
		(net_name "/2xSFP+/PHY0_{RESET}")
		(layer "In2.Cu")
		(name "$teardrop_padvia$")
		(hatch none 0.1)
		(priority 30043)
		(attr
			(teardrop
				(type padvia)
			)
		)
		(connect_pads yes
			(clearance 0)
		)
		(min_thickness 0.0254)
		(filled_areas_thickness no)
		(fill yes
			(thermal_gap 0.5)
			(thermal_bridge_width 0.5)
			(island_removal_mode 1)
			(island_area_min 10)
		)
		(polygon
			(pts
				(xy 159.167485 147.515873) (xy 159.215627 147.570891) (xy 159.243489 147.618601) (xy 159.267333 147.720468)
				(xy 159.279323 147.793895) (xy 159.500707 147.750707) (xy 159.543895 147.529323) (xy 159.453217 147.51717)
				(xy 159.357666 147.499363) (xy 159.309996 147.473754) (xy 159.255873 147.427485)
			)
		)
	)
	(zone
		(net 490)
		(net_name "/2xSFP+/MDIO1.MDIO")
		(layer "In2.Cu")
		(name "$teardrop_padvia$")
		(hatch none 0.1)
		(priority 30183)
		(attr
			(teardrop
				(type padvia)
			)
		)
		(connect_pads yes
			(clearance 0)
		)
		(min_thickness 0.0254)
		(filled_areas_thickness no)
		(fill yes
			(thermal_gap 0.5)
			(thermal_bridge_width 0.5)
			(island_removal_mode 1)
			(island_area_min 10)
		)
		(polygon
			(pts
				(xy 196.585873 149.677515) (xy 196.638382 149.631819) (xy 196.684376 149.605231) (xy 196.770824 149.584847)
				(xy 196.78616 149.583011) (xy 196.868895 149.570677) (xy 196.825707 149.349293) (xy 196.604323 149.306105)
				(xy 196.591988 149.388841) (xy 196.571651 149.486119) (xy 196.544943 149.534159) (xy 196.497485 149.589127)
			)
		)
	)
	(zone
		(net 729)
		(net_name "Net-(U43C-AMUXB)")
		(layer "In2.Cu")
		(name "$teardrop_padvia$")
		(hatch none 0.1)
		(priority 30097)
		(attr
			(teardrop
				(type padvia)
			)
		)
		(connect_pads yes
			(clearance 0)
		)
		(min_thickness 0.0254)
		(filled_areas_thickness no)
		(fill yes
			(thermal_gap 0.5)
			(thermal_bridge_width 0.5)
			(island_removal_mode 1)
			(island_area_min 10)
		)
		(polygon
			(pts
				(xy 154.4625 130.540677) (xy 154.467318 130.471236) (xy 154.48104 130.419912) (xy 154.527755 130.34437)
				(xy 154.537299 130.332229) (xy 154.587081 130.265003) (xy 154.4 130.139) (xy 154.212919 130.265003)
				(xy 154.262701 130.332231) (xy 154.317106 130.415397) (xy 154.33219 130.468251) (xy 154.3375 130.540677)
			)
		)
	)
	(zone
		(net 310)
		(net_name "/Com Express 7 MGMT/~{BIOS_DIS0}")
		(layer "In2.Cu")
		(name "$teardrop_padvia$")
		(hatch none 0.1)
		(priority 30077)
		(attr
			(teardrop
				(type padvia)
			)
		)
		(connect_pads yes
			(clearance 0)
		)
		(min_thickness 0.0254)
		(filled_areas_thickness no)
		(fill yes
			(thermal_gap 0.5)
			(thermal_bridge_width 0.5)
			(island_removal_mode 1)
			(island_area_min 10)
		)
		(polygon
			(pts
				(xy 216.249323 82.3725) (xy 216.318764 82.377318) (xy 216.370088 82.39104) (xy 216.445629 82.437755)
				(xy 216.457769 82.447299) (xy 216.524997 82.497081) (xy 216.651 82.31) (xy 216.524997 82.122919)
				(xy 216.457768 82.172702) (xy 216.374602 82.227106) (xy 216.321748 82.24219) (xy 216.249323 82.2475)
			)
		)
	)
	(zone
		(net 291)
		(net_name "/2xUSB3.0+RJ45/~{GBE0_LINK}")
		(layer "In2.Cu")
		(name "$teardrop_padvia$")
		(hatch none 0.1)
		(priority 30165)
		(attr
			(teardrop
				(type padvia)
			)
		)
		(connect_pads yes
			(clearance 0)
		)
		(min_thickness 0.0254)
		(filled_areas_thickness no)
		(fill yes
			(thermal_gap 0.5)
			(thermal_bridge_width 0.5)
			(island_removal_mode 1)
			(island_area_min 10)
		)
		(polygon
			(pts
				(xy 144.872485 149.260873) (xy 144.918181 149.313382) (xy 144.944768 149.359376) (xy 144.965152 149.445825)
				(xy 144.966988 149.461158) (xy 144.979323 149.543895) (xy 145.200707 149.500707) (xy 145.243895 149.279323)
				(xy 145.161158 149.266988) (xy 145.06388 149.246651) (xy 145.01584 149.219943) (xy 144.960873 149.172485)
			)
		)
	)
	(zone
		(net 164)
		(net_name "/2xSFP+/SDA0")
		(layer "In2.Cu")
		(name "$teardrop_padvia$")
		(hatch none 0.1)
		(priority 30061)
		(attr
			(teardrop
				(type padvia)
			)
		)
		(connect_pads yes
			(clearance 0)
		)
		(min_thickness 0.0254)
		(filled_areas_thickness no)
		(fill yes
			(thermal_gap 0.5)
			(thermal_bridge_width 0.5)
			(island_removal_mode 1)
			(island_area_min 10)
		)
		(polygon
			(pts
				(xy 175.299323 142.7625) (xy 175.368764 142.767318) (xy 175.420088 142.78104) (xy 175.495629 142.827755)
				(xy 175.507769 142.837299) (xy 175.574997 142.887081) (xy 175.701 142.7) (xy 175.574997 142.512919)
				(xy 175.507768 142.562702) (xy 175.424602 142.617106) (xy 175.371748 142.63219) (xy 175.299323 142.6375)
			)
		)
	)
	(zone
		(net 58)
		(net_name "/USB-C console/VBUS_FTDI")
		(layer "In2.Cu")
		(name "$teardrop_padvia$")
		(hatch none 0.1)
		(priority 30004)
		(attr
			(teardrop
				(type padvia)
			)
		)
		(connect_pads yes
			(clearance 0)
		)
		(min_thickness 0.0254)
		(filled_areas_thickness no)
		(fill yes
			(thermal_gap 0.5)
			(thermal_bridge_width 0.5)
			(island_removal_mode 1)
			(island_area_min 10)
		)
		(polygon
			(pts
				(xy 120.322745 73.519387) (xy 120.439071 73.412864) (xy 120.539522 73.352752) (xy 120.58112 73.335257)
				(xy 120.500707 73.129293) (xy 120.294742 73.048879) (xy 120.251141 73.141105) (xy 120.189861 73.223905)
				(xy 120.110613 73.307255)
			)
		)
	)
	(zone
		(net 53)
		(net_name "/2xSFP+/SH")
		(layer "In2.Cu")
		(name "$teardrop_padvia$")
		(hatch none 0.1)
		(priority 30003)
		(attr
			(teardrop
				(type padvia)
			)
		)
		(connect_pads yes
			(clearance 0)
		)
		(min_thickness 0.0254)
		(filled_areas_thickness no)
		(fill yes
			(thermal_gap 0.5)
			(thermal_bridge_width 0.5)
			(island_removal_mode 1)
			(island_area_min 10)
		)
		(polygon
			(pts
				(xy 151.9 162.445589) (xy 151.904851 162.503441) (xy 151.918807 162.555639) (xy 151.971667 162.644672)
				(xy 152.057314 162.714617) (xy 152.176113 162.76215) (xy 152.321905 162.779096) (xy 152.399243 162.773409)
				(xy 152.47399 162.757855) (xy 152.54143 162.7336) (xy 152.602027 162.700388) (xy 152.648895 162.662956)
				(xy 152.686882 162.618458) (xy 152.713648 162.568862) (xy 152.075 162.311) (xy 151.386352 162.322316)
				(xy 151.406699 162.409112) (xy 151.466303 162.49452) (xy 151.570357 162.575933) (xy 151.716986 162.641763)
				(xy 151.800016 162.663138) (xy 151.88279 162.67398) (xy 151.957831 162.673703) (xy 152.02725 162.662416)
				(xy 152.080503 162.643275) (xy 152.125983 162.61488) (xy 152.157596 162.582682) (xy 152.181167 162.542946)
				(xy 152.194969 162.498811) (xy 152.199994 162.447578) (xy 152.2 162.445589)
			)
		)
	)
	(zone
		(net 945)
		(net_name "/GPIO expander/GPIOEX5")
		(layer "In2.Cu")
		(name "$teardrop_padvia$")
		(hatch none 0.1)
		(priority 30087)
		(attr
			(teardrop
				(type padvia)
			)
		)
		(connect_pads yes
			(clearance 0)
		)
		(min_thickness 0.0254)
		(filled_areas_thickness no)
		(fill yes
			(thermal_gap 0.5)
			(thermal_bridge_width 0.5)
			(island_removal_mode 1)
			(island_area_min 10)
		)
		(polygon
			(pts
				(xy 122.6125 148.100677) (xy 122.617318 148.031236) (xy 122.63104 147.979912) (xy 122.677755 147.90437)
				(xy 122.687299 147.892229) (xy 122.737081 147.825003) (xy 122.55 147.699) (xy 122.362919 147.825003)
				(xy 122.412701 147.892231) (xy 122.467106 147.975397) (xy 122.48219 148.028251) (xy 122.4875 148.100677)
			)
		)
	)
	(zone
		(net 385)
		(net_name "/Com Express 7 Interfaces/SDIO.CMD")
		(layer "In2.Cu")
		(name "$teardrop_padvia$")
		(hatch none 0.1)
		(priority 30019)
		(attr
			(teardrop
				(type padvia)
			)
		)
		(connect_pads yes
			(clearance 0)
		)
		(min_thickness 0.0254)
		(filled_areas_thickness no)
		(fill yes
			(thermal_gap 0.5)
			(thermal_bridge_width 0.5)
			(island_removal_mode 1)
			(island_area_min 10)
		)
		(polygon
			(pts
				(xy 202.211879 161.67148) (xy 202.256901 161.723136) (xy 202.284795 161.769182) (xy 202.313406 161.866971)
				(xy 202.344742 161.98112) (xy 202.550707 161.900707) (xy 202.63112 161.694742) (xy 202.516971 161.663406)
				(xy 202.424573 161.6373) (xy 202.376086 161.609044) (xy 202.32148 161.561879)
			)
		)
	)
	(zone
		(net 935)
		(net_name "Net-(D13-C)")
		(layer "In2.Cu")
		(name "$teardrop_padvia$")
		(hatch none 0.1)
		(priority 30029)
		(attr
			(teardrop
				(type padvia)
			)
		)
		(connect_pads yes
			(clearance 0)
		)
		(min_thickness 0.0254)
		(filled_areas_thickness no)
		(fill yes
			(thermal_gap 0.5)
			(thermal_bridge_width 0.5)
			(island_removal_mode 1)
			(island_area_min 10)
		)
		(polygon
			(pts
				(xy 177.184617 94.283005) (xy 177.261087 94.353061) (xy 177.321832 94.397189) (xy 177.364554 94.42348)
				(xy 177.469508 94.491592) (xy 177.600707 94.310707) (xy 177.545386 94.093762) (xy 177.478755 94.127235)
				(xy 177.429461 94.169794) (xy 177.392259 94.202532) (xy 177.355536 94.223499) (xy 177.316661 94.22382)
				(xy 177.273005 94.194617)
			)
		)
	)
	(zone
		(net 166)
		(net_name "Net-(J2A-MOD_{ABS})")
		(layer "In2.Cu")
		(name "$teardrop_padvia$")
		(hatch none 0.1)
		(priority 30072)
		(attr
			(teardrop
				(type padvia)
			)
		)
		(connect_pads yes
			(clearance 0)
		)
		(min_thickness 0.0254)
		(filled_areas_thickness no)
		(fill yes
			(thermal_gap 0.5)
			(thermal_bridge_width 0.5)
			(island_removal_mode 1)
			(island_area_min 10)
		)
		(polygon
			(pts
				(xy 176.799323 145.0625) (xy 176.868764 145.067318) (xy 176.920088 145.08104) (xy 176.995629 145.127755)
				(xy 177.007769 145.137299) (xy 177.074997 145.187081) (xy 177.201 145) (xy 177.074997 144.812919)
				(xy 177.007768 144.862702) (xy 176.924602 144.917106) (xy 176.871748 144.93219) (xy 176.799323 144.9375)
			)
		)
	)
	(zone
		(net 341)
		(net_name "/Com Express 7 MGMT/SPI.MOSI")
		(layer "In2.Cu")
		(name "$teardrop_padvia$")
		(hatch none 0.1)
		(priority 30038)
		(attr
			(teardrop
				(type padvia)
			)
		)
		(connect_pads yes
			(clearance 0)
		)
		(min_thickness 0.0254)
		(filled_areas_thickness no)
		(fill yes
			(thermal_gap 0.5)
			(thermal_bridge_width 0.5)
			(island_removal_mode 1)
			(island_area_min 10)
		)
		(polygon
			(pts
				(xy 247.262641 160.329283) (xy 247.315916 160.282837) (xy 247.362456 160.255813) (xy 247.464454 160.232924)
				(xy 247.543895 160.220677) (xy 247.500707 159.999293) (xy 247.279323 159.956105) (xy 247.267075 160.035547)
				(xy 247.245808 160.133706) (xy 247.218673 160.181988) (xy 247.170717 160.237359)
			)
		)
	)
	(zone
		(net 143)
		(net_name "/2xSFP+/KR to SFI #2/~{RESET}")
		(layer "In2.Cu")
		(name "$teardrop_padvia$")
		(hatch none 0.1)
		(priority 30204)
		(attr
			(teardrop
				(type padvia)
			)
		)
		(connect_pads yes
			(clearance 0)
		)
		(min_thickness 0.0254)
		(filled_areas_thickness no)
		(fill yes
			(thermal_gap 0.5)
			(thermal_bridge_width 0.5)
			(island_removal_mode 1)
			(island_area_min 10)
		)
		(polygon
			(pts
				(xy 131.617515 136.099127) (xy 131.571819 136.046618) (xy 131.545231 136.000623) (xy 131.524847 135.914175)
				(xy 131.523011 135.89884) (xy 131.510677 135.816105) (xy 131.289293 135.859293) (xy 131.246105 136.080677)
				(xy 131.32884 136.093011) (xy 131.426119 136.113349) (xy 131.474159 136.140057) (xy 131.529127 136.187515)
			)
		)
	)
	(zone
		(net 894)
		(net_name "Net-(J2B-MOD_{ABS})")
		(layer "In2.Cu")
		(name "$teardrop_padvia$")
		(hatch none 0.1)
		(priority 30184)
		(attr
			(teardrop
				(type padvia)
			)
		)
		(connect_pads yes
			(clearance 0)
		)
		(min_thickness 0.0254)
		(filled_areas_thickness no)
		(fill yes
			(thermal_gap 0.5)
			(thermal_bridge_width 0.5)
			(island_removal_mode 1)
			(island_area_min 10)
		)
		(polygon
			(pts
				(xy 175.760873 146.327515) (xy 175.813382 146.281819) (xy 175.859376 146.255231) (xy 175.945824 146.234847)
				(xy 175.96116 146.233011) (xy 176.043895 146.220677) (xy 176.000707 145.999293) (xy 175.779323 145.956105)
				(xy 175.766988 146.038841) (xy 175.746651 146.136119) (xy 175.719943 146.184159) (xy 175.672485 146.239127)
			)
		)
	)
	(zone
		(net 365)
		(net_name "/Com Express 7 MGMT/PWR_OK")
		(layer "In2.Cu")
		(name "$teardrop_padvia$")
		(hatch none 0.1)
		(priority 30115)
		(attr
			(teardrop
				(type padvia)
			)
		)
		(connect_pads yes
			(clearance 0)
		)
		(min_thickness 0.0254)
		(filled_areas_thickness no)
		(fill yes
			(thermal_gap 0.5)
			(thermal_bridge_width 0.5)
			(island_removal_mode 1)
			(island_area_min 10)
		)
		(polygon
			(pts
				(xy 189.300677 117.8875) (xy 189.231236 117.882682) (xy 189.179913 117.86896) (xy 189.104371 117.822246)
				(xy 189.092231 117.812701) (xy 189.025003 117.762919) (xy 188.899 117.95) (xy 189.025003 118.137081)
				(xy 189.092229 118.087299) (xy 189.175396 118.032894) (xy 189.228251 118.01781) (xy 189.300677 118.0125)
			)
		)
	)
	(zone
		(net 528)
		(net_name "/Backplane/~{PERST}")
		(layer "In2.Cu")
		(name "$teardrop_padvia$")
		(hatch none 0.1)
		(priority 30050)
		(attr
			(teardrop
				(type padvia)
			)
		)
		(connect_pads yes
			(clearance 0)
		)
		(min_thickness 0.0254)
		(filled_areas_thickness no)
		(fill yes
			(thermal_gap 0.5)
			(thermal_bridge_width 0.5)
			(island_removal_mode 1)
			(island_area_min 10)
		)
		(polygon
			(pts
				(xy 177.9375 107.259323) (xy 177.932682 107.328763) (xy 177.91896 107.380087) (xy 177.872245 107.455628)
				(xy 177.862702 107.467768) (xy 177.812919 107.534997) (xy 178 107.661) (xy 178.187081 107.534997)
				(xy 178.137299 107.467769) (xy 178.082894 107.384603) (xy 178.06781 107.331748) (xy 178.0625 107.259323)
			)
		)
	)
	(zone
		(net 401)
		(net_name "/Com Express 7 MGMT/FAM_TACH")
		(layer "In2.Cu")
		(name "$teardrop_padvia$")
		(hatch none 0.1)
		(priority 30145)
		(attr
			(teardrop
				(type padvia)
			)
		)
		(connect_pads yes
			(clearance 0)
		)
		(min_thickness 0.0254)
		(filled_areas_thickness no)
		(fill yes
			(thermal_gap 0.5)
			(thermal_bridge_width 0.5)
			(island_removal_mode 1)
			(island_area_min 10)
		)
		(polygon
			(pts
				(xy 226.839127 161.372485) (xy 226.786618 161.418181) (xy 226.740623 161.444768) (xy 226.654174 161.465152)
				(xy 226.638841 161.466988) (xy 226.556105 161.479323) (xy 226.599293 161.700707) (xy 226.820677 161.743895)
				(xy 226.833011 161.66116) (xy 226.853349 161.563881) (xy 226.880057 161.515841) (xy 226.927515 161.460873)
			)
		)
	)
	(zone
		(net 526)
		(net_name "/Backplane/~{PRSNT}")
		(layer "In2.Cu")
		(name "$teardrop_padvia$")
		(hatch none 0.1)
		(priority 30197)
		(attr
			(teardrop
				(type padvia)
			)
		)
		(connect_pads yes
			(clearance 0)
		)
		(min_thickness 0.0254)
		(filled_areas_thickness no)
		(fill yes
			(thermal_gap 0.5)
			(thermal_bridge_width 0.5)
			(island_removal_mode 1)
			(island_area_min 10)
		)
		(polygon
			(pts
				(xy 222.427515 133.799127) (xy 222.381819 133.746618) (xy 222.355231 133.700623) (xy 222.334847 133.614175)
				(xy 222.333011 133.59884) (xy 222.320677 133.516105) (xy 222.099293 133.559293) (xy 222.056105 133.780677)
				(xy 222.13884 133.793011) (xy 222.236119 133.813349) (xy 222.284159 133.840057) (xy 222.339127 133.887515)
			)
		)
	)
	(zone
		(net 358)
		(net_name "/Com Express 7 MGMT/SMBus.SDA")
		(layer "In2.Cu")
		(name "$teardrop_padvia$")
		(hatch none 0.1)
		(priority 30113)
		(attr
			(teardrop
				(type padvia)
			)
		)
		(connect_pads yes
			(clearance 0)
		)
		(min_thickness 0.0254)
		(filled_areas_thickness no)
		(fill yes
			(thermal_gap 0.5)
			(thermal_bridge_width 0.5)
			(island_removal_mode 1)
			(island_area_min 10)
		)
		(polygon
			(pts
				(xy 167.575677 163.3875) (xy 167.506236 163.382682) (xy 167.454913 163.36896) (xy 167.379371 163.322246)
				(xy 167.367231 163.312701) (xy 167.300003 163.262919) (xy 167.174 163.45) (xy 167.300003 163.637081)
				(xy 167.367229 163.587299) (xy 167.450396 163.532894) (xy 167.503251 163.51781) (xy 167.575677 163.5125)
			)
		)
	)
	(zone
		(net 358)
		(net_name "/Com Express 7 MGMT/SMBus.SDA")
		(layer "In2.Cu")
		(name "$teardrop_padvia$")
		(hatch none 0.1)
		(priority 30028)
		(attr
			(teardrop
				(type padvia)
			)
		)
		(connect_pads yes
			(clearance 0)
		)
		(min_thickness 0.0254)
		(filled_areas_thickness no)
		(fill yes
			(thermal_gap 0.5)
			(thermal_bridge_width 0.5)
			(island_removal_mode 1)
			(island_area_min 10)
		)
		(polygon
			(pts
				(xy 127.500677 148.6125) (xy 127.439547 148.607747) (xy 127.393447 148.59448) (xy 127.326755 148.549229)
				(xy 127.307658 148.53137) (xy 127.225003 148.462919) (xy 127.099 148.65) (xy 127.175358 148.857644)
				(xy 127.290418 148.799334) (xy 127.37453 148.755855) (xy 127.428939 148.742451) (xy 127.500677 148.7375)
			)
		)
	)
	(zone
		(net 303)
		(net_name "/Com Express 7 MGMT/~{SUS_S5}")
		(layer "In2.Cu")
		(name "$teardrop_padvia$")
		(hatch none 0.1)
		(priority 30154)
		(attr
			(teardrop
				(type padvia)
			)
		)
		(connect_pads yes
			(clearance 0)
		)
		(min_thickness 0.0254)
		(filled_areas_thickness no)
		(fill yes
			(thermal_gap 0.5)
			(thermal_bridge_width 0.5)
			(island_removal_mode 1)
			(island_area_min 10)
		)
		(polygon
			(pts
				(xy 184.772485 170.560873) (xy 184.818181 170.613382) (xy 184.844768 170.659376) (xy 184.865152 170.745825)
				(xy 184.866988 170.761158) (xy 184.879323 170.843895) (xy 185.100707 170.800707) (xy 185.143895 170.579323)
				(xy 185.061158 170.566988) (xy 184.96388 170.546651) (xy 184.91584 170.519943) (xy 184.860873 170.472485)
			)
		)
	)
	(zone
		(net 356)
		(net_name "/Com Express 7 MGMT/~{CW_PWRBTN}")
		(layer "In2.Cu")
		(name "$teardrop_padvia$")
		(hatch none 0.1)
		(priority 30190)
		(attr
			(teardrop
				(type padvia)
			)
		)
		(connect_pads yes
			(clearance 0)
		)
		(min_thickness 0.0254)
		(filled_areas_thickness no)
		(fill yes
			(thermal_gap 0.5)
			(thermal_bridge_width 0.5)
			(island_removal_mode 1)
			(island_area_min 10)
		)
		(polygon
			(pts
				(xy 184.727515 158.739127) (xy 184.681819 158.686618) (xy 184.655231 158.640623) (xy 184.634847 158.554175)
				(xy 184.633011 158.53884) (xy 184.620677 158.456105) (xy 184.399293 158.499293) (xy 184.356105 158.720677)
				(xy 184.43884 158.733011) (xy 184.536119 158.753349) (xy 184.584159 158.780057) (xy 184.639127 158.827515)
			)
		)
	)
	(zone
		(net 81)
		(net_name "/Misc/FAN_12V")
		(layer "In2.Cu")
		(hatch edge 0.5)
		(priority 1)
		(connect_pads yes
			(clearance 0.15)
		)
		(min_thickness 0.15)
		(filled_areas_thickness no)
		(fill yes
			(thermal_gap 0.2)
			(thermal_bridge_width 0.5)
			(smoothing fillet)
			(radius 0.2)
		)
		(polygon
			(pts
				(xy 290.7 91.385) (xy 290.7 122.585) (xy 298.1 129.985) (xy 298.1 144.21) (xy 292.6 144.21) (xy 292.6 132.71)
				(xy 284.825 124.935) (xy 284.825 94.76) (xy 265.85 75.785) (xy 235.1 75.785) (xy 235.1 69.46) (xy 268.775 69.46)
			)
		)
	)
	(zone
		(net 587)
		(net_name "/M.2 key E/SUSCLK")
		(layer "In2.Cu")
		(name "$teardrop_padvia$")
		(hatch none 0.1)
		(priority 30162)
		(attr
			(teardrop
				(type padvia)
			)
		)
		(connect_pads yes
			(clearance 0)
		)
		(min_thickness 0.0254)
		(filled_areas_thickness no)
		(fill yes
			(thermal_gap 0.5)
			(thermal_bridge_width 0.5)
			(island_removal_mode 1)
			(island_area_min 10)
		)
		(polygon
			(pts
				(xy 176.672485 108.420873) (xy 176.718181 108.473382) (xy 176.744768 108.519376) (xy 176.765152 108.605825)
				(xy 176.766988 108.621158) (xy 176.779323 108.703895) (xy 177.000707 108.660707) (xy 177.043895 108.439323)
				(xy 176.961158 108.426988) (xy 176.86388 108.406651) (xy 176.81584 108.379943) (xy 176.760873 108.332485)
			)
		)
	)
	(zone
		(net 291)
		(net_name "/2xUSB3.0+RJ45/~{GBE0_LINK}")
		(layer "In2.Cu")
		(name "$teardrop_padvia$")
		(hatch none 0.1)
		(priority 30089)
		(attr
			(teardrop
				(type padvia)
			)
		)
		(connect_pads yes
			(clearance 0)
		)
		(min_thickness 0.0254)
		(filled_areas_thickness no)
		(fill yes
			(thermal_gap 0.5)
			(thermal_bridge_width 0.5)
			(island_removal_mode 1)
			(island_area_min 10)
		)
		(polygon
			(pts
				(xy 127.1625 112.100677) (xy 127.167318 112.031236) (xy 127.18104 111.979912) (xy 127.227755 111.90437)
				(xy 127.237299 111.892229) (xy 127.287081 111.825003) (xy 127.1 111.699) (xy 126.912919 111.825003)
				(xy 126.962701 111.892231) (xy 127.017106 111.975397) (xy 127.03219 112.028251) (xy 127.0375 112.100677)
			)
		)
	)
	(zone
		(net 528)
		(net_name "/Backplane/~{PERST}")
		(layer "In2.Cu")
		(name "$teardrop_padvia$")
		(hatch none 0.1)
		(priority 30101)
		(attr
			(teardrop
				(type padvia)
			)
		)
		(connect_pads yes
			(clearance 0)
		)
		(min_thickness 0.0254)
		(filled_areas_thickness no)
		(fill yes
			(thermal_gap 0.5)
			(thermal_bridge_width 0.5)
			(island_removal_mode 1)
			(island_area_min 10)
		)
		(polygon
			(pts
				(xy 291.1875 103.260677) (xy 291.192318 103.191236) (xy 291.20604 103.139912) (xy 291.252755 103.06437)
				(xy 291.262299 103.052229) (xy 291.312081 102.985003) (xy 291.125 102.859) (xy 290.937919 102.985003)
				(xy 290.987701 103.052231) (xy 291.042106 103.135397) (xy 291.05719 103.188251) (xy 291.0625 103.260677)
			)
		)
	)
	(zone
		(net 528)
		(net_name "/Backplane/~{PERST}")
		(layer "In2.Cu")
		(name "$teardrop_padvia$")
		(hatch none 0.1)
		(priority 30122)
		(attr
			(teardrop
				(type padvia)
			)
		)
		(connect_pads yes
			(clearance 0)
		)
		(min_thickness 0.0254)
		(filled_areas_thickness no)
		(fill yes
			(thermal_gap 0.5)
			(thermal_bridge_width 0.5)
			(island_removal_mode 1)
			(island_area_min 10)
		)
		(polygon
			(pts
				(xy 158.950677 150.2475) (xy 158.881236 150.242682) (xy 158.829913 150.22896) (xy 158.754371 150.182246)
				(xy 158.742231 150.172701) (xy 158.675003 150.122919) (xy 158.549 150.31) (xy 158.675003 150.497081)
				(xy 158.742229 150.447299) (xy 158.825396 150.392894) (xy 158.878251 150.37781) (xy 158.950677 150.3725)
			)
		)
	)
	(zone
		(net 291)
		(net_name "/2xUSB3.0+RJ45/~{GBE0_LINK}")
		(layer "In2.Cu")
		(name "$teardrop_padvia$")
		(hatch none 0.1)
		(priority 30030)
		(attr
			(teardrop
				(type padvia)
			)
		)
		(connect_pads yes
			(clearance 0)
		)
		(min_thickness 0.0254)
		(filled_areas_thickness no)
		(fill yes
			(thermal_gap 0.5)
			(thermal_bridge_width 0.5)
			(island_removal_mode 1)
			(island_area_min 10)
		)
		(polygon
			(pts
				(xy 144.715383 152.826995) (xy 144.69199 152.796852) (xy 144.683384 152.76928) (xy 144.696967 152.722666)
				(xy 144.740205 152.670537) (xy 144.785207 152.617907) (xy 144.816237 152.554613) (xy 144.599293 152.499293)
				(xy 144.418407 152.630491) (xy 144.486516 152.735442) (xy 144.538647 152.81549) (xy 144.626995 152.915383)
			)
		)
	)
	(zone
		(net 401)
		(net_name "/Com Express 7 MGMT/FAM_TACH")
		(layer "In2.Cu")
		(name "$teardrop_padvia$")
		(hatch none 0.1)
		(priority 30168)
		(attr
			(teardrop
				(type padvia)
			)
		)
		(connect_pads yes
			(clearance 0)
		)
		(min_thickness 0.0254)
		(filled_areas_thickness no)
		(fill yes
			(thermal_gap 0.5)
			(thermal_bridge_width 0.5)
			(island_removal_mode 1)
			(island_area_min 10)
		)
		(polygon
			(pts
				(xy 235.593193 78.870873) (xy 235.638889 78.923382) (xy 235.665476 78.969376) (xy 235.68586 79.055825)
				(xy 235.687696 79.071158) (xy 235.700031 79.153895) (xy 235.921415 79.110707) (xy 235.964603 78.889323)
				(xy 235.881866 78.876988) (xy 235.784588 78.856651) (xy 235.736548 78.829943) (xy 235.681581 78.782485)
			)
		)
	)
	(zone
		(net 371)
		(net_name "/Com Express 7 MGMT/I2C.SCL")
		(layer "In2.Cu")
		(name "$teardrop_padvia$")
		(hatch none 0.1)
		(priority 30151)
		(attr
			(teardrop
				(type padvia)
			)
		)
		(connect_pads yes
			(clearance 0)
		)
		(min_thickness 0.0254)
		(filled_areas_thickness no)
		(fill yes
			(thermal_gap 0.5)
			(thermal_bridge_width 0.5)
			(island_removal_mode 1)
			(island_area_min 10)
		)
		(polygon
			(pts
				(xy 192.514127 161.397485) (xy 192.461618 161.443181) (xy 192.415623 161.469768) (xy 192.329174 161.490152)
				(xy 192.313841 161.491988) (xy 192.231105 161.504323) (xy 192.274293 161.725707) (xy 192.495677 161.768895)
				(xy 192.508011 161.68616) (xy 192.528349 161.588881) (xy 192.555057 161.540841) (xy 192.602515 161.485873)
			)
		)
	)
	(zone
		(net 357)
		(net_name "/Com Express 7 MGMT/SMBus.SCL")
		(layer "In2.Cu")
		(name "$teardrop_padvia$")
		(hatch none 0.1)
		(priority 30167)
		(attr
			(teardrop
				(type padvia)
			)
		)
		(connect_pads yes
			(clearance 0)
		)
		(min_thickness 0.0254)
		(filled_areas_thickness no)
		(fill yes
			(thermal_gap 0.5)
			(thermal_bridge_width 0.5)
			(island_removal_mode 1)
			(island_area_min 10)
		)
		(polygon
			(pts
				(xy 181.272485 164.260873) (xy 181.318181 164.313382) (xy 181.344768 164.359376) (xy 181.365152 164.445825)
				(xy 181.366988 164.461158) (xy 181.379323 164.543895) (xy 181.600707 164.500707) (xy 181.643895 164.279323)
				(xy 181.561158 164.266988) (xy 181.46388 164.246651) (xy 181.41584 164.219943) (xy 181.360873 164.172485)
			)
		)
	)
	(zone
		(net 136)
		(net_name "/Com Express 7 MGMT/~{TYPE0}")
		(layer "In2.Cu")
		(name "$teardrop_padvia$")
		(hatch none 0.1)
		(priority 30024)
		(attr
			(teardrop
				(type padvia)
			)
		)
		(connect_pads yes
			(clearance 0)
		)
		(min_thickness 0.0254)
		(filled_areas_thickness no)
		(fill yes
			(thermal_gap 0.5)
			(thermal_bridge_width 0.5)
			(island_removal_mode 1)
			(island_area_min 10)
		)
		(polygon
			(pts
				(xy 241.962207 153.0375) (xy 242.013569 153.04224) (xy 242.052574 153.055419) (xy 242.106135 153.100293)
				(xy 242.132143 153.135713) (xy 242.168185 153.183725) (xy 242.21861 153.230694) (xy 242.351 153.05)
				(xy 242.296578 152.833268) (xy 242.179068 152.871603) (xy 242.090416 152.900489) (xy 241.962207 152.9125)
			)
		)
	)
	(zone
		(net 356)
		(net_name "/Com Express 7 MGMT/~{CW_PWRBTN}")
		(layer "In2.Cu")
		(name "$teardrop_padvia$")
		(hatch none 0.1)
		(priority 30133)
		(attr
			(teardrop
				(type padvia)
			)
		)
		(connect_pads yes
			(clearance 0)
		)
		(min_thickness 0.0254)
		(filled_areas_thickness no)
		(fill yes
			(thermal_gap 0.5)
			(thermal_bridge_width 0.5)
			(island_removal_mode 1)
			(island_area_min 10)
		)
		(polygon
			(pts
				(xy 222.139127 142.472485) (xy 222.086618 142.518181) (xy 222.040623 142.544768) (xy 221.954174 142.565152)
				(xy 221.938841 142.566988) (xy 221.856105 142.579323) (xy 221.899293 142.800707) (xy 222.120677 142.843895)
				(xy 222.133011 142.76116) (xy 222.153349 142.663881) (xy 222.180057 142.615841) (xy 222.227515 142.560873)
			)
		)
	)
	(zone
		(net 303)
		(net_name "/Com Express 7 MGMT/~{SUS_S5}")
		(layer "In2.Cu")
		(name "$teardrop_padvia$")
		(hatch none 0.1)
		(priority 30142)
		(attr
			(teardrop
				(type padvia)
			)
		)
		(connect_pads yes
			(clearance 0)
		)
		(min_thickness 0.0254)
		(filled_areas_thickness no)
		(fill yes
			(thermal_gap 0.5)
			(thermal_bridge_width 0.5)
			(island_removal_mode 1)
			(island_area_min 10)
		)
		(polygon
			(pts
				(xy 167.489127 141.547485) (xy 167.436618 141.593181) (xy 167.390623 141.619768) (xy 167.304174 141.640152)
				(xy 167.288841 141.641988) (xy 167.206105 141.654323) (xy 167.249293 141.875707) (xy 167.470677 141.918895)
				(xy 167.483011 141.83616) (xy 167.503349 141.738881) (xy 167.530057 141.690841) (xy 167.577515 141.635873)
			)
		)
	)
	(zone
		(net 365)
		(net_name "/Com Express 7 MGMT/PWR_OK")
		(layer "In2.Cu")
		(name "$teardrop_padvia$")
		(hatch none 0.1)
		(priority 30186)
		(attr
			(teardrop
				(type padvia)
			)
		)
		(connect_pads yes
			(clearance 0)
		)
		(min_thickness 0.0254)
		(filled_areas_thickness no)
		(fill yes
			(thermal_gap 0.5)
			(thermal_bridge_width 0.5)
			(island_removal_mode 1)
			(island_area_min 10)
		)
		(polygon
			(pts
				(xy 190.660873 154.777515) (xy 190.713382 154.731819) (xy 190.759376 154.705231) (xy 190.845824 154.684847)
				(xy 190.86116 154.683011) (xy 190.943895 154.670677) (xy 190.900707 154.449293) (xy 190.679323 154.406105)
				(xy 190.666988 154.488841) (xy 190.646651 154.586119) (xy 190.619943 154.634159) (xy 190.572485 154.689127)
			)
		)
	)
	(zone
		(net 397)
		(net_name "/Com Express 7 MGMT/SPI.~{CS}")
		(layer "In2.Cu")
		(name "$teardrop_padvia$")
		(hatch none 0.1)
		(priority 30137)
		(attr
			(teardrop
				(type padvia)
			)
		)
		(connect_pads yes
			(clearance 0)
		)
		(min_thickness 0.0254)
		(filled_areas_thickness no)
		(fill yes
			(thermal_gap 0.5)
			(thermal_bridge_width 0.5)
			(island_removal_mode 1)
			(island_area_min 10)
		)
		(polygon
			(pts
				(xy 258.139127 163.472485) (xy 258.086618 163.518181) (xy 258.040623 163.544768) (xy 257.954174 163.565152)
				(xy 257.938841 163.566988) (xy 257.856105 163.579323) (xy 257.899293 163.800707) (xy 258.120677 163.843895)
				(xy 258.133011 163.76116) (xy 258.153349 163.663881) (xy 258.180057 163.615841) (xy 258.227515 163.560873)
			)
		)
	)
	(zone
		(net 533)
		(net_name "/Com Express 7 MGMT/PSON")
		(layer "In2.Cu")
		(name "$teardrop_padvia$")
		(hatch none 0.1)
		(priority 30114)
		(attr
			(teardrop
				(type padvia)
			)
		)
		(connect_pads yes
			(clearance 0)
		)
		(min_thickness 0.0254)
		(filled_areas_thickness no)
		(fill yes
			(thermal_gap 0.5)
			(thermal_bridge_width 0.5)
			(island_removal_mode 1)
			(island_area_min 10)
		)
		(polygon
			(pts
				(xy 258.500677 130.3475) (xy 258.431236 130.342682) (xy 258.379913 130.32896) (xy 258.304371 130.282246)
				(xy 258.292231 130.272701) (xy 258.225003 130.222919) (xy 258.099 130.41) (xy 258.225003 130.597081)
				(xy 258.292229 130.547299) (xy 258.375396 130.492894) (xy 258.428251 130.47781) (xy 258.500677 130.4725)
			)
		)
	)
	(zone
		(net 139)
		(net_name "/Com Express 7 MGMT/SPI_POWER")
		(layer "In2.Cu")
		(name "$teardrop_padvia$")
		(hatch none 0.1)
		(priority 30009)
		(attr
			(teardrop
				(type padvia)
			)
		)
		(connect_pads yes
			(clearance 0)
		)
		(min_thickness 0.0254)
		(filled_areas_thickness no)
		(fill yes
			(thermal_gap 0.5)
			(thermal_bridge_width 0.5)
			(island_removal_mode 1)
			(island_area_min 10)
		)
		(polygon
			(pts
				(xy 220.9 166.499323) (xy 220.895287 166.577234) (xy 220.8823 166.636018) (xy 220.840199 166.727048)
				(xy 220.7975 166.812221) (xy 221 166.901) (xy 221.2025 166.812221) (xy 221.159801 166.72705) (xy 221.117133 166.634217)
				(xy 221.104556 166.576078) (xy 221.1 166.499323)
			)
		)
	)
	(zone
		(net 727)
		(net_name "Net-(U43C-PRBS_{PASS})")
		(layer "In2.Cu")
		(name "$teardrop_padvia$")
		(hatch none 0.1)
		(priority 30141)
		(attr
			(teardrop
				(type padvia)
			)
		)
		(connect_pads yes
			(clearance 0)
		)
		(min_thickness 0.0254)
		(filled_areas_thickness no)
		(fill yes
			(thermal_gap 0.5)
			(thermal_bridge_width 0.5)
			(island_removal_mode 1)
			(island_area_min 10)
		)
		(polygon
			(pts
				(xy 148.689127 139.532485) (xy 148.636618 139.578181) (xy 148.590623 139.604768) (xy 148.504174 139.625152)
				(xy 148.488841 139.626988) (xy 148.406105 139.639323) (xy 148.449293 139.860707) (xy 148.670677 139.903895)
				(xy 148.683011 139.82116) (xy 148.703349 139.723881) (xy 148.730057 139.675841) (xy 148.777515 139.620873)
			)
		)
	)
	(zone
		(net 945)
		(net_name "/GPIO expander/GPIOEX5")
		(layer "In2.Cu")
		(name "$teardrop_padvia$")
		(hatch none 0.1)
		(priority 30148)
		(attr
			(teardrop
				(type padvia)
			)
		)
		(connect_pads yes
			(clearance 0)
		)
		(min_thickness 0.0254)
		(filled_areas_thickness no)
		(fill yes
			(thermal_gap 0.5)
			(thermal_bridge_width 0.5)
			(island_removal_mode 1)
			(island_area_min 10)
		)
		(polygon
			(pts
				(xy 197.939127 131.872485) (xy 197.886618 131.918181) (xy 197.840623 131.944768) (xy 197.754174 131.965152)
				(xy 197.738841 131.966988) (xy 197.656105 131.979323) (xy 197.699293 132.200707) (xy 197.920677 132.243895)
				(xy 197.933011 132.16116) (xy 197.953349 132.063881) (xy 197.980057 132.015841) (xy 198.027515 131.960873)
			)
		)
	)
	(zone
		(net 533)
		(net_name "/Com Express 7 MGMT/PSON")
		(layer "In2.Cu")
		(name "$teardrop_padvia$")
		(hatch none 0.1)
		(priority 30169)
		(attr
			(teardrop
				(type padvia)
			)
		)
		(connect_pads yes
			(clearance 0)
		)
		(min_thickness 0.0254)
		(filled_areas_thickness no)
		(fill yes
			(thermal_gap 0.5)
			(thermal_bridge_width 0.5)
			(island_removal_mode 1)
			(island_area_min 10)
		)
		(polygon
			(pts
				(xy 291.572485 138.770873) (xy 291.618181 138.823382) (xy 291.644768 138.869376) (xy 291.665152 138.955825)
				(xy 291.666988 138.971158) (xy 291.679323 139.053895) (xy 291.900707 139.010707) (xy 291.943895 138.789323)
				(xy 291.861158 138.776988) (xy 291.76388 138.756651) (xy 291.71584 138.729943) (xy 291.660873 138.682485)
			)
		)
	)
	(zone
		(net 322)
		(net_name "/Com Express 7 Interfaces/SDIO.DAT1")
		(layer "In2.Cu")
		(name "$teardrop_padvia$")
		(hatch none 0.1)
		(priority 30013)
		(attr
			(teardrop
				(type padvia)
			)
		)
		(connect_pads yes
			(clearance 0)
		)
		(min_thickness 0.0254)
		(filled_areas_thickness no)
		(fill yes
			(thermal_gap 0.5)
			(thermal_bridge_width 0.5)
			(island_removal_mode 1)
			(island_area_min 10)
		)
		(polygon
			(pts
				(xy 207.0775 170.250677) (xy 207.082191 170.182314) (xy 207.095026 170.13003) (xy 207.143943 170.040651)
				(xy 207.2025 169.937778) (xy 207 169.849) (xy 206.7975 169.937778) (xy 206.856057 170.040652) (xy 206.902933 170.124447)
				(xy 206.917239 170.178713) (xy 206.9225 170.250677)
			)
		)
	)
	(zone
		(net 529)
		(net_name "/M.2 key M #1/~{CLKREQ}")
		(layer "In2.Cu")
		(name "$teardrop_padvia$")
		(hatch none 0.1)
		(priority 30063)
		(attr
			(teardrop
				(type padvia)
			)
		)
		(connect_pads yes
			(clearance 0)
		)
		(min_thickness 0.0254)
		(filled_areas_thickness no)
		(fill yes
			(thermal_gap 0.5)
			(thermal_bridge_width 0.5)
			(island_removal_mode 1)
			(island_area_min 10)
		)
		(polygon
			(pts
				(xy 210.399323 126.1525) (xy 210.468764 126.157318) (xy 210.520088 126.17104) (xy 210.595629 126.217755)
				(xy 210.607769 126.227299) (xy 210.674997 126.277081) (xy 210.801 126.09) (xy 210.674997 125.902919)
				(xy 210.607768 125.952702) (xy 210.524602 126.007106) (xy 210.471748 126.02219) (xy 210.399323 126.0275)
			)
		)
	)
	(zone
		(net 528)
		(net_name "/Backplane/~{PERST}")
		(layer "In2.Cu")
		(name "$teardrop_padvia$")
		(hatch none 0.1)
		(priority 30155)
		(attr
			(teardrop
				(type padvia)
			)
		)
		(connect_pads yes
			(clearance 0)
		)
		(min_thickness 0.0254)
		(filled_areas_thickness no)
		(fill yes
			(thermal_gap 0.5)
			(thermal_bridge_width 0.5)
			(island_removal_mode 1)
			(island_area_min 10)
		)
		(polygon
			(pts
				(xy 142.642485 83.820873) (xy 142.688181 83.873382) (xy 142.714768 83.919376) (xy 142.735152 84.005825)
				(xy 142.736988 84.021158) (xy 142.749323 84.103895) (xy 142.970707 84.060707) (xy 143.013895 83.839323)
				(xy 142.931158 83.826988) (xy 142.83388 83.806651) (xy 142.78584 83.779943) (xy 142.730873 83.732485)
			)
		)
	)
	(zone
		(net 531)
		(net_name "/Com Express 7 Interfaces/SD_CD")
		(layer "In2.Cu")
		(name "$teardrop_padvia$")
		(hatch none 0.1)
		(priority 30208)
		(attr
			(teardrop
				(type padvia)
			)
		)
		(connect_pads yes
			(clearance 0)
		)
		(min_thickness 0.0254)
		(filled_areas_thickness no)
		(fill yes
			(thermal_gap 0.5)
			(thermal_bridge_width 0.5)
			(island_removal_mode 1)
			(island_area_min 10)
		)
		(polygon
			(pts
				(xy 166.847123 157.3875) (xy 166.772053 157.392084) (xy 166.715165 157.404176) (xy 166.641868 157.433216)
				(xy 166.58319 157.457913) (xy 166.506105 157.479323) (xy 166.549 157.7) (xy 166.770677 157.743895)
				(xy 166.772773 157.64204) (xy 166.770825 157.592149) (xy 166.777199 157.550914) (xy 166.799947 157.522857)
				(xy 166.847123 157.5125)
			)
		)
	)
	(zone
		(net 359)
		(net_name "/Com Express 7 MGMT/SMBus.~{INT}")
		(layer "In2.Cu")
		(name "$teardrop_padvia$")
		(hatch none 0.1)
		(priority 30108)
		(attr
			(teardrop
				(type padvia)
			)
		)
		(connect_pads yes
			(clearance 0)
		)
		(min_thickness 0.0254)
		(filled_areas_thickness no)
		(fill yes
			(thermal_gap 0.5)
			(thermal_bridge_width 0.5)
			(island_removal_mode 1)
			(island_area_min 10)
		)
		(polygon
			(pts
				(xy 187.300677 131.9375) (xy 187.231236 131.932682) (xy 187.179913 131.91896) (xy 187.104371 131.872246)
				(xy 187.092231 131.862701) (xy 187.025003 131.812919) (xy 186.899 132) (xy 187.025003 132.187081)
				(xy 187.092229 132.137299) (xy 187.175396 132.082894) (xy 187.228251 132.06781) (xy 187.300677 132.0625)
			)
		)
	)
	(zone
		(net 358)
		(net_name "/Com Express 7 MGMT/SMBus.SDA")
		(layer "In2.Cu")
		(name "$teardrop_padvia$")
		(hatch none 0.1)
		(priority 30068)
		(attr
			(teardrop
				(type padvia)
			)
		)
		(connect_pads yes
			(clearance 0)
		)
		(min_thickness 0.0254)
		(filled_areas_thickness no)
		(fill yes
			(thermal_gap 0.5)
			(thermal_bridge_width 0.5)
			(island_removal_mode 1)
			(island_area_min 10)
		)
		(polygon
			(pts
				(xy 158.549323 148.2875) (xy 158.618764 148.292318) (xy 158.670088 148.30604) (xy 158.745629 148.352755)
				(xy 158.757769 148.362299) (xy 158.824997 148.412081) (xy 158.951 148.225) (xy 158.824997 148.037919)
				(xy 158.757768 148.087702) (xy 158.674602 148.142106) (xy 158.621748 148.15719) (xy 158.549323 148.1625)
			)
		)
	)
	(zone
		(net 358)
		(net_name "/Com Express 7 MGMT/SMBus.SDA")
		(layer "In2.Cu")
		(name "$teardrop_padvia$")
		(hatch none 0.1)
		(priority 30090)
		(attr
			(teardrop
				(type padvia)
			)
		)
		(connect_pads yes
			(clearance 0)
		)
		(min_thickness 0.0254)
		(filled_areas_thickness no)
		(fill yes
			(thermal_gap 0.5)
			(thermal_bridge_width 0.5)
			(island_removal_mode 1)
			(island_area_min 10)
		)
		(polygon
			(pts
				(xy 131.9625 81.680677) (xy 131.967318 81.611236) (xy 131.98104 81.559912) (xy 132.027755 81.48437)
				(xy 132.037299 81.472229) (xy 132.087081 81.405003) (xy 131.9 81.279) (xy 131.712919 81.405003)
				(xy 131.762701 81.472231) (xy 131.817106 81.555397) (xy 131.83219 81.608251) (xy 131.8375 81.680677)
			)
		)
	)
	(zone
		(net 875)
		(net_name "/2xSFP+/SCL1")
		(layer "In2.Cu")
		(name "$teardrop_padvia$")
		(hatch none 0.1)
		(priority 30106)
		(attr
			(teardrop
				(type padvia)
			)
		)
		(connect_pads yes
			(clearance 0)
		)
		(min_thickness 0.0254)
		(filled_areas_thickness no)
		(fill yes
			(thermal_gap 0.5)
			(thermal_bridge_width 0.5)
			(island_removal_mode 1)
			(island_area_min 10)
		)
		(polygon
			(pts
				(xy 168.300677 148.2375) (xy 168.231236 148.232682) (xy 168.179913 148.21896) (xy 168.104371 148.172246)
				(xy 168.092231 148.162701) (xy 168.025003 148.112919) (xy 167.899 148.3) (xy 168.025003 148.487081)
				(xy 168.092229 148.437299) (xy 168.175396 148.382894) (xy 168.228251 148.36781) (xy 168.300677 148.3625)
			)
		)
	)
	(zone
		(net 424)
		(net_name "/2xSFP+/I2C_{SFP1}.SDA")
		(layer "In2.Cu")
		(name "$teardrop_padvia$")
		(hatch none 0.1)
		(priority 30157)
		(attr
			(teardrop
				(type padvia)
			)
		)
		(connect_pads yes
			(clearance 0)
		)
		(min_thickness 0.0254)
		(filled_areas_thickness no)
		(fill yes
			(thermal_gap 0.5)
			(thermal_bridge_width 0.5)
			(island_removal_mode 1)
			(island_area_min 10)
		)
		(polygon
			(pts
				(xy 192.572485 153.560873) (xy 192.618181 153.613382) (xy 192.644768 153.659376) (xy 192.665152 153.745825)
				(xy 192.666988 153.761158) (xy 192.679323 153.843895) (xy 192.900707 153.800707) (xy 192.943895 153.579323)
				(xy 192.861158 153.566988) (xy 192.76388 153.546651) (xy 192.71584 153.519943) (xy 192.660873 153.472485)
			)
		)
	)
	(zone
		(net 2)
		(net_name "+3V3")
		(layer "In2.Cu")
		(name "$teardrop_padvia$")
		(hatch none 0.1)
		(priority 30135)
		(attr
			(teardrop
				(type padvia)
			)
		)
		(connect_pads yes
			(clearance 0)
		)
		(min_thickness 0.0254)
		(filled_areas_thickness no)
		(fill yes
			(thermal_gap 0.5)
			(thermal_bridge_width 0.5)
			(island_removal_mode 1)
			(island_area_min 10)
		)
		(polygon
			(pts
				(xy 163.264127 153.072485) (xy 163.211618 153.118181) (xy 163.165623 153.144768) (xy 163.079174 153.165152)
				(xy 163.063841 153.166988) (xy 162.981105 153.179323) (xy 163.024293 153.400707) (xy 163.245677 153.443895)
				(xy 163.258011 153.36116) (xy 163.278349 153.263881) (xy 163.305057 153.215841) (xy 163.352515 153.160873)
			)
		)
	)
	(zone
		(net 530)
		(net_name "/M.2 key M #2/~{CLKREQ}")
		(layer "In2.Cu")
		(name "$teardrop_padvia$")
		(hatch none 0.1)
		(priority 30152)
		(attr
			(teardrop
				(type padvia)
			)
		)
		(connect_pads yes
			(clearance 0)
		)
		(min_thickness 0.0254)
		(filled_areas_thickness no)
		(fill yes
			(thermal_gap 0.5)
			(thermal_bridge_width 0.5)
			(island_removal_mode 1)
			(island_area_min 10)
		)
		(polygon
			(pts
				(xy 290.799127 88.472485) (xy 290.746618 88.518181) (xy 290.700623 88.544768) (xy 290.614174 88.565152)
				(xy 290.598841 88.566988) (xy 290.516105 88.579323) (xy 290.559293 88.800707) (xy 290.780677 88.843895)
				(xy 290.793011 88.76116) (xy 290.813349 88.663881) (xy 290.840057 88.615841) (xy 290.887515 88.560873)
			)
		)
	)
	(zone
		(net 333)
		(net_name "/Com Express 7 Interfaces/SDIO.DAT3")
		(layer "In2.Cu")
		(name "$teardrop_padvia$")
		(hatch none 0.1)
		(priority 30020)
		(attr
			(teardrop
				(type padvia)
			)
		)
		(connect_pads yes
			(clearance 0)
		)
		(min_thickness 0.0254)
		(filled_areas_thickness no)
		(fill yes
			(thermal_gap 0.5)
			(thermal_bridge_width 0.5)
			(island_removal_mode 1)
			(island_area_min 10)
		)
		(polygon
			(pts
				(xy 217.661879 169.67148) (xy 217.706901 169.723136) (xy 217.734795 169.769182) (xy 217.763406 169.866971)
				(xy 217.794742 169.98112) (xy 218.000707 169.900707) (xy 218.08112 169.694742) (xy 217.966971 169.663406)
				(xy 217.874573 169.6373) (xy 217.826086 169.609044) (xy 217.77148 169.561879)
			)
		)
	)
	(zone
		(net 310)
		(net_name "/Com Express 7 MGMT/~{BIOS_DIS0}")
		(layer "In2.Cu")
		(name "$teardrop_padvia$")
		(hatch none 0.1)
		(priority 30092)
		(attr
			(teardrop
				(type padvia)
			)
		)
		(connect_pads yes
			(clearance 0)
		)
		(min_thickness 0.0254)
		(filled_areas_thickness no)
		(fill yes
			(thermal_gap 0.5)
			(thermal_bridge_width 0.5)
			(island_removal_mode 1)
			(island_area_min 10)
		)
		(polygon
			(pts
				(xy 225.1625 146.800677) (xy 225.167318 146.731236) (xy 225.18104 146.679912) (xy 225.227755 146.60437)
				(xy 225.237299 146.592229) (xy 225.287081 146.525003) (xy 225.1 146.399) (xy 224.912919 146.525003)
				(xy 224.962701 146.592231) (xy 225.017106 146.675397) (xy 225.03219 146.728251) (xy 225.0375 146.800677)
			)
		)
	)
	(zone
		(net 296)
		(net_name "/2xUSB3.0+RJ45/GbE.CTREF")
		(layer "In2.Cu")
		(name "$teardrop_padvia$")
		(hatch none 0.1)
		(priority 30008)
		(attr
			(teardrop
				(type padvia)
			)
		)
		(connect_pads yes
			(clearance 0)
		)
		(min_thickness 0.0254)
		(filled_areas_thickness no)
		(fill yes
			(thermal_gap 0.5)
			(thermal_bridge_width 0.5)
			(island_removal_mode 1)
			(island_area_min 10)
		)
		(polygon
			(pts
				(xy 131.83 98.310677) (xy 131.834713 98.232764) (xy 131.8477 98.17398) (xy 131.889802 98.082947)
				(xy 131.9325 97.997778) (xy 131.73 97.909) (xy 131.5275 97.997778) (xy 131.570198 98.082949) (xy 131.612867 98.175783)
				(xy 131.625444 98.233922) (xy 131.63 98.310677)
			)
		)
	)
	(zone
		(net 595)
		(net_name "/Misc/PWM_{SRCSEL}")
		(layer "In2.Cu")
		(name "$teardrop_padvia$")
		(hatch none 0.1)
		(priority 30192)
		(attr
			(teardrop
				(type padvia)
			)
		)
		(connect_pads yes
			(clearance 0)
		)
		(min_thickness 0.0254)
		(filled_areas_thickness no)
		(fill yes
			(thermal_gap 0.5)
			(thermal_bridge_width 0.5)
			(island_removal_mode 1)
			(island_area_min 10)
		)
		(polygon
			(pts
				(xy 253.472515 84.689126) (xy 253.426819 84.636617) (xy 253.400231 84.590622) (xy 253.379847 84.504174)
				(xy 253.378011 84.488839) (xy 253.365677 84.406104) (xy 253.144293 84.449292) (xy 253.101105 84.670676)
				(xy 253.18384 84.68301) (xy 253.281119 84.703348) (xy 253.329159 84.730056) (xy 253.384127 84.777514)
			)
		)
	)
	(zone
		(net 143)
		(net_name "/2xSFP+/KR to SFI #2/~{RESET}")
		(layer "In2.Cu")
		(name "$teardrop_padvia$")
		(hatch none 0.1)
		(priority 30188)
		(attr
			(teardrop
				(type padvia)
			)
		)
		(connect_pads yes
			(clearance 0)
		)
		(min_thickness 0.0254)
		(filled_areas_thickness no)
		(fill yes
			(thermal_gap 0.5)
			(thermal_bridge_width 0.5)
			(island_removal_mode 1)
			(island_area_min 10)
		)
		(polygon
			(pts
				(xy 140.010873 136.137515) (xy 140.063382 136.091819) (xy 140.109376 136.065231) (xy 140.195824 136.044847)
				(xy 140.21116 136.043011) (xy 140.293895 136.030677) (xy 140.250707 135.809293) (xy 140.029323 135.766105)
				(xy 140.016988 135.848841) (xy 139.996651 135.946119) (xy 139.969943 135.994159) (xy 139.922485 136.049127)
			)
		)
	)
	(zone
		(net 526)
		(net_name "/Backplane/~{PRSNT}")
		(layer "In2.Cu")
		(name "$teardrop_padvia$")
		(hatch none 0.1)
		(priority 30086)
		(attr
			(teardrop
				(type padvia)
			)
		)
		(connect_pads yes
			(clearance 0)
		)
		(min_thickness 0.0254)
		(filled_areas_thickness no)
		(fill yes
			(thermal_gap 0.5)
			(thermal_bridge_width 0.5)
			(island_removal_mode 1)
			(island_area_min 10)
		)
		(polygon
			(pts
				(xy 310.099323 165.7725) (xy 310.168764 165.777318) (xy 310.220088 165.79104) (xy 310.295629 165.837755)
				(xy 310.307769 165.847299) (xy 310.374997 165.897081) (xy 310.501 165.71) (xy 310.374997 165.522919)
				(xy 310.307768 165.572702) (xy 310.224602 165.627106) (xy 310.171748 165.64219) (xy 310.099323 165.6475)
			)
		)
	)
	(zone
		(net 430)
		(net_name "/2xSFP+/MDIO0.MDC")
		(layer "In2.Cu")
		(name "$teardrop_padvia$")
		(hatch none 0.1)
		(priority 30042)
		(attr
			(teardrop
				(type padvia)
			)
		)
		(connect_pads yes
			(clearance 0)
		)
		(min_thickness 0.0254)
		(filled_areas_thickness no)
		(fill yes
			(thermal_gap 0.5)
			(thermal_bridge_width 0.5)
			(island_removal_mode 1)
			(island_area_min 10)
		)
		(polygon
			(pts
				(xy 167.048963 143.96265) (xy 167.004404 144.01372) (xy 166.976256 144.059164) (xy 166.947112 144.139659)
				(xy 166.926571 144.202341) (xy 166.887919 144.274997) (xy 167.074293 144.400707) (xy 167.262081 144.274997)
				(xy 167.203449 144.21358) (xy 167.181536 144.195619) (xy 167.142234 144.162108) (xy 167.11561 144.128656)
				(xy 167.110902 144.09254) (xy 167.13735 144.051037)
			)
		)
	)
	(zone
		(net 749)
		(net_name "Net-(U45C-AMUXB)")
		(layer "In2.Cu")
		(name "$teardrop_padvia$")
		(hatch none 0.1)
		(priority 30098)
		(attr
			(teardrop
				(type padvia)
			)
		)
		(connect_pads yes
			(clearance 0)
		)
		(min_thickness 0.0254)
		(filled_areas_thickness no)
		(fill yes
			(thermal_gap 0.5)
			(thermal_bridge_width 0.5)
			(island_removal_mode 1)
			(island_area_min 10)
		)
		(polygon
			(pts
				(xy 136.3025 130.540677) (xy 136.307318 130.471236) (xy 136.32104 130.419912) (xy 136.367755 130.34437)
				(xy 136.377299 130.332229) (xy 136.427081 130.265003) (xy 136.24 130.139) (xy 136.052919 130.265003)
				(xy 136.102701 130.332231) (xy 136.157106 130.415397) (xy 136.17219 130.468251) (xy 136.1775 130.540677)
			)
		)
	)
	(zone
		(net 303)
		(net_name "/Com Express 7 MGMT/~{SUS_S5}")
		(layer "In2.Cu")
		(name "$teardrop_padvia$")
		(hatch none 0.1)
		(priority 30134)
		(attr
			(teardrop
				(type padvia)
			)
		)
		(connect_pads yes
			(clearance 0)
		)
		(min_thickness 0.0254)
		(filled_areas_thickness no)
		(fill yes
			(thermal_gap 0.5)
			(thermal_bridge_width 0.5)
			(island_removal_mode 1)
			(island_area_min 10)
		)
		(polygon
			(pts
				(xy 222.039127 141.772485) (xy 221.986618 141.818181) (xy 221.940623 141.844768) (xy 221.854174 141.865152)
				(xy 221.838841 141.866988) (xy 221.756105 141.879323) (xy 221.799293 142.100707) (xy 222.020677 142.143895)
				(xy 222.033011 142.06116) (xy 222.053349 141.963881) (xy 222.080057 141.915841) (xy 222.127515 141.860873)
			)
		)
	)
	(zone
		(net 345)
		(net_name "/Com Express 7 MGMT/SER0.RX")
		(layer "In2.Cu")
		(name "$teardrop_padvia$")
		(hatch none 0.1)
		(priority 30203)
		(attr
			(teardrop
				(type padvia)
			)
		)
		(connect_pads yes
			(clearance 0)
		)
		(min_thickness 0.0254)
		(filled_areas_thickness no)
		(fill yes
			(thermal_gap 0.5)
			(thermal_bridge_width 0.5)
			(island_removal_mode 1)
			(island_area_min 10)
		)
		(polygon
			(pts
				(xy 163.927515 107.139127) (xy 163.881819 107.086618) (xy 163.855231 107.040623) (xy 163.834847 106.954175)
				(xy 163.833011 106.93884) (xy 163.820677 106.856105) (xy 163.599293 106.899293) (xy 163.556105 107.120677)
				(xy 163.63884 107.133011) (xy 163.736119 107.153349) (xy 163.784159 107.180057) (xy 163.839127 107.227515)
			)
		)
	)
	(zone
		(net 490)
		(net_name "/2xSFP+/MDIO1.MDIO")
		(layer "In2.Cu")
		(name "$teardrop_padvia$")
		(hatch none 0.1)
		(priority 30075)
		(attr
			(teardrop
				(type padvia)
			)
		)
		(connect_pads yes
			(clearance 0)
		)
		(min_thickness 0.0254)
		(filled_areas_thickness no)
		(fill yes
			(thermal_gap 0.5)
			(thermal_bridge_width 0.5)
			(island_removal_mode 1)
			(island_area_min 10)
		)
		(polygon
			(pts
				(xy 173.099323 139.7625) (xy 173.168764 139.767318) (xy 173.220088 139.78104) (xy 173.295629 139.827755)
				(xy 173.307769 139.837299) (xy 173.374997 139.887081) (xy 173.501 139.7) (xy 173.374997 139.512919)
				(xy 173.307768 139.562702) (xy 173.224602 139.617106) (xy 173.171748 139.63219) (xy 173.099323 139.6375)
			)
		)
	)
	(zone
		(net 425)
		(net_name "/2xSFP+/I2C_{SFP0}.SDA")
		(layer "In2.Cu")
		(name "$teardrop_padvia$")
		(hatch none 0.1)
		(priority 30057)
		(attr
			(teardrop
				(type padvia)
			)
		)
		(connect_pads yes
			(clearance 0)
		)
		(min_thickness 0.0254)
		(filled_areas_thickness no)
		(fill yes
			(thermal_gap 0.5)
			(thermal_bridge_width 0.5)
			(island_removal_mode 1)
			(island_area_min 10)
		)
		(polygon
			(pts
				(xy 192.7875 152.649323) (xy 192.782682 152.718763) (xy 192.76896 152.770087) (xy 192.722245 152.845628)
				(xy 192.712702 152.857768) (xy 192.662919 152.924997) (xy 192.85 153.051) (xy 193.037081 152.924997)
				(xy 192.987299 152.857769) (xy 192.932894 152.774603) (xy 192.91781 152.721748) (xy 192.9125 152.649323)
			)
		)
	)
	(zone
		(net 165)
		(net_name "/2xSFP+/SCL0")
		(layer "In2.Cu")
		(name "$teardrop_padvia$")
		(hatch none 0.1)
		(priority 30111)
		(attr
			(teardrop
				(type padvia)
			)
		)
		(connect_pads yes
			(clearance 0)
		)
		(min_thickness 0.0254)
		(filled_areas_thickness no)
		(fill yes
			(thermal_gap 0.5)
			(thermal_bridge_width 0.5)
			(island_removal_mode 1)
			(island_area_min 10)
		)
		(polygon
			(pts
				(xy 165.900677 147.6375) (xy 165.831236 147.632682) (xy 165.779913 147.61896) (xy 165.704371 147.572246)
				(xy 165.692231 147.562701) (xy 165.625003 147.512919) (xy 165.499 147.7) (xy 165.625003 147.887081)
				(xy 165.692229 147.837299) (xy 165.775396 147.782894) (xy 165.828251 147.76781) (xy 165.900677 147.7625)
			)
		)
	)
	(zone
		(net 142)
		(net_name "/2xSFP+/PHY0_{RESET}")
		(layer "In2.Cu")
		(name "$teardrop_padvia$")
		(hatch none 0.1)
		(priority 30201)
		(attr
			(teardrop
				(type padvia)
			)
		)
		(connect_pads yes
			(clearance 0)
		)
		(min_thickness 0.0254)
		(filled_areas_thickness no)
		(fill yes
			(thermal_gap 0.5)
			(thermal_bridge_width 0.5)
			(island_removal_mode 1)
			(island_area_min 10)
		)
		(polygon
			(pts
				(xy 141.377515 136.049127) (xy 141.331819 135.996618) (xy 141.305231 135.950623) (xy 141.284847 135.864175)
				(xy 141.283011 135.84884) (xy 141.270677 135.766105) (xy 141.049293 135.809293) (xy 141.006105 136.030677)
				(xy 141.08884 136.043011) (xy 141.186119 136.063349) (xy 141.234159 136.090057) (xy 141.289127 136.137515)
			)
		)
	)
	(zone
		(net 314)
		(net_name "/2xUSB3.0+RJ45/FLG_1")
		(layer "In2.Cu")
		(name "$teardrop_padvia$")
		(hatch none 0.1)
		(priority 30056)
		(attr
			(teardrop
				(type padvia)
			)
		)
		(connect_pads yes
			(clearance 0)
		)
		(min_thickness 0.0254)
		(filled_areas_thickness no)
		(fill yes
			(thermal_gap 0.5)
			(thermal_bridge_width 0.5)
			(island_removal_mode 1)
			(island_area_min 10)
		)
		(polygon
			(pts
				(xy 135.3375 122.599323) (xy 135.332682 122.668763) (xy 135.31896 122.720087) (xy 135.272245 122.795628)
				(xy 135.262702 122.807768) (xy 135.212919 122.874997) (xy 135.4 123.001) (xy 135.587081 122.874997)
				(xy 135.537299 122.807769) (xy 135.482894 122.724603) (xy 135.46781 122.671748) (xy 135.4625 122.599323)
			)
		)
	)
	(zone
		(net 24)
		(net_name "/M.2 key E/~{CLKREQ}")
		(layer "In2.Cu")
		(name "$teardrop_padvia$")
		(hatch none 0.1)
		(priority 30052)
		(attr
			(teardrop
				(type padvia)
			)
		)
		(connect_pads yes
			(clearance 0)
		)
		(min_thickness 0.0254)
		(filled_areas_thickness no)
		(fill yes
			(thermal_gap 0.5)
			(thermal_bridge_width 0.5)
			(island_removal_mode 1)
			(island_area_min 10)
		)
		(polygon
			(pts
				(xy 216.8625 137.019323) (xy 216.857682 137.088763) (xy 216.84396 137.140087) (xy 216.797245 137.215628)
				(xy 216.787702 137.227768) (xy 216.737919 137.294997) (xy 216.925 137.421) (xy 217.112081 137.294997)
				(xy 217.062299 137.227769) (xy 217.007894 137.144603) (xy 216.99281 137.091748) (xy 216.9875 137.019323)
			)
		)
	)
	(zone
		(net 371)
		(net_name "/Com Express 7 MGMT/I2C.SCL")
		(layer "In2.Cu")
		(name "$teardrop_padvia$")
		(hatch none 0.1)
		(priority 30080)
		(attr
			(teardrop
				(type padvia)
			)
		)
		(connect_pads yes
			(clearance 0)
		)
		(min_thickness 0.0254)
		(filled_areas_thickness no)
		(fill yes
			(thermal_gap 0.5)
			(thermal_bridge_width 0.5)
			(island_removal_mode 1)
			(island_area_min 10)
		)
		(polygon
			(pts
				(xy 239.774323 153.1625) (xy 239.843764 153.167318) (xy 239.895088 153.18104) (xy 239.970629 153.227755)
				(xy 239.982769 153.237299) (xy 240.049997 153.287081) (xy 240.176 153.1) (xy 240.049997 152.912919)
				(xy 239.982768 152.962702) (xy 239.899602 153.017106) (xy 239.846748 153.03219) (xy 239.774323 153.0375)
			)
		)
	)
	(zone
		(net 490)
		(net_name "/2xSFP+/MDIO1.MDIO")
		(layer "In2.Cu")
		(name "$teardrop_padvia$")
		(hatch none 0.1)
		(priority 30041)
		(attr
			(teardrop
				(type padvia)
			)
		)
		(connect_pads yes
			(clearance 0)
		)
		(min_thickness 0.0254)
		(filled_areas_thickness no)
		(fill yes
			(thermal_gap 0.5)
			(thermal_bridge_width 0.5)
			(island_removal_mode 1)
			(island_area_min 10)
		)
		(polygon
			(pts
				(xy 184.51235 146.448963) (xy 184.490898 146.420754) (xy 184.484462 146.39531) (xy 184.502161 146.353963)
				(xy 184.556537 146.30438) (xy 184.599858 146.267542) (xy 184.637081 146.225003) (xy 184.449293 146.099293)
				(xy 184.262919 146.225003) (xy 184.311344 146.324596) (xy 184.322112 146.360341) (xy 184.352058 146.442418)
				(xy 184.380051 146.487151) (xy 184.423963 146.53735)
			)
		)
	)
	(zone
		(net 945)
		(net_name "/GPIO expander/GPIOEX5")
		(layer "In2.Cu")
		(name "$teardrop_padvia$")
		(hatch none 0.1)
		(priority 30065)
		(attr
			(teardrop
				(type padvia)
			)
		)
		(connect_pads yes
			(clearance 0)
		)
		(min_thickness 0.0254)
		(filled_areas_thickness no)
		(fill yes
			(thermal_gap 0.5)
			(thermal_bridge_width 0.5)
			(island_removal_mode 1)
			(island_area_min 10)
		)
		(polygon
			(pts
				(xy 210.449323 133.8725) (xy 210.518764 133.877318) (xy 210.570088 133.89104) (xy 210.645629 133.937755)
				(xy 210.657769 133.947299) (xy 210.724997 133.997081) (xy 210.851 133.81) (xy 210.724997 133.622919)
				(xy 210.657768 133.672702) (xy 210.574602 133.727106) (xy 210.521748 133.74219) (xy 210.449323 133.7475)
			)
		)
	)
	(zone
		(net 423)
		(net_name "/2xSFP+/I2C_{LED}.SCL")
		(layer "In2.Cu")
		(name "$teardrop_padvia$")
		(hatch none 0.1)
		(priority 30058)
		(attr
			(teardrop
				(type padvia)
			)
		)
		(connect_pads yes
			(clearance 0)
		)
		(min_thickness 0.0254)
		(filled_areas_thickness no)
		(fill yes
			(thermal_gap 0.5)
			(thermal_bridge_width 0.5)
			(island_removal_mode 1)
			(island_area_min 10)
		)
		(polygon
			(pts
				(xy 160.8875 153.799323) (xy 160.882682 153.868763) (xy 160.86896 153.920087) (xy 160.822245 153.995628)
				(xy 160.812702 154.007768) (xy 160.762919 154.074997) (xy 160.95 154.201) (xy 161.137081 154.074997)
				(xy 161.087299 154.007769) (xy 161.032894 153.924603) (xy 161.01781 153.871748) (xy 161.0125 153.799323)
			)
		)
	)
	(zone
		(net 431)
		(net_name "/2xSFP+/MOD0_ABS")
		(layer "In2.Cu")
		(name "$teardrop_padvia$")
		(hatch none 0.1)
		(priority 30119)
		(attr
			(teardrop
				(type padvia)
			)
		)
		(connect_pads yes
			(clearance 0)
		)
		(min_thickness 0.0254)
		(filled_areas_thickness no)
		(fill yes
			(thermal_gap 0.5)
			(thermal_bridge_width 0.5)
			(island_removal_mode 1)
			(island_area_min 10)
		)
		(polygon
			(pts
				(xy 180.500677 144.9875) (xy 180.431236 144.982682) (xy 180.379913 144.96896) (xy 180.304371 144.922246)
				(xy 180.292231 144.912701) (xy 180.225003 144.862919) (xy 180.099 145.05) (xy 180.225003 145.237081)
				(xy 180.292229 145.187299) (xy 180.375396 145.132894) (xy 180.428251 145.11781) (xy 180.500677 145.1125)
			)
		)
	)
	(zone
		(net 729)
		(net_name "Net-(U43C-AMUXB)")
		(layer "In2.Cu")
		(name "$teardrop_padvia$")
		(hatch none 0.1)
		(priority 30132)
		(attr
			(teardrop
				(type padvia)
			)
		)
		(connect_pads yes
			(clearance 0)
		)
		(min_thickness 0.0254)
		(filled_areas_thickness no)
		(fill yes
			(thermal_gap 0.5)
			(thermal_bridge_width 0.5)
			(island_removal_mode 1)
			(island_area_min 10)
		)
		(polygon
			(pts
				(xy 153.689127 134.532485) (xy 153.636618 134.578181) (xy 153.590623 134.604768) (xy 153.504174 134.625152)
				(xy 153.488841 134.626988) (xy 153.406105 134.639323) (xy 153.449293 134.860707) (xy 153.670677 134.903895)
				(xy 153.683011 134.82116) (xy 153.703349 134.723881) (xy 153.730057 134.675841) (xy 153.777515 134.620873)
			)
		)
	)
	(zone
		(net 322)
		(net_name "/Com Express 7 Interfaces/SDIO.DAT1")
		(layer "In2.Cu")
		(name "$teardrop_padvia$")
		(hatch none 0.1)
		(priority 30016)
		(attr
			(teardrop
				(type padvia)
			)
		)
		(connect_pads yes
			(clearance 0)
		)
		(min_thickness 0.0254)
		(filled_areas_thickness no)
		(fill yes
			(thermal_gap 0.5)
			(thermal_bridge_width 0.5)
			(island_removal_mode 1)
			(island_area_min 10)
		)
		(polygon
			(pts
				(xy 164.57148 159.638121) (xy 164.623136 159.593098) (xy 164.669183 159.565204) (xy 164.766972 159.536593)
				(xy 164.881121 159.505257) (xy 164.800707 159.299293) (xy 164.594741 159.21888) (xy 164.563405 159.33303)
				(xy 164.5373 159.425427) (xy 164.509044 159.473914) (xy 164.461879 159.52852)
			)
		)
	)
	(zone
		(net 323)
		(net_name "/Com Express 7 Interfaces/SDIO.DAT2")
		(layer "In2.Cu")
		(name "$teardrop_padvia$")
		(hatch none 0.1)
		(priority 30015)
		(attr
			(teardrop
				(type padvia)
			)
		)
		(connect_pads yes
			(clearance 0)
		)
		(min_thickness 0.0254)
		(filled_areas_thickness no)
		(fill yes
			(thermal_gap 0.5)
			(thermal_bridge_width 0.5)
			(island_removal_mode 1)
			(island_area_min 10)
		)
		(polygon
			(pts
				(xy 208.6225 170.424323) (xy 208.617809 170.492685) (xy 208.604974 170.544969) (xy 208.556058 170.634347)
				(xy 208.4975 170.737221) (xy 208.7 170.826) (xy 208.9025 170.737221) (xy 208.843943 170.634348)
				(xy 208.797067 170.550553) (xy 208.782761 170.496287) (xy 208.7775 170.424323)
			)
		)
	)
	(zone
		(net 528)
		(net_name "/Backplane/~{PERST}")
		(layer "In2.Cu")
		(name "$teardrop_padvia$")
		(hatch none 0.1)
		(priority 30198)
		(attr
			(teardrop
				(type padvia)
			)
		)
		(connect_pads yes
			(clearance 0)
		)
		(min_thickness 0.0254)
		(filled_areas_thickness no)
		(fill yes
			(thermal_gap 0.5)
			(thermal_bridge_width 0.5)
			(island_removal_mode 1)
			(island_area_min 10)
		)
		(polygon
			(pts
				(xy 178.327515 107.899127) (xy 178.281819 107.846618) (xy 178.255231 107.800623) (xy 178.234847 107.714175)
				(xy 178.233011 107.69884) (xy 178.220677 107.616105) (xy 177.999293 107.659293) (xy 177.956105 107.880677)
				(xy 178.03884 107.893011) (xy 178.136119 107.913349) (xy 178.184159 107.940057) (xy 178.239127 107.987515)
			)
		)
	)
	(zone
		(net 315)
		(net_name "Net-(J12H-VCC_RTC)")
		(layer "In2.Cu")
		(name "$teardrop_padvia$")
		(hatch none 0.1)
		(priority 30074)
		(attr
			(teardrop
				(type padvia)
			)
		)
		(connect_pads yes
			(clearance 0)
		)
		(min_thickness 0.0254)
		(filled_areas_thickness no)
		(fill yes
			(thermal_gap 0.5)
			(thermal_bridge_width 0.5)
			(island_removal_mode 1)
			(island_area_min 10)
		)
		(polygon
			(pts
				(xy 166.749323 158.9625) (xy 166.818764 158.967318) (xy 166.870088 158.98104) (xy 166.945629 159.027755)
				(xy 166.957769 159.037299) (xy 167.024997 159.087081) (xy 167.151 158.9) (xy 167.024997 158.712919)
				(xy 166.957768 158.762702) (xy 166.874602 158.817106) (xy 166.821748 158.83219) (xy 166.749323 158.8375)
			)
		)
	)
	(zone
		(net 339)
		(net_name "/Com Express 7 Interfaces/SDIO.CLK")
		(layer "In2.Cu")
		(name "$teardrop_padvia$")
		(hatch none 0.1)
		(priority 30012)
		(attr
			(teardrop
				(type padvia)
			)
		)
		(connect_pads yes
			(clearance 0)
		)
		(min_thickness 0.0254)
		(filled_areas_thickness no)
		(fill yes
			(thermal_gap 0.5)
			(thermal_bridge_width 0.5)
			(island_removal_mode 1)
			(island_area_min 10)
		)
		(polygon
			(pts
				(xy 166.800677 160.8225) (xy 166.732314 160.817809) (xy 166.68003 160.804974) (xy 166.590652 160.756057)
				(xy 166.487778 160.6975) (xy 166.399 160.9) (xy 166.487778 161.1025) (xy 166.590651 161.043943)
				(xy 166.674447 160.997067) (xy 166.728713 160.982761) (xy 166.800677 160.9775)
			)
		)
	)
	(zone
		(net 321)
		(net_name "/Com Express 7 Interfaces/SDIO.DAT0")
		(layer "In2.Cu")
		(name "$teardrop_padvia$")
		(hatch none 0.1)
		(priority 30014)
		(attr
			(teardrop
				(type padvia)
			)
		)
		(connect_pads yes
			(clearance 0)
		)
		(min_thickness 0.0254)
		(filled_areas_thickness no)
		(fill yes
			(thermal_gap 0.5)
			(thermal_bridge_width 0.5)
			(island_removal_mode 1)
			(island_area_min 10)
		)
		(polygon
			(pts
				(xy 202.099323 167.5775) (xy 202.167686 167.582191) (xy 202.21997 167.595026) (xy 202.309348 167.643942)
				(xy 202.412222 167.7025) (xy 202.501 167.5) (xy 202.412222 167.2975) (xy 202.309347 167.356058)
				(xy 202.225552 167.402933) (xy 202.171286 167.417239) (xy 202.099323 167.4225)
			)
		)
	)
	(zone
		(net 875)
		(net_name "/2xSFP+/SCL1")
		(layer "In2.Cu")
		(name "$teardrop_padvia$")
		(hatch none 0.1)
		(priority 30172)
		(attr
			(teardrop
				(type padvia)
			)
		)
		(connect_pads yes
			(clearance 0)
		)
		(min_thickness 0.0254)
		(filled_areas_thickness no)
		(fill yes
			(thermal_gap 0.5)
			(thermal_bridge_width 0.5)
			(island_removal_mode 1)
			(island_area_min 10)
		)
		(polygon
			(pts
				(xy 175.360873 148.327515) (xy 175.413382 148.281819) (xy 175.459376 148.255231) (xy 175.545824 148.234847)
				(xy 175.56116 148.233011) (xy 175.643895 148.220677) (xy 175.600707 147.999293) (xy 175.379323 147.956105)
				(xy 175.366988 148.038841) (xy 175.346651 148.136119) (xy 175.319943 148.184159) (xy 175.272485 148.239127)
			)
		)
	)
	(zone
		(net 528)
		(net_name "/Backplane/~{PERST}")
		(layer "In2.Cu")
		(name "$teardrop_padvia$")
		(hatch none 0.1)
		(priority 30046)
		(attr
			(teardrop
				(type padvia)
			)
		)
		(connect_pads yes
			(clearance 0)
		)
		(min_thickness 0.0254)
		(filled_areas_thickness no)
		(fill yes
			(thermal_gap 0.5)
			(thermal_bridge_width 0.5)
			(island_removal_mode 1)
			(island_area_min 10)
		)
		(polygon
			(pts
				(xy 157.4875 155.929323) (xy 157.482682 155.998763) (xy 157.46896 156.050087) (xy 157.422245 156.125628)
				(xy 157.412702 156.137768) (xy 157.362919 156.204997) (xy 157.55 156.331) (xy 157.737081 156.204997)
				(xy 157.687299 156.137769) (xy 157.632894 156.054603) (xy 157.61781 156.001748) (xy 157.6125 155.929323)
			)
		)
	)
	(zone
		(net 303)
		(net_name "/Com Express 7 MGMT/~{SUS_S5}")
		(layer "In2.Cu")
		(name "$teardrop_padvia$")
		(hatch none 0.1)
		(priority 30182)
		(attr
			(teardrop
				(type padvia)
			)
		)
		(connect_pads yes
			(clearance 0)
		)
		(min_thickness 0.0254)
		(filled_areas_thickness no)
		(fill yes
			(thermal_gap 0.5)
			(thermal_bridge_width 0.5)
			(island_removal_mode 1)
			(island_area_min 10)
		)
		(polygon
			(pts
				(xy 158.310873 154.727515) (xy 158.363382 154.681819) (xy 158.409376 154.655231) (xy 158.495824 154.634847)
				(xy 158.51116 154.633011) (xy 158.593895 154.620677) (xy 158.550707 154.399293) (xy 158.329323 154.356105)
				(xy 158.316988 154.438841) (xy 158.296651 154.536119) (xy 158.269943 154.584159) (xy 158.222485 154.639127)
			)
		)
	)
	(zone
		(net 164)
		(net_name "/2xSFP+/SDA0")
		(layer "In2.Cu")
		(name "$teardrop_padvia$")
		(hatch none 0.1)
		(priority 30107)
		(attr
			(teardrop
				(type padvia)
			)
		)
		(connect_pads yes
			(clearance 0)
		)
		(min_thickness 0.0254)
		(filled_areas_thickness no)
		(fill yes
			(thermal_gap 0.5)
			(thermal_bridge_width 0.5)
			(island_removal_mode 1)
			(island_area_min 10)
		)
		(polygon
			(pts
				(xy 165.900677 146.0375) (xy 165.831236 146.032682) (xy 165.779913 146.01896) (xy 165.704371 145.972246)
				(xy 165.692231 145.962701) (xy 165.625003 145.912919) (xy 165.499 146.1) (xy 165.625003 146.287081)
				(xy 165.692229 146.237299) (xy 165.775396 146.182894) (xy 165.828251 146.16781) (xy 165.900677 146.1625)
			)
		)
	)
	(zone
		(net 165)
		(net_name "/2xSFP+/SCL0")
		(layer "In2.Cu")
		(name "$teardrop_padvia$")
		(hatch none 0.1)
		(priority 30067)
		(attr
			(teardrop
				(type padvia)
			)
		)
		(connect_pads yes
			(clearance 0)
		)
		(min_thickness 0.0254)
		(filled_areas_thickness no)
		(fill yes
			(thermal_gap 0.5)
			(thermal_bridge_width 0.5)
			(island_removal_mode 1)
			(island_area_min 10)
		)
		(polygon
			(pts
				(xy 176.599323 147.0625) (xy 176.668764 147.067318) (xy 176.720088 147.08104) (xy 176.795629 147.127755)
				(xy 176.807769 147.137299) (xy 176.874997 147.187081) (xy 177.001 147) (xy 176.874997 146.812919)
				(xy 176.807768 146.862702) (xy 176.724602 146.917106) (xy 176.671748 146.93219) (xy 176.599323 146.9375)
			)
		)
	)
	(zone
		(net 356)
		(net_name "/Com Express 7 MGMT/~{CW_PWRBTN}")
		(layer "In2.Cu")
		(name "$teardrop_padvia$")
		(hatch none 0.1)
		(priority 30095)
		(attr
			(teardrop
				(type padvia)
			)
		)
		(connect_pads yes
			(clearance 0)
		)
		(min_thickness 0.0254)
		(filled_areas_thickness no)
		(fill yes
			(thermal_gap 0.5)
			(thermal_bridge_width 0.5)
			(island_removal_mode 1)
			(island_area_min 10)
		)
		(polygon
			(pts
				(xy 223.4625 146.300677) (xy 223.467318 146.231236) (xy 223.48104 146.179912) (xy 223.527755 146.10437)
				(xy 223.537299 146.092229) (xy 223.587081 146.025003) (xy 223.4 145.899) (xy 223.212919 146.025003)
				(xy 223.262701 146.092231) (xy 223.317106 146.175397) (xy 223.33219 146.228251) (xy 223.3375 146.300677)
			)
		)
	)
	(zone
		(net 358)
		(net_name "/Com Express 7 MGMT/SMBus.SDA")
		(layer "In2.Cu")
		(name "$teardrop_padvia$")
		(hatch none 0.1)
		(priority 30055)
		(attr
			(teardrop
				(type padvia)
			)
		)
		(connect_pads yes
			(clearance 0)
		)
		(min_thickness 0.0254)
		(filled_areas_thickness no)
		(fill yes
			(thermal_gap 0.5)
			(thermal_bridge_width 0.5)
			(island_removal_mode 1)
			(island_area_min 10)
		)
		(polygon
			(pts
				(xy 110.1125 162.171823) (xy 110.107682 162.241263) (xy 110.09396 162.292587) (xy 110.047245 162.368128)
				(xy 110.037702 162.380268) (xy 109.987919 162.447497) (xy 110.175 162.5735) (xy 110.362081 162.447497)
				(xy 110.312299 162.380269) (xy 110.257894 162.297103) (xy 110.24281 162.244248) (xy 110.2375 162.171823)
			)
		)
	)
	(zone
		(net 135)
		(net_name "Net-(D19-Pad3)")
		(layer "In2.Cu")
		(name "$teardrop_padvia$")
		(hatch none 0.1)
		(priority 30000)
		(attr
			(teardrop
				(type padvia)
			)
		)
		(connect_pads yes
			(clearance 0)
		)
		(min_thickness 0.0254)
		(filled_areas_thickness no)
		(fill yes
			(thermal_gap 0.5)
			(thermal_bridge_width 0.5)
			(island_removal_mode 1)
			(island_area_min 10)
		)
		(polygon
			(pts
				(xy 222.462258 69.43361) (xy 222.367308 69.521661) (xy 222.278795 69.590165) (xy 222.19954 69.639326)
				(xy 222.1234 69.67542) (xy 221.970836 69.717845) (xy 221.7811 69.734431) (xy 221.73573 69.736089)
				(xy 221.550362 69.74587) (xy 221.332173 69.776333) (xy 221.497293 70.610707) (xy 222.331667 70.775827)
				(xy 222.364197 70.531229) (xy 222.37191 70.37227) (xy 222.382577 70.192159) (xy 222.395863 70.10666)
				(xy 222.418869 70.021566) (xy 222.454911 69.934901) (xy 222.507301 69.844692) (xy 222.579356 69.748964)
				(xy 222.67439 69.645742)
			)
		)
	)
	(zone
		(net 321)
		(net_name "/Com Express 7 Interfaces/SDIO.DAT0")
		(layer "In2.Cu")
		(name "$teardrop_padvia$")
		(hatch none 0.1)
		(priority 30011)
		(attr
			(teardrop
				(type padvia)
			)
		)
		(connect_pads yes
			(clearance 0)
		)
		(min_thickness 0.0254)
		(filled_areas_thickness no)
		(fill yes
			(thermal_gap 0.5)
			(thermal_bridge_width 0.5)
			(island_removal_mode 1)
			(island_area_min 10)
		)
		(polygon
			(pts
				(xy 166.800677 159.8225) (xy 166.732314 159.817809) (xy 166.68003 159.804974) (xy 166.590652 159.756057)
				(xy 166.487778 159.6975) (xy 166.399 159.9) (xy 166.487778 160.1025) (xy 166.590651 160.043943)
				(xy 166.674447 159.997067) (xy 166.728713 159.982761) (xy 166.800677 159.9775)
			)
		)
	)
	(zone
		(net 365)
		(net_name "/Com Express 7 MGMT/PWR_OK")
		(layer "In2.Cu")
		(name "$teardrop_padvia$")
		(hatch none 0.1)
		(priority 30091)
		(attr
			(teardrop
				(type padvia)
			)
		)
		(connect_pads yes
			(clearance 0)
		)
		(min_thickness 0.0254)
		(filled_areas_thickness no)
		(fill yes
			(thermal_gap 0.5)
			(thermal_bridge_width 0.5)
			(island_removal_mode 1)
			(island_area_min 10)
		)
		(polygon
			(pts
				(xy 186.0125 146.850677) (xy 186.017318 146.781236) (xy 186.03104 146.729912) (xy 186.077755 146.65437)
				(xy 186.087299 146.642229) (xy 186.137081 146.575003) (xy 185.95 146.449) (xy 185.762919 146.575003)
				(xy 185.812701 146.642231) (xy 185.867106 146.725397) (xy 185.88219 146.778251) (xy 185.8875 146.850677)
			)
		)
	)
	(zone
		(net 727)
		(net_name "Net-(U43C-PRBS_{PASS})")
		(layer "In2.Cu")
		(name "$teardrop_padvia$")
		(hatch none 0.1)
		(priority 30102)
		(attr
			(teardrop
				(type padvia)
			)
		)
		(connect_pads yes
			(clearance 0)
		)
		(min_thickness 0.0254)
		(filled_areas_thickness no)
		(fill yes
			(thermal_gap 0.5)
			(thermal_bridge_width 0.5)
			(island_removal_mode 1)
			(island_area_min 10)
		)
		(polygon
			(pts
				(xy 149.2625 130.540677) (xy 149.267318 130.471236) (xy 149.28104 130.419912) (xy 149.327755 130.34437)
				(xy 149.337299 130.332229) (xy 149.387081 130.265003) (xy 149.2 130.139) (xy 149.012919 130.265003)
				(xy 149.062701 130.332231) (xy 149.117106 130.415397) (xy 149.13219 130.468251) (xy 149.1375 130.540677)
			)
		)
	)
	(zone
		(net 587)
		(net_name "/M.2 key E/SUSCLK")
		(layer "In2.Cu")
		(name "$teardrop_padvia$")
		(hatch none 0.1)
		(priority 30112)
		(attr
			(teardrop
				(type padvia)
			)
		)
		(connect_pads yes
			(clearance 0)
		)
		(min_thickness 0.0254)
		(filled_areas_thickness no)
		(fill yes
			(thermal_gap 0.5)
			(thermal_bridge_width 0.5)
			(island_removal_mode 1)
			(island_area_min 10)
		)
		(polygon
			(pts
				(xy 143.350677 83.0475) (xy 143.281236 83.042682) (xy 143.229913 83.02896) (xy 143.154371 82.982246)
				(xy 143.142231 82.972701) (xy 143.075003 82.922919) (xy 142.949 83.11) (xy 143.075003 83.297081)
				(xy 143.142229 83.247299) (xy 143.225396 83.192894) (xy 143.278251 83.17781) (xy 143.350677 83.1725)
			)
		)
	)
	(zone
		(net 587)
		(net_name "/M.2 key E/SUSCLK")
		(layer "In2.Cu")
		(name "$teardrop_padvia$")
		(hatch none 0.1)
		(priority 30079)
		(attr
			(teardrop
				(type padvia)
			)
		)
		(connect_pads yes
			(clearance 0)
		)
		(min_thickness 0.0254)
		(filled_areas_thickness no)
		(fill yes
			(thermal_gap 0.5)
			(thermal_bridge_width 0.5)
			(island_removal_mode 1)
			(island_area_min 10)
		)
		(polygon
			(pts
				(xy 247.720031 80.3225) (xy 247.789472 80.327318) (xy 247.840796 80.34104) (xy 247.916337 80.387755)
				(xy 247.928477 80.397299) (xy 247.995705 80.447081) (xy 248.121708 80.26) (xy 247.995705 80.072919)
				(xy 247.928476 80.122702) (xy 247.84531 80.177106) (xy 247.792456 80.19219) (xy 247.720031 80.1975)
			)
		)
	)
	(zone
		(net 139)
		(net_name "/Com Express 7 MGMT/SPI_POWER")
		(layer "In2.Cu")
		(name "$teardrop_padvia$")
		(hatch none 0.1)
		(priority 30007)
		(attr
			(teardrop
				(type padvia)
			)
		)
		(connect_pads yes
			(clearance 0)
		)
		(min_thickness 0.0254)
		(filled_areas_thickness no)
		(fill yes
			(thermal_gap 0.5)
			(thermal_bridge_width 0.5)
			(island_removal_mode 1)
			(island_area_min 10)
		)
		(polygon
			(pts
				(xy 263.499323 162.6) (xy 263.577235 162.604713) (xy 263.63602 162.6177) (xy 263.727051 162.659802)
				(xy 263.812222 162.7025) (xy 263.901 162.5) (xy 263.812222 162.2975) (xy 263.72705 162.340199) (xy 263.634217 162.382867)
				(xy 263.576078 162.395444) (xy 263.499323 162.4)
			)
		)
	)
	(zone
		(net 425)
		(net_name "/2xSFP+/I2C_{SFP0}.SDA")
		(layer "In2.Cu")
		(name "$teardrop_padvia$")
		(hatch none 0.1)
		(priority 30064)
		(attr
			(teardrop
				(type padvia)
			)
		)
		(connect_pads yes
			(clearance 0)
		)
		(min_thickness 0.0254)
		(filled_areas_thickness no)
		(fill yes
			(thermal_gap 0.5)
			(thermal_bridge_width 0.5)
			(island_removal_mode 1)
			(island_area_min 10)
		)
		(polygon
			(pts
				(xy 180.199323 142.7625) (xy 180.268764 142.767318) (xy 180.320088 142.78104) (xy 180.395629 142.827755)
				(xy 180.407769 142.837299) (xy 180.474997 142.887081) (xy 180.601 142.7) (xy 180.474997 142.512919)
				(xy 180.407768 142.562702) (xy 180.324602 142.617106) (xy 180.271748 142.63219) (xy 180.199323 142.6375)
			)
		)
	)
	(zone
		(net 357)
		(net_name "/Com Express 7 MGMT/SMBus.SCL")
		(layer "In2.Cu")
		(name "$teardrop_padvia$")
		(hatch none 0.1)
		(priority 30100)
		(attr
			(teardrop
				(type padvia)
			)
		)
		(connect_pads yes
			(clearance 0)
		)
		(min_thickness 0.0254)
		(filled_areas_thickness no)
		(fill yes
			(thermal_gap 0.5)
			(thermal_bridge_width 0.5)
			(island_removal_mode 1)
			(island_area_min 10)
		)
		(polygon
			(pts
				(xy 132.9625 81.680678) (xy 132.967318 81.611237) (xy 132.98104 81.559913) (xy 133.027755 81.484371)
				(xy 133.037299 81.47223) (xy 133.087081 81.405004) (xy 132.9 81.279001) (xy 132.712919 81.405004)
				(xy 132.762701 81.472232) (xy 132.817106 81.555398) (xy 132.83219 81.608252) (xy 132.8375 81.680678)
			)
		)
	)
	(zone
		(net 528)
		(net_name "/Backplane/~{PERST}")
		(layer "In2.Cu")
		(name "$teardrop_padvia$")
		(hatch none 0.1)
		(priority 30136)
		(attr
			(teardrop
				(type padvia)
			)
		)
		(connect_pads yes
			(clearance 0)
		)
		(min_thickness 0.0254)
		(filled_areas_thickness no)
		(fill yes
			(thermal_gap 0.5)
			(thermal_bridge_width 0.5)
			(island_removal_mode 1)
			(island_area_min 10)
		)
		(polygon
			(pts
				(xy 128.139127 80.952486) (xy 128.086618 80.998182) (xy 128.040623 81.024769) (xy 127.954174 81.045153)
				(xy 127.938841 81.046989) (xy 127.856105 81.059324) (xy 127.899293 81.280708) (xy 128.120677 81.323896)
				(xy 128.133011 81.241161) (xy 128.153349 81.143882) (xy 128.180057 81.095842) (xy 128.227515 81.040874)
			)
		)
	)
	(zone
		(net 357)
		(net_name "/Com Express 7 MGMT/SMBus.SCL")
		(layer "In2.Cu")
		(name "$teardrop_padvia$")
		(hatch none 0.1)
		(priority 30175)
		(attr
			(teardrop
				(type padvia)
			)
		)
		(connect_pads yes
			(clearance 0)
		)
		(min_thickness 0.0254)
		(filled_areas_thickness no)
		(fill yes
			(thermal_gap 0.5)
			(thermal_bridge_width 0.5)
			(island_removal_mode 1)
			(island_area_min 10)
		)
		(polygon
			(pts
				(xy 120.860873 153.052515) (xy 120.913382 153.006819) (xy 120.959376 152.980231) (xy 121.045824 152.959847)
				(xy 121.06116 152.958011) (xy 121.143895 152.945677) (xy 121.100707 152.724293) (xy 120.879323 152.681105)
				(xy 120.866988 152.763841) (xy 120.846651 152.861119) (xy 120.819943 152.909159) (xy 120.772485 152.964127)
			)
		)
	)
	(zone
		(net 542)
		(net_name "Net-(Q9-E)")
		(layer "In2.Cu")
		(name "$teardrop_padvia$")
		(hatch none 0.1)
		(priority 30047)
		(attr
			(teardrop
				(type padvia)
			)
		)
		(connect_pads yes
			(clearance 0)
		)
		(min_thickness 0.0254)
		(filled_areas_thickness no)
		(fill yes
			(thermal_gap 0.5)
			(thermal_bridge_width 0.5)
			(island_removal_mode 1)
			(island_area_min 10)
		)
		(polygon
			(pts
				(xy 121.7375 140.509323) (xy 121.732682 140.578763) (xy 121.71896 140.630087) (xy 121.672245 140.705628)
				(xy 121.662702 140.717768) (xy 121.612919 140.784997) (xy 121.8 140.911) (xy 121.987081 140.784997)
				(xy 121.937299 140.717769) (xy 121.882894 140.634603) (xy 121.86781 140.581748) (xy 121.8625 140.509323)
			)
		)
	)
	(zone
		(net 434)
		(net_name "/Com Express 7 MGMT/~{TYPE1}")
		(layer "In2.Cu")
		(name "$teardrop_padvia$")
		(hatch none 0.1)
		(priority 30143)
		(attr
			(teardrop
				(type padvia)
			)
		)
		(connect_pads yes
			(clearance 0)
		)
		(min_thickness 0.0254)
		(filled_areas_thickness no)
		(fill yes
			(thermal_gap 0.5)
			(thermal_bridge_width 0.5)
			(island_removal_mode 1)
			(island_area_min 10)
		)
		(polygon
			(pts
				(xy 204.289127 155.147485) (xy 204.236618 155.193181) (xy 204.190623 155.219768) (xy 204.104174 155.240152)
				(xy 204.088841 155.241988) (xy 204.006105 155.254323) (xy 204.049293 155.475707) (xy 204.270677 155.518895)
				(xy 204.283011 155.43616) (xy 204.303349 155.338881) (xy 204.330057 155.290841) (xy 204.377515 155.235873)
			)
		)
	)
	(zone
		(net 894)
		(net_name "Net-(J2B-MOD_{ABS})")
		(layer "In2.Cu")
		(name "$teardrop_padvia$")
		(hatch none 0.1)
		(priority 30140)
		(attr
			(teardrop
				(type padvia)
			)
		)
		(connect_pads yes
			(clearance 0)
		)
		(min_thickness 0.0254)
		(filled_areas_thickness no)
		(fill yes
			(thermal_gap 0.5)
			(thermal_bridge_width 0.5)
			(island_removal_mode 1)
			(island_area_min 10)
		)
		(polygon
			(pts
				(xy 167.339127 147.372485) (xy 167.286618 147.418181) (xy 167.240623 147.444768) (xy 167.154174 147.465152)
				(xy 167.138841 147.466988) (xy 167.056105 147.479323) (xy 167.099293 147.700707) (xy 167.320677 147.743895)
				(xy 167.333011 147.66116) (xy 167.353349 147.563881) (xy 167.380057 147.515841) (xy 167.427515 147.460873)
			)
		)
	)
	(zone
		(net 542)
		(net_name "Net-(Q9-E)")
		(layer "In2.Cu")
		(name "$teardrop_padvia$")
		(hatch none 0.1)
		(priority 30044)
		(attr
			(teardrop
				(type padvia)
			)
		)
		(connect_pads yes
			(clearance 0)
		)
		(min_thickness 0.0254)
		(filled_areas_thickness no)
		(fill yes
			(thermal_gap 0.5)
			(thermal_bridge_width 0.5)
			(island_removal_mode 1)
			(island_area_min 10)
		)
		(polygon
			(pts
				(xy 255.6875 83.429322) (xy 255.682682 83.498762) (xy 255.66896 83.550086) (xy 255.622245 83.625627)
				(xy 255.612702 83.637767) (xy 255.562919 83.704996) (xy 255.75 83.830999) (xy 255.937081 83.704996)
				(xy 255.887299 83.637768) (xy 255.832894 83.554602) (xy 255.81781 83.501747) (xy 255.8125 83.429322)
			)
		)
	)
	(zone
		(net 345)
		(net_name "/Com Express 7 MGMT/SER0.RX")
		(layer "In2.Cu")
		(name "$teardrop_padvia$")
		(hatch none 0.1)
		(priority 30071)
		(attr
			(teardrop
				(type padvia)
			)
		)
		(connect_pads yes
			(clearance 0)
		)
		(min_thickness 0.0254)
		(filled_areas_thickness no)
		(fill yes
			(thermal_gap 0.5)
			(thermal_bridge_width 0.5)
			(island_removal_mode 1)
			(island_area_min 10)
		)
		(polygon
			(pts
				(xy 215.599323 146.2625) (xy 215.668764 146.267318) (xy 215.720088 146.28104) (xy 215.795629 146.327755)
				(xy 215.807769 146.337299) (xy 215.874997 146.387081) (xy 216.001 146.2) (xy 215.874997 146.012919)
				(xy 215.807768 146.062702) (xy 215.724602 146.117106) (xy 215.671748 146.13219) (xy 215.599323 146.1375)
			)
		)
	)
	(zone
		(net 359)
		(net_name "/Com Express 7 MGMT/SMBus.~{INT}")
		(layer "In2.Cu")
		(name "$teardrop_padvia$")
		(hatch none 0.1)
		(priority 30181)
		(attr
			(teardrop
				(type padvia)
			)
		)
		(connect_pads yes
			(clearance 0)
		)
		(min_thickness 0.0254)
		(filled_areas_thickness no)
		(fill yes
			(thermal_gap 0.5)
			(thermal_bridge_width 0.5)
			(island_removal_mode 1)
			(island_area_min 10)
		)
		(polygon
			(pts
				(xy 200.660873 122.627515) (xy 200.713382 122.581819) (xy 200.759376 122.555231) (xy 200.845824 122.534847)
				(xy 200.86116 122.533011) (xy 200.943895 122.520677) (xy 200.900707 122.299293) (xy 200.679323 122.256105)
				(xy 200.666988 122.338841) (xy 200.646651 122.436119) (xy 200.619943 122.484159) (xy 200.572485 122.539127)
			)
		)
	)
	(zone
		(net 423)
		(net_name "/2xSFP+/I2C_{LED}.SCL")
		(layer "In2.Cu")
		(name "$teardrop_padvia$")
		(hatch none 0.1)
		(priority 30158)
		(attr
			(teardrop
				(type padvia)
			)
		)
		(connect_pads yes
			(clearance 0)
		)
		(min_thickness 0.0254)
		(filled_areas_thickness no)
		(fill yes
			(thermal_gap 0.5)
			(thermal_bridge_width 0.5)
			(island_removal_mode 1)
			(island_area_min 10)
		)
		(polygon
			(pts
				(xy 175.872485 153.135873) (xy 175.918181 153.188382) (xy 175.944768 153.234376) (xy 175.965152 153.320825)
				(xy 175.966988 153.336158) (xy 175.979323 153.418895) (xy 176.200707 153.375707) (xy 176.243895 153.154323)
				(xy 176.161158 153.141988) (xy 176.06388 153.121651) (xy 176.01584 153.094943) (xy 175.960873 153.047485)
			)
		)
	)
	(zone
		(net 315)
		(net_name "Net-(J12H-VCC_RTC)")
		(layer "In2.Cu")
		(name "$teardrop_padvia$")
		(hatch none 0.1)
		(priority 30049)
		(attr
			(teardrop
				(type padvia)
			)
		)
		(connect_pads yes
			(clearance 0)
		)
		(min_thickness 0.0254)
		(filled_areas_thickness no)
		(fill yes
			(thermal_gap 0.5)
			(thermal_bridge_width 0.5)
			(island_removal_mode 1)
			(island_area_min 10)
		)
		(polygon
			(pts
				(xy 199.5375 166.449323) (xy 199.532682 166.518763) (xy 199.51896 166.570087) (xy 199.472245 166.645628)
				(xy 199.462702 166.657768) (xy 199.412919 166.724997) (xy 199.6 166.851) (xy 199.787081 166.724997)
				(xy 199.737299 166.657769) (xy 199.682894 166.574603) (xy 199.66781 166.521748) (xy 199.6625 166.449323)
			)
		)
	)
	(zone
		(net 930)
		(net_name "Net-(D5-C)")
		(layer "In2.Cu")
		(name "$teardrop_padvia$")
		(hatch none 0.1)
		(priority 30207)
		(attr
			(teardrop
				(type padvia)
			)
		)
		(connect_pads yes
			(clearance 0)
		)
		(min_thickness 0.0254)
		(filled_areas_thickness no)
		(fill yes
			(thermal_gap 0.5)
			(thermal_bridge_width 0.5)
			(island_removal_mode 1)
			(island_area_min 10)
		)
		(polygon
			(pts
				(xy 139.574127 155.847485) (xy 139.523677 155.891162) (xy 139.479079 155.916637) (xy 139.395164 155.935408)
				(xy 139.376783 155.93717) (xy 139.286105 155.949323) (xy 139.329293 156.170707) (xy 139.550677 156.213895)
				(xy 139.562667 156.140469) (xy 139.585659 156.040579) (xy 139.613585 155.991973) (xy 139.662515 155.935873)
			)
		)
	)
	(zone
		(net 357)
		(net_name "/Com Express 7 MGMT/SMBus.SCL")
		(layer "In2.Cu")
		(name "$teardrop_padvia$")
		(hatch none 0.1)
		(priority 30121)
		(attr
			(teardrop
				(type padvia)
			)
		)
		(connect_pads yes
			(clearance 0)
		)
		(min_thickness 0.0254)
		(filled_areas_thickness no)
		(fill yes
			(thermal_gap 0.5)
			(thermal_bridge_width 0.5)
			(island_removal_mode 1)
			(island_area_min 10)
		)
		(polygon
			(pts
				(xy 167.175677 163.8375) (xy 167.106236 163.832682) (xy 167.054913 163.81896) (xy 166.979371 163.772246)
				(xy 166.967231 163.762701) (xy 166.900003 163.712919) (xy 166.774 163.9) (xy 166.900003 164.087081)
				(xy 166.967229 164.037299) (xy 167.050396 163.982894) (xy 167.103251 163.96781) (xy 167.175677 163.9625)
			)
		)
	)
	(zone
		(net 874)
		(net_name "/2xSFP+/SDA1")
		(layer "In2.Cu")
		(name "$teardrop_padvia$")
		(hatch none 0.1)
		(priority 30174)
		(attr
			(teardrop
				(type padvia)
			)
		)
		(connect_pads yes
			(clearance 0)
		)
		(min_thickness 0.0254)
		(filled_areas_thickness no)
		(fill yes
			(thermal_gap 0.5)
			(thermal_bridge_width 0.5)
			(island_removal_mode 1)
			(island_area_min 10)
		)
		(polygon
			(pts
				(xy 165.360873 144.727515) (xy 165.413382 144.681819) (xy 165.459376 144.655231) (xy 165.545824 144.634847)
				(xy 165.56116 144.633011) (xy 165.643895 144.620677) (xy 165.600707 144.399293) (xy 165.379323 144.356105)
				(xy 165.366988 144.438841) (xy 165.346651 144.536119) (xy 165.319943 144.584159) (xy 165.272485 144.639127)
			)
		)
	)
	(zone
		(net 528)
		(net_name "/Backplane/~{PERST}")
		(layer "In2.Cu")
		(name "$teardrop_padvia$")
		(hatch none 0.1)
		(priority 30211)
		(attr
			(teardrop
				(type padvia)
			)
		)
		(connect_pads yes
			(clearance 0)
		)
		(min_thickness 0.0254)
		(filled_areas_thickness no)
		(fill yes
			(thermal_gap 0.5)
			(thermal_bridge_width 0.5)
			(island_removal_mode 1)
			(island_area_min 10)
		)
		(polygon
			(pts
				(xy 264.534569 93.557957) (xy 264.54265 93.572596) (xy 264.537932 93.585498) (xy 264.476895 93.618271)
				(xy 264.43589 93.637278) (xy 264.428478 93.646841) (xy 264.435574 93.656952) (xy 264.550707 93.485707)
				(xy 264.435574 93.656952) (xy 264.486999 93.669704) (xy 264.556701 93.648537) (xy 264.594612 93.622356)
				(xy 264.625014 93.58943) (xy 264.642889 93.555444) (xy 264.647686 93.520251) (xy 264.640672 93.494161)
				(xy 264.622957 93.469569)
			)
		)
	)
	(zone
		(net 357)
		(net_name "/Com Express 7 MGMT/SMBus.SCL")
		(layer "In2.Cu")
		(name "$teardrop_padvia$")
		(hatch none 0.1)
		(priority 30027)
		(attr
			(teardrop
				(type padvia)
			)
		)
		(connect_pads yes
			(clearance 0)
		)
		(min_thickness 0.0254)
		(filled_areas_thickness no)
		(fill yes
			(thermal_gap 0.5)
			(thermal_bridge_width 0.5)
			(island_removal_mode 1)
			(island_area_min 10)
		)
		(polygon
			(pts
				(xy 128.233651 150.6775) (xy 128.144294 150.672904) (xy 128.079145 150.660733) (xy 128.016031 150.640803)
				(xy 127.899201 150.60652) (xy 127.849 150.825) (xy 127.984681 151.002402) (xy 128.047213 150.935965)
				(xy 128.068426 150.903897) (xy 128.094966 150.864872) (xy 128.126596 150.832592) (xy 128.170447 150.810616)
				(xy 128.233651 150.8025)
			)
		)
	)
	(zone
		(net 315)
		(net_name "Net-(J12H-VCC_RTC)")
		(layer "In2.Cu")
		(name "$teardrop_padvia$")
		(hatch none 0.1)
		(priority 30099)
		(attr
			(teardrop
				(type padvia)
			)
		)
		(connect_pads yes
			(clearance 0)
		)
		(min_thickness 0.0254)
		(filled_areas_thickness no)
		(fill yes
			(thermal_gap 0.5)
			(thermal_bridge_width 0.5)
			(island_removal_mode 1)
			(island_area_min 10)
		)
		(polygon
			(pts
				(xy 167.9125 150.350677) (xy 167.917318 150.281236) (xy 167.93104 150.229912) (xy 167.977755 150.15437)
				(xy 167.987299 150.142229) (xy 168.037081 150.075003) (xy 167.85 149.949) (xy 167.662919 150.075003)
				(xy 167.712701 150.142231) (xy 167.767106 150.225397) (xy 167.78219 150.278251) (xy 167.7875 150.350677)
			)
		)
	)
	(zone
		(net 166)
		(net_name "Net-(J2A-MOD_{ABS})")
		(layer "In2.Cu")
		(name "$teardrop_padvia$")
		(hatch none 0.1)
		(priority 30164)
		(attr
			(teardrop
				(type padvia)
			)
		)
		(connect_pads yes
			(clearance 0)
		)
		(min_thickness 0.0254)
		(filled_areas_thickness no)
		(fill yes
			(thermal_gap 0.5)
			(thermal_bridge_width 0.5)
			(island_removal_mode 1)
			(island_area_min 10)
		)
		(polygon
			(pts
				(xy 164.872485 148.060873) (xy 164.918181 148.113382) (xy 164.944768 148.159376) (xy 164.965152 148.245825)
				(xy 164.966988 148.261158) (xy 164.979323 148.343895) (xy 165.200707 148.300707) (xy 165.243895 148.079323)
				(xy 165.161158 148.066988) (xy 165.06388 148.046651) (xy 165.01584 148.019943) (xy 164.960873 147.972485)
			)
		)
	)
	(zone
		(net 357)
		(net_name "/Com Express 7 MGMT/SMBus.SCL")
		(layer "In2.Cu")
		(name "$teardrop_padvia$")
		(hatch none 0.1)
		(priority 30138)
		(attr
			(teardrop
				(type padvia)
			)
		)
		(connect_pads yes
			(clearance 0)
		)
		(min_thickness 0.0254)
		(filled_areas_thickness no)
		(fill yes
			(thermal_gap 0.5)
			(thermal_bridge_width 0.5)
			(island_removal_mode 1)
			(island_area_min 10)
		)
		(polygon
			(pts
				(xy 110.199127 163.202485) (xy 110.146618 163.248181) (xy 110.100623 163.274768) (xy 110.014174 163.295152)
				(xy 109.998841 163.296988) (xy 109.916105 163.309323) (xy 109.959293 163.530707) (xy 110.180677 163.573895)
				(xy 110.193011 163.49116) (xy 110.213349 163.393881) (xy 110.240057 163.345841) (xy 110.287515 163.290873)
			)
		)
	)
	(zone
		(net 365)
		(net_name "/Com Express 7 MGMT/PWR_OK")
		(layer "In2.Cu")
		(name "$teardrop_padvia$")
		(hatch none 0.1)
		(priority 30160)
		(attr
			(teardrop
				(type padvia)
			)
		)
		(connect_pads yes
			(clearance 0)
		)
		(min_thickness 0.0254)
		(filled_areas_thickness no)
		(fill yes
			(thermal_gap 0.5)
			(thermal_bridge_width 0.5)
			(island_removal_mode 1)
			(island_area_min 10)
		)
		(polygon
			(pts
				(xy 190.422485 152.560873) (xy 190.468181 152.613382) (xy 190.494768 152.659376) (xy 190.515152 152.745825)
				(xy 190.516988 152.761158) (xy 190.529323 152.843895) (xy 190.750707 152.800707) (xy 190.793895 152.579323)
				(xy 190.711158 152.566988) (xy 190.61388 152.546651) (xy 190.56584 152.519943) (xy 190.510873 152.472485)
			)
		)
	)
	(zone
		(net 749)
		(net_name "Net-(U45C-AMUXB)")
		(layer "In2.Cu")
		(name "$teardrop_padvia$")
		(hatch none 0.1)
		(priority 30125)
		(attr
			(teardrop
				(type padvia)
			)
		)
		(connect_pads yes
			(clearance 0)
		)
		(min_thickness 0.0254)
		(filled_areas_thickness no)
		(fill yes
			(thermal_gap 0.5)
			(thermal_bridge_width 0.5)
			(island_removal_mode 1)
			(island_area_min 10)
		)
		(polygon
			(pts
				(xy 135.529127 134.532485) (xy 135.476618 134.578181) (xy 135.430623 134.604768) (xy 135.344174 134.625152)
				(xy 135.328841 134.626988) (xy 135.246105 134.639323) (xy 135.289293 134.860707) (xy 135.510677 134.903895)
				(xy 135.523011 134.82116) (xy 135.543349 134.723881) (xy 135.570057 134.675841) (xy 135.617515 134.620873)
			)
		)
	)
	(zone
		(net 357)
		(net_name "/Com Express 7 MGMT/SMBus.SCL")
		(layer "In2.Cu")
		(name "$teardrop_padvia$")
		(hatch none 0.1)
		(priority 30202)
		(attr
			(teardrop
				(type padvia)
			)
		)
		(connect_pads yes
			(clearance 0)
		)
		(min_thickness 0.0254)
		(filled_areas_thickness no)
		(fill yes
			(thermal_gap 0.5)
			(thermal_bridge_width 0.5)
			(island_removal_mode 1)
			(island_area_min 10)
		)
		(polygon
			(pts
				(xy 160.127515 147.239127) (xy 160.081819 147.186618) (xy 160.055231 147.140623) (xy 160.034847 147.054175)
				(xy 160.033011 147.03884) (xy 160.020677 146.956105) (xy 159.799293 146.999293) (xy 159.756105 147.220677)
				(xy 159.83884 147.233011) (xy 159.936119 147.253349) (xy 159.984159 147.280057) (xy 160.039127 147.327515)
			)
		)
	)
	(zone
		(net 24)
		(net_name "/M.2 key E/~{CLKREQ}")
		(layer "In2.Cu")
		(name "$teardrop_padvia$")
		(hatch none 0.1)
		(priority 30094)
		(attr
			(teardrop
				(type padvia)
			)
		)
		(connect_pads yes
			(clearance 0)
		)
		(min_thickness 0.0254)
		(filled_areas_thickness no)
		(fill yes
			(thermal_gap 0.5)
			(thermal_bridge_width 0.5)
			(island_removal_mode 1)
			(island_area_min 10)
		)
		(polygon
			(pts
				(xy 154.7925 84.460177) (xy 154.797318 84.390736) (xy 154.81104 84.339412) (xy 154.857755 84.26387)
				(xy 154.867299 84.251729) (xy 154.917081 84.184503) (xy 154.73 84.0585) (xy 154.542919 84.184503)
				(xy 154.592701 84.251731) (xy 154.647106 84.334897) (xy 154.66219 84.387751) (xy 154.6675 84.460177)
			)
		)
	)
	(zone
		(net 528)
		(net_name "/Backplane/~{PERST}")
		(layer "In2.Cu")
		(name "$teardrop_padvia$")
		(hatch none 0.1)
		(priority 30131)
		(attr
			(teardrop
				(type padvia)
			)
		)
		(connect_pads yes
			(clearance 0)
		)
		(min_thickness 0.0254)
		(filled_areas_thickness no)
		(fill yes
			(thermal_gap 0.5)
			(thermal_bridge_width 0.5)
			(island_removal_mode 1)
			(island_area_min 10)
		)
		(polygon
			(pts
				(xy 291.364127 102.532485) (xy 291.311618 102.578181) (xy 291.265623 102.604768) (xy 291.179174 102.625152)
				(xy 291.163841 102.626988) (xy 291.081105 102.639323) (xy 291.124293 102.860707) (xy 291.345677 102.903895)
				(xy 291.358011 102.82116) (xy 291.378349 102.723881) (xy 291.405057 102.675841) (xy 291.452515 102.620873)
			)
		)
	)
	(zone
		(net 528)
		(net_name "/Backplane/~{PERST}")
		(layer "In2.Cu")
		(name "$teardrop_padvia$")
		(hatch none 0.1)
		(priority 30118)
		(attr
			(teardrop
				(type padvia)
			)
		)
		(connect_pads yes
			(clearance 0)
		)
		(min_thickness 0.0254)
		(filled_areas_thickness no)
		(fill yes
			(thermal_gap 0.5)
			(thermal_bridge_width 0.5)
			(island_removal_mode 1)
			(island_area_min 10)
		)
		(polygon
			(pts
				(xy 122.580677 163.4975) (xy 122.511236 163.492682) (xy 122.459913 163.47896) (xy 122.384371 163.432246)
				(xy 122.372231 163.422701) (xy 122.305003 163.372919) (xy 122.179 163.56) (xy 122.305003 163.747081)
				(xy 122.372229 163.697299) (xy 122.455396 163.642894) (xy 122.508251 163.62781) (xy 122.580677 163.6225)
			)
		)
	)
	(zone
		(net 422)
		(net_name "/2xSFP+/I2C_{LED}.SDA")
		(layer "In2.Cu")
		(name "$teardrop_padvia$")
		(hatch none 0.1)
		(priority 30147)
		(attr
			(teardrop
				(type padvia)
			)
		)
		(connect_pads yes
			(clearance 0)
		)
		(min_thickness 0.0254)
		(filled_areas_thickness no)
		(fill yes
			(thermal_gap 0.5)
			(thermal_bridge_width 0.5)
			(island_removal_mode 1)
			(island_area_min 10)
		)
		(polygon
			(pts
				(xy 160.789127 156.002485) (xy 160.736618 156.048181) (xy 160.690623 156.074768) (xy 160.604174 156.095152)
				(xy 160.588841 156.096988) (xy 160.506105 156.109323) (xy 160.549293 156.330707) (xy 160.770677 156.373895)
				(xy 160.783011 156.29116) (xy 160.803349 156.193881) (xy 160.830057 156.145841) (xy 160.877515 156.090873)
			)
		)
	)
	(zone
		(net 356)
		(net_name "/Com Express 7 MGMT/~{CW_PWRBTN}")
		(layer "In2.Cu")
		(name "$teardrop_padvia$")
		(hatch none 0.1)
		(priority 30153)
		(attr
			(teardrop
				(type padvia)
			)
		)
		(connect_pads yes
			(clearance 0)
		)
		(min_thickness 0.0254)
		(filled_areas_thickness no)
		(fill yes
			(thermal_gap 0.5)
			(thermal_bridge_width 0.5)
			(island_removal_mode 1)
			(island_area_min 10)
		)
		(polygon
			(pts
				(xy 241.472485 133.360873) (xy 241.518181 133.413382) (xy 241.544768 133.459376) (xy 241.565152 133.545825)
				(xy 241.566988 133.561158) (xy 241.579323 133.643895) (xy 241.800707 133.600707) (xy 241.843895 133.379323)
				(xy 241.761158 133.366988) (xy 241.66388 133.346651) (xy 241.61584 133.319943) (xy 241.560873 133.272485)
			)
		)
	)
	(zone
		(net 530)
		(net_name "/M.2 key M #2/~{CLKREQ}")
		(layer "In2.Cu")
		(name "$teardrop_padvia$")
		(hatch none 0.1)
		(priority 30088)
		(attr
			(teardrop
				(type padvia)
			)
		)
		(connect_pads yes
			(clearance 0)
		)
		(min_thickness 0.0254)
		(filled_areas_thickness no)
		(fill yes
			(thermal_gap 0.5)
			(thermal_bridge_width 0.5)
			(island_removal_mode 1)
			(island_area_min 10)
		)
		(polygon
			(pts
				(xy 283.3125 94.700677) (xy 283.317318 94.631236) (xy 283.33104 94.579912) (xy 283.377755 94.50437)
				(xy 283.387299 94.492229) (xy 283.437081 94.425003) (xy 283.25 94.299) (xy 283.062919 94.425003)
				(xy 283.112701 94.492231) (xy 283.167106 94.575397) (xy 283.18219 94.628251) (xy 283.1875 94.700677)
			)
		)
	)
	(zone
		(net 314)
		(net_name "/2xUSB3.0+RJ45/FLG_1")
		(layer "In2.Cu")
		(name "$teardrop_padvia$")
		(hatch none 0.1)
		(priority 30195)
		(attr
			(teardrop
				(type padvia)
			)
		)
		(connect_pads yes
			(clearance 0)
		)
		(min_thickness 0.0254)
		(filled_areas_thickness no)
		(fill yes
			(thermal_gap 0.5)
			(thermal_bridge_width 0.5)
			(island_removal_mode 1)
			(island_area_min 10)
		)
		(polygon
			(pts
				(xy 126.927515 93.239127) (xy 126.881819 93.186618) (xy 126.855231 93.140623) (xy 126.834847 93.054175)
				(xy 126.833011 93.03884) (xy 126.820677 92.956105) (xy 126.599293 92.999293) (xy 126.556105 93.220677)
				(xy 126.63884 93.233011) (xy 126.736119 93.253349) (xy 126.784159 93.280057) (xy 126.839127 93.327515)
			)
		)
	)
	(zone
		(net 424)
		(net_name "/2xSFP+/I2C_{SFP1}.SDA")
		(layer "In2.Cu")
		(name "$teardrop_padvia$")
		(hatch none 0.1)
		(priority 30110)
		(attr
			(teardrop
				(type padvia)
			)
		)
		(connect_pads yes
			(clearance 0)
		)
		(min_thickness 0.0254)
		(filled_areas_thickness no)
		(fill yes
			(thermal_gap 0.5)
			(thermal_bridge_width 0.5)
			(island_removal_mode 1)
			(island_area_min 10)
		)
		(polygon
			(pts
				(xy 180.150677 144.1875) (xy 180.081236 144.182682) (xy 180.029913 144.16896) (xy 179.954371 144.122246)
				(xy 179.942231 144.112701) (xy 179.875003 144.062919) (xy 179.749 144.25) (xy 179.875003 144.437081)
				(xy 179.942229 144.387299) (xy 180.025396 144.332894) (xy 180.078251 144.31781) (xy 180.150677 144.3125)
			)
		)
	)
	(zone
		(net 142)
		(net_name "/2xSFP+/PHY0_{RESET}")
		(layer "In2.Cu")
		(name "$teardrop_padvia$")
		(hatch none 0.1)
		(priority 30073)
		(attr
			(teardrop
				(type padvia)
			)
		)
		(connect_pads yes
			(clearance 0)
		)
		(min_thickness 0.0254)
		(filled_areas_thickness no)
		(fill yes
			(thermal_gap 0.5)
			(thermal_bridge_width 0.5)
			(island_removal_mode 1)
			(island_area_min 10)
		)
		(polygon
			(pts
				(xy 175.749323 154.6625) (xy 175.818764 154.667318) (xy 175.870088 154.68104) (xy 175.945629 154.727755)
				(xy 175.957769 154.737299) (xy 176.024997 154.787081) (xy 176.151 154.6) (xy 176.024997 154.412919)
				(xy 175.957768 154.462702) (xy 175.874602 154.517106) (xy 175.821748 154.53219) (xy 175.749323 154.5375)
			)
		)
	)
	(zone
		(net 528)
		(net_name "/Backplane/~{PERST}")
		(layer "In2.Cu")
		(name "$teardrop_padvia$")
		(hatch none 0.1)
		(priority 30178)
		(attr
			(teardrop
				(type padvia)
			)
		)
		(connect_pads yes
			(clearance 0)
		)
		(min_thickness 0.0254)
		(filled_areas_thickness no)
		(fill yes
			(thermal_gap 0.5)
			(thermal_bridge_width 0.5)
			(island_removal_mode 1)
			(island_area_min 10)
		)
		(polygon
			(pts
				(xy 142.730873 84.387515) (xy 142.783382 84.341819) (xy 142.829376 84.315231) (xy 142.915824 84.294847)
				(xy 142.93116 84.293011) (xy 143.013895 84.280677) (xy 142.970707 84.059293) (xy 142.749323 84.016105)
				(xy 142.736988 84.098841) (xy 142.716651 84.196119) (xy 142.689943 84.244159) (xy 142.642485 84.299127)
			)
		)
	)
	(zone
		(net 303)
		(net_name "/Com Express 7 MGMT/~{SUS_S5}")
		(layer "In2.Cu")
		(name "$teardrop_padvia$")
		(hatch none 0.1)
		(priority 30103)
		(attr
			(teardrop
				(type padvia)
			)
		)
		(connect_pads yes
			(clearance 0)
		)
		(min_thickness 0.0254)
		(filled_areas_thickness no)
		(fill yes
			(thermal_gap 0.5)
			(thermal_bridge_width 0.5)
			(island_removal_mode 1)
			(island_area_min 10)
		)
		(polygon
			(pts
				(xy 222.0625 146.300677) (xy 222.067318 146.231236) (xy 222.08104 146.179912) (xy 222.127755 146.10437)
				(xy 222.137299 146.092229) (xy 222.187081 146.025003) (xy 222 145.899) (xy 221.812919 146.025003)
				(xy 221.862701 146.092231) (xy 221.917106 146.175397) (xy 221.93219 146.228251) (xy 221.9375 146.300677)
			)
		)
	)
	(zone
		(net 526)
		(net_name "/Backplane/~{PRSNT}")
		(layer "In2.Cu")
		(name "$teardrop_padvia$")
		(hatch none 0.1)
		(priority 30083)
		(attr
			(teardrop
				(type padvia)
			)
		)
		(connect_pads yes
			(clearance 0)
		)
		(min_thickness 0.0254)
		(filled_areas_thickness no)
		(fill yes
			(thermal_gap 0.5)
			(thermal_bridge_width 0.5)
			(island_removal_mode 1)
			(island_area_min 10)
		)
		(polygon
			(pts
				(xy 159.274323 108.6625) (xy 159.343764 108.667318) (xy 159.395088 108.68104) (xy 159.470629 108.727755)
				(xy 159.482769 108.737299) (xy 159.549997 108.787081) (xy 159.676 108.6) (xy 159.549997 108.412919)
				(xy 159.482768 108.462702) (xy 159.399602 108.517106) (xy 159.346748 108.53219) (xy 159.274323 108.5375)
			)
		)
	)
	(zone
		(net 338)
		(net_name "/Com Express 7 MGMT/SPI.MISO")
		(layer "In2.Cu")
		(name "$teardrop_padvia$")
		(hatch none 0.1)
		(priority 30036)
		(attr
			(teardrop
				(type padvia)
			)
		)
		(connect_pads yes
			(clearance 0)
		)
		(min_thickness 0.0254)
		(filled_areas_thickness no)
		(fill yes
			(thermal_gap 0.5)
			(thermal_bridge_width 0.5)
			(island_removal_mode 1)
			(island_area_min 10)
		)
		(polygon
			(pts
				(xy 257.520717 162.762641) (xy 257.567163 162.815916) (xy 257.594186 162.862456) (xy 257.617075 162.964452)
				(xy 257.629323 163.043895) (xy 257.850707 163.000707) (xy 257.893895 162.779323) (xy 257.814452 162.767075)
				(xy 257.716294 162.745808) (xy 257.668012 162.718673) (xy 257.612641 162.670717)
			)
		)
	)
	(zone
		(net 541)
		(net_name "Net-(Q9-B)")
		(layer "In2.Cu")
		(name "$teardrop_padvia$")
		(hatch none 0.1)
		(priority 30051)
		(attr
			(teardrop
				(type padvia)
			)
		)
		(connect_pads yes
			(clearance 0)
		)
		(min_thickness 0.0254)
		(filled_areas_thickness no)
		(fill yes
			(thermal_gap 0.5)
			(thermal_bridge_width 0.5)
			(island_removal_mode 1)
			(island_area_min 10)
		)
		(polygon
			(pts
				(xy 256.1875 84.059323) (xy 256.182682 84.128763) (xy 256.16896 84.180087) (xy 256.122245 84.255628)
				(xy 256.112702 84.267768) (xy 256.062919 84.334997) (xy 256.25 84.461) (xy 256.437081 84.334997)
				(xy 256.387299 84.267769) (xy 256.332894 84.184603) (xy 256.31781 84.131748) (xy 256.3125 84.059323)
			)
		)
	)
	(zone
		(net 73)
		(net_name "+3V3_AON")
		(layer "In3.Cu")
		(hatch edge 0.5)
		(priority 39)
		(connect_pads
			(clearance 0.2)
		)
		(min_thickness 0.25)
		(filled_areas_thickness no)
		(fill yes
			(thermal_gap 0.2)
			(thermal_bridge_width 0.5)
			(smoothing fillet)
			(radius 0.2)
		)
		(polygon
			(pts
				(xy 259.425 126.385) (xy 242.5 126.385) (xy 242.5 133.135) (xy 259.425 133.135)
			)
		)
	)
	(zone
		(net 127)
		(net_name "/USB-C console/FTDI_LED_RX")
		(layer "In3.Cu")
		(name "$teardrop_padvia$")
		(hatch none 0.1)
		(priority 30002)
		(attr
			(teardrop
				(type padvia)
			)
		)
		(connect_pads yes
			(clearance 0)
		)
		(min_thickness 0.0254)
		(filled_areas_thickness no)
		(fill yes
			(thermal_gap 0.5)
			(thermal_bridge_width 0.5)
			(island_removal_mode 1)
			(island_area_min 10)
		)
		(polygon
			(pts
				(xy 113.627515 74.199127) (xy 113.581819 74.146618) (xy 113.555231 74.100623) (xy 113.534847 74.014175)
				(xy 113.533011 73.99884) (xy 113.520677 73.916105) (xy 113.299293 73.959293) (xy 113.256105 74.180677)
				(xy 113.33884 74.193011) (xy 113.436119 74.213349) (xy 113.484159 74.240057) (xy 113.539127 74.287515)
			)
		)
	)
	(zone
		(net 969)
		(net_name "/M.2 key M #1/M2_3V3")
		(layer "In3.Cu")
		(hatch edge 0.5)
		(priority 8)
		(connect_pads
			(clearance 0.15)
		)
		(min_thickness 0.25)
		(filled_areas_thickness no)
		(fill yes
			(thermal_gap 0.5)
			(thermal_bridge_width 0.5)
		)
		(polygon
			(pts
				(xy 177.6 111.41) (xy 179.95 111.41) (xy 179.95 91.31) (xy 177.6 91.31)
			)
		)
	)
	(zone
		(net 61)
		(net_name "/OCuLink/5V_CONN0")
		(layer "In3.Cu")
		(hatch edge 0.5)
		(priority 8)
		(connect_pads
			(clearance 0.15)
		)
		(min_thickness 0.15)
		(filled_areas_thickness no)
		(fill yes
			(thermal_gap 0.5)
			(thermal_bridge_width 0.5)
			(smoothing fillet)
			(radius 0.2)
		)
		(polygon
			(pts
				(xy 104.25 168.36) (xy 104.25 152.585) (xy 100.25 152.585) (xy 100.25 168.36)
			)
		)
	)
	(zone
		(net 144)
		(net_name "VCC")
		(layer "In3.Cu")
		(hatch edge 0.5)
		(priority 9)
		(connect_pads
			(clearance 0.15)
		)
		(min_thickness 0.25)
		(filled_areas_thickness no)
		(fill yes
			(thermal_gap 0.2)
			(thermal_bridge_width 0.5)
			(smoothing fillet)
			(radius 0.5)
		)
		(polygon
			(pts
				(xy 300.35 171.76) (xy 321.919818 171.76) (xy 321.932241 147.912241) (xy 306.85 147.91) (xy 306.85 154.01)
				(xy 300.35 160.51)
			)
		)
	)
	(zone
		(net 1)
		(net_name "GND")
		(layer "In3.Cu")
		(hatch edge 0.5)
		(priority 29)
		(connect_pads
			(clearance 0.15)
		)
		(min_thickness 0.25)
		(filled_areas_thickness no)
		(fill yes
			(thermal_gap 0.5)
			(thermal_bridge_width 0.5)
		)
		(polygon
			(pts
				(xy 164.4 151.8) (xy 164.4 171.75003) (xy 224 171.76003) (xy 224 164.2) (xy 216.2 164.2) (xy 216.2 151.8)
			)
		)
	)
	(zone
		(net 2)
		(net_name "+3V3")
		(layer "In3.Cu")
		(hatch edge 0.5)
		(priority 7)
		(connect_pads yes
			(clearance 0.15)
		)
		(min_thickness 0.15)
		(filled_areas_thickness no)
		(fill yes
			(thermal_gap 0.2)
			(thermal_bridge_width 0.5)
			(smoothing fillet)
			(radius 0.2)
		)
		(polygon
			(pts
				(xy 319.95 68.21466) (xy 319.95 91.725) (xy 308.38 91.725) (xy 308.38 94.86) (xy 299.368843 94.866157)
				(xy 299.375 98.71) (xy 303.45 98.71) (xy 303.45 112.11) (xy 299.45 112.11) (xy 299.45 112.01) (xy 287.75 123.71)
				(xy 272.8 123.71) (xy 257.65 138.86) (xy 194.85 138.88) (xy 193.58 140.16) (xy 192.98 140.16) (xy 191.85 138.86)
				(xy 173.196225 138.86) (xy 162.9 128.405942) (xy 130.571656 128.242756) (xy 123.35 135.291438) (xy 123.35 149.46)
				(xy 143.8 149.46) (xy 146.2 151.86) (xy 164 151.86) (xy 164 171.41) (xy 104.55 171.41) (xy 104.55 153.96)
				(xy 106.4 153.96) (xy 106.4 131.876988) (xy 123.4 114.971694) (xy 123.4 94.71) (xy 120.4 91.71)
				(xy 120.4 74.51) (xy 126.715923 68.21)
			)
		)
	)
	(zone
		(net 77)
		(net_name "+5V_AON")
		(layer "In3.Cu")
		(hatch edge 0.5)
		(priority 42)
		(connect_pads yes
			(clearance 0.15)
		)
		(min_thickness 0.25)
		(filled_areas_thickness no)
		(fill yes
			(thermal_gap 0.5)
			(thermal_bridge_width 0.5)
		)
		(polygon
			(pts
				(xy 216.4 164) (xy 224 164) (xy 224 155.6) (xy 283 155.6) (xy 298.8 139.8) (xy 308.4 139.8) (xy 308.4 95)
				(xy 299.4 95) (xy 299.4 98.6) (xy 303.6 98.6) (xy 303.6 137.2) (xy 299.4 137.2) (xy 297.6 135.4)
				(xy 283.8 135.4) (xy 267.4 151.8) (xy 216.4 151.8)
			)
		)
	)
	(zone
		(net 2)
		(net_name "+3V3")
		(layer "In3.Cu")
		(name "$teardrop_padvia$")
		(hatch none 0.1)
		(priority 30000)
		(attr
			(teardrop
				(type padvia)
			)
		)
		(connect_pads yes
			(clearance 0)
		)
		(min_thickness 0.0254)
		(filled_areas_thickness no)
		(fill yes
			(thermal_gap 0.5)
			(thermal_bridge_width 0.5)
			(island_removal_mode 1)
			(island_area_min 10)
		)
		(polygon
			(pts
				(xy 124.399323 138.79) (xy 124.5569 138.796932) (xy 124.670434 138.825456) (xy 124.712222 138.8425)
				(xy 124.801 138.64) (xy 124.712222 138.4375) (xy 124.616177 138.471883) (xy 124.514296 138.487101)
				(xy 124.399323 138.49)
			)
		)
	)
	(zone
		(net 62)
		(net_name "+12V_AON")
		(layer "In3.Cu")
		(hatch edge 0.5)
		(priority 12)
		(connect_pads
			(clearance 0.15)
		)
		(min_thickness 0.25)
		(filled_areas_thickness no)
		(fill yes
			(thermal_gap 0.2)
			(thermal_bridge_width 0.5)
			(smoothing fillet)
			(radius 0.5)
		)
		(polygon
			(pts
				(xy 319.95 147.6) (xy 319.95 91.91) (xy 308.51 91.91) (xy 308.468022 147.6)
			)
		)
	)
	(zone
		(net 78)
		(net_name "+1V8")
		(layer "In3.Cu")
		(hatch edge 0.5)
		(priority 2)
		(connect_pads
			(clearance 0.15)
		)
		(min_thickness 0.25)
		(filled_areas_thickness no)
		(fill yes
			(thermal_gap 0.2)
			(thermal_bridge_width 0.5)
			(smoothing fillet)
			(radius 0.5)
		)
		(polygon
			(pts
				(xy 303.3 137.06) (xy 299.5 137.06) (xy 297.7 135.26) (xy 283.65 135.26) (xy 267.25 151.66) (xy 182.35 151.66)
				(xy 182.1 151.41) (xy 146.3 151.41) (xy 143.95 149.06) (xy 123.75 149.06) (xy 123.75 133.61) (xy 156.75 133.61)
				(xy 167.85 144.71) (xy 263.75 144.71) (xy 276.5 131.96) (xy 303.3 131.96)
			)
		)
	)
	(zone
		(net 65)
		(net_name "+12V")
		(layer "In3.Cu")
		(hatch edge 0.5)
		(priority 41)
		(connect_pads yes
			(clearance 0.15)
		)
		(min_thickness 0.25)
		(filled_areas_thickness no)
		(fill yes
			(thermal_gap 0.5)
			(thermal_bridge_width 0.5)
		)
		(polygon
			(pts
				(xy 224.2 155.8) (xy 283.2 155.8) (xy 299 140) (xy 308.4 140) (xy 308.4 147.6) (xy 306.6 147.6)
				(xy 306.6 153.8) (xy 300 160.4) (xy 300 171.76) (xy 224.2 171.76)
			)
		)
	)
	(zone
		(net 52)
		(net_name "+5V")
		(layer "In3.Cu")
		(hatch edge 0.5)
		(priority 7)
		(connect_pads yes
			(clearance 0.15)
		)
		(min_thickness 0.15)
		(filled_areas_thickness no)
		(fill yes
			(thermal_gap 0.2)
			(thermal_bridge_width 0.5)
			(smoothing fillet)
			(radius 0.2)
		)
		(polygon
			(pts
				(xy 294.75 101.41) (xy 294.75 94.86) (xy 268.1 68.21) (xy 95.85 68.21) (xy 94.9 69.16) (xy 94.9 153.735)
				(xy 106.1 153.735) (xy 106.1 131.71) (xy 123.15 114.66) (xy 123.15 94.86) (xy 120 91.71) (xy 120 74.25)
				(xy 120.99 73.26) (xy 147.84 73.26) (xy 151.19 76.61) (xy 266.65 76.61) (xy 291.45 101.41)
			)
		)
	)
	(zone
		(net 74)
		(net_name "+1V0")
		(layer "In3.Cu")
		(hatch edge 0.5)
		(priority 23)
		(connect_pads
			(clearance 0.15)
		)
		(min_thickness 0.195)
		(filled_areas_thickness no)
		(fill yes
			(thermal_gap 0.2)
			(thermal_bridge_width 0.5)
			(smoothing fillet)
			(radius 0.5)
		)
		(polygon
			(pts
				(xy 303.35 131.36) (xy 276.25 131.36) (xy 263.15 144.46) (xy 167.95 144.46) (xy 156.95 133.46) (xy 154.01 133.46)
				(xy 154.01 134.61) (xy 155.01 135.61) (xy 155.01 139.11) (xy 151.91 142.21) (xy 150.96 142.21) (xy 147.11 138.36)
				(xy 147.11 135.81) (xy 147.86 135.06) (xy 147.86 133.46) (xy 135.85 133.46) (xy 135.85 134.61) (xy 136.85 135.61)
				(xy 136.85 139.11) (xy 133.75 142.21) (xy 132.8 142.21) (xy 128.95 138.36) (xy 128.95 135.81) (xy 129.7 135.06)
				(xy 129.7 132.36) (xy 129.7 129.71) (xy 130.85 128.56) (xy 162.15 128.56) (xy 172.7 139.11) (xy 191.76 139.11)
				(xy 192.87 140.36) (xy 193.71 140.36) (xy 194.95 139.11) (xy 258.25 139.11) (xy 272.85 124.51) (xy 289.15 124.51)
				(xy 299.2 114.46) (xy 303.35 114.46)
			)
		)
	)
	(zone
		(net 127)
		(net_name "/USB-C console/FTDI_LED_RX")
		(layer "In3.Cu")
		(name "$teardrop_padvia$")
		(hatch none 0.1)
		(priority 30001)
		(attr
			(teardrop
				(type padvia)
			)
		)
		(connect_pads yes
			(clearance 0)
		)
		(min_thickness 0.0254)
		(filled_areas_thickness no)
		(fill yes
			(thermal_gap 0.5)
			(thermal_bridge_width 0.5)
			(island_removal_mode 1)
			(island_area_min 10)
		)
		(polygon
			(pts
				(xy 114.649323 78.9225) (xy 114.718764 78.927318) (xy 114.770088 78.94104) (xy 114.845629 78.987755)
				(xy 114.857769 78.997299) (xy 114.924997 79.047081) (xy 115.051 78.86) (xy 114.924997 78.672919)
				(xy 114.857768 78.722702) (xy 114.774602 78.777106) (xy 114.721748 78.79219) (xy 114.649323 78.7975)
			)
		)
	)
	(zone
		(net 158)
		(net_name "/2xUSB3.0+RJ45/USBSS_1.RX-")
		(layer "In5.Cu")
		(name "$teardrop_padvia$")
		(hatch none 0.1)
		(priority 30153)
		(attr
			(teardrop
				(type padvia)
			)
		)
		(connect_pads yes
			(clearance 0)
		)
		(min_thickness 0.0254)
		(filled_areas_thickness no)
		(fill yes
			(thermal_gap 0.5)
			(thermal_bridge_width 0.5)
			(island_removal_mode 1)
			(island_area_min 10)
		)
		(polygon
			(pts
				(xy 180.014 157.998916) (xy 180.009242 158.040486) (xy 179.995936 158.070544) (xy 179.951424 158.106646)
				(xy 179.909043 158.124196) (xy 179.827497 158.162919) (xy 179.9525 158.351) (xy 180.173177 158.306105)
				(xy 180.162675 158.229686) (xy 180.163114 158.169066) (xy 180.166226 158.13169) (xy 180.173 157.998916)
			)
		)
	)
	(zone
		(net 325)
		(net_name "/Com Express 7 Interfaces/PCIe_{B2Ax4}.TX0-")
		(layer "In5.Cu")
		(name "$teardrop_padvia$")
		(hatch none 0.1)
		(priority 30099)
		(attr
			(teardrop
				(type padvia)
			)
		)
		(connect_pads yes
			(clearance 0)
		)
		(min_thickness 0.0254)
		(filled_areas_thickness no)
		(fill yes
			(thermal_gap 0.5)
			(thermal_bridge_width 0.5)
			(island_removal_mode 1)
			(island_area_min 10)
		)
		(polygon
			(pts
				(xy 228.576 143.756084) (xy 228.580759 143.713152) (xy 228.594072 143.681738) (xy 228.638959 143.642447)
				(xy 228.678471 143.623424) (xy 228.748003 143.587081) (xy 228.623 143.399) (xy 228.402323 143.40947)
				(xy 228.401698 143.589597) (xy 228.398 143.756084)
			)
		)
	)
	(zone
		(net 756)
		(net_name "Net-(U45A-LS_OK_{OUT_A})")
		(layer "In5.Cu")
		(name "$teardrop_padvia$")
		(hatch none 0.1)
		(priority 30127)
		(attr
			(teardrop
				(type padvia)
			)
		)
		(connect_pads yes
			(clearance 0)
		)
		(min_thickness 0.0254)
		(filled_areas_thickness no)
		(fill yes
			(thermal_gap 0.5)
			(thermal_bridge_width 0.5)
			(island_removal_mode 1)
			(island_area_min 10)
		)
		(polygon
			(pts
				(xy 134.954985 139.628373) (xy 134.998576 139.678586) (xy 135.025537 139.723616) (xy 135.052715 139.821806)
				(xy 135.064424 139.879432) (xy 135.087012 139.946601) (xy 135.290707 139.860707) (xy 135.333895 139.639323)
				(xy 135.239643 139.627421) (xy 135.144708 139.610844) (xy 135.097162 139.585747) (xy 135.043373 139.539985)
			)
		)
	)
	(zone
		(net 323)
		(net_name "/Com Express 7 Interfaces/SDIO.DAT2")
		(layer "In5.Cu")
		(name "$teardrop_padvia$")
		(hatch none 0.1)
		(priority 30037)
		(attr
			(teardrop
				(type padvia)
			)
		)
		(connect_pads yes
			(clearance 0)
		)
		(min_thickness 0.0254)
		(filled_areas_thickness no)
		(fill yes
			(thermal_gap 0.5)
			(thermal_bridge_width 0.5)
			(island_removal_mode 1)
			(island_area_min 10)
		)
		(polygon
			(pts
				(xy 113.760677 138.326852) (xy 113.692314 138.322161) (xy 113.64003 138.309326) (xy 113.550652 138.260409)
				(xy 113.447778 138.201852) (xy 113.359 138.404352) (xy 113.447778 138.606852) (xy 113.550651 138.548295)
				(xy 113.634447 138.501419) (xy 113.688713 138.487113) (xy 113.760677 138.481852)
			)
		)
	)
	(zone
		(net 264)
		(net_name "/Com Express 7 Interfaces/PCIe_{B2Bx4}.RX0+")
		(layer "In5.Cu")
		(name "$teardrop_padvia$")
		(hatch none 0.1)
		(priority 30056)
		(attr
			(teardrop
				(type padvia)
			)
		)
		(connect_pads yes
			(clearance 0)
		)
		(min_thickness 0.0254)
		(filled_areas_thickness no)
		(fill yes
			(thermal_gap 0.5)
			(thermal_bridge_width 0.5)
			(island_removal_mode 1)
			(island_area_min 10)
		)
		(polygon
			(pts
				(xy 194.999 161.139416) (xy 194.994259 161.184146) (xy 194.981069 161.21761) (xy 194.936306 161.261123)
				(xy 194.89281 161.284187) (xy 194.843872 161.310164) (xy 194.79681 161.347605) (xy 194.9565 161.501)
				(xy 195.177177 161.456105) (xy 195.166552 161.379042) (xy 195.166818 161.317339) (xy 195.170104 161.276751)
				(xy 195.177 161.139416)
			)
		)
	)
	(zone
		(net 736)
		(net_name "Net-(U43A-LS_OK_{OUT_A})")
		(layer "In5.Cu")
		(name "$teardrop_padvia$")
		(hatch none 0.1)
		(priority 30259)
		(attr
			(teardrop
				(type padvia)
			)
		)
		(connect_pads yes
			(clearance 0)
		)
		(min_thickness 0.0254)
		(filled_areas_thickness no)
		(fill yes
			(thermal_gap 0.5)
			(thermal_bridge_width 0.5)
			(island_removal_mode 1)
			(island_area_min 10)
		)
		(polygon
			(pts
				(xy 153.122485 139.620873) (xy 153.168181 139.673382) (xy 153.194768 139.719376) (xy 153.215152 139.805825)
				(xy 153.216988 139.821158) (xy 153.229323 139.903895) (xy 153.450707 139.860707) (xy 153.493895 139.639323)
				(xy 153.411158 139.626988) (xy 153.31388 139.606651) (xy 153.26584 139.579943) (xy 153.210873 139.532485)
			)
		)
	)
	(zone
		(net 738)
		(net_name "Net-(U43B-LS_OK_{IN_B})")
		(layer "In5.Cu")
		(name "$teardrop_padvia$")
		(hatch none 0.1)
		(priority 30291)
		(attr
			(teardrop
				(type padvia)
			)
		)
		(connect_pads yes
			(clearance 0)
		)
		(min_thickness 0.0254)
		(filled_areas_thickness no)
		(fill yes
			(thermal_gap 0.5)
			(thermal_bridge_width 0.5)
			(island_removal_mode 1)
			(island_area_min 10)
		)
		(polygon
			(pts
				(xy 146.019972 138.86836) (xy 146.077349 138.919257) (xy 146.126778 138.951616) (xy 146.197691 138.983136)
				(xy 146.255953 139.007672) (xy 146.324997 139.047081) (xy 146.450707 138.860707) (xy 146.324997 138.672919)
				(xy 146.252514 138.741809) (xy 146.218538 138.778033) (xy 146.184828 138.80236) (xy 146.148922 138.805951)
				(xy 146.10836 138.779972)
			)
		)
	)
	(zone
		(net 944)
		(net_name "/GPIO expander/GPIOEX2")
		(layer "In5.Cu")
		(name "$teardrop_padvia$")
		(hatch none 0.1)
		(priority 30285)
		(attr
			(teardrop
				(type padvia)
			)
		)
		(connect_pads yes
			(clearance 0)
		)
		(min_thickness 0.0254)
		(filled_areas_thickness no)
		(fill yes
			(thermal_gap 0.5)
			(thermal_bridge_width 0.5)
			(island_removal_mode 1)
			(island_area_min 10)
		)
		(polygon
			(pts
				(xy 99.147515 79.049127) (xy 99.101819 78.996618) (xy 99.075231 78.950623) (xy 99.054847 78.864175)
				(xy 99.053011 78.84884) (xy 99.040677 78.766105) (xy 98.819293 78.809293) (xy 98.776105 79.030677)
				(xy 98.85884 79.043011) (xy 98.956119 79.063349) (xy 99.004159 79.090057) (xy 99.059127 79.137515)
			)
		)
	)
	(zone
		(net 259)
		(net_name "/Com Express 7 Interfaces/PCIe_{B2Bx4}.TX1+")
		(layer "In5.Cu")
		(name "$teardrop_padvia$")
		(hatch none 0.1)
		(priority 30078)
		(attr
			(teardrop
				(type padvia)
			)
		)
		(connect_pads yes
			(clearance 0)
		)
		(min_thickness 0.0254)
		(filled_areas_thickness no)
		(fill yes
			(thermal_gap 0.5)
			(thermal_bridge_width 0.5)
			(island_removal_mode 1)
			(island_area_min 10)
		)
		(polygon
			(pts
				(xy 173.939416 101.512) (xy 174.076751 101.505104) (xy 174.157939 101.500724) (xy 174.256105 101.512177)
				(xy 174.301 101.2915) (xy 174.147605 101.13181) (xy 174.098527 101.199306) (xy 174.084187 101.22781)
				(xy 174.062888 101.268429) (xy 174.036197 101.302262) (xy 173.997308 101.325417) (xy 173.939416 101.334)
			)
		)
	)
	(zone
		(net 239)
		(net_name "/Com Express 7 Interfaces/PCIe_{B2Bx4}.RX3+")
		(layer "In5.Cu")
		(name "$teardrop_padvia$")
		(hatch none 0.1)
		(priority 30062)
		(attr
			(teardrop
				(type padvia)
			)
		)
		(connect_pads yes
			(clearance 0)
		)
		(min_thickness 0.0254)
		(filled_areas_thickness no)
		(fill yes
			(thermal_gap 0.5)
			(thermal_bridge_width 0.5)
			(island_removal_mode 1)
			(island_area_min 10)
		)
		(polygon
			(pts
				(xy 191.560584 159.324) (xy 191.515854 159.319259) (xy 191.482389 159.306069) (xy 191.438876 159.261306)
				(xy 191.415811 159.217809) (xy 191.389834 159.168871) (xy 191.352394 159.12181) (xy 191.199 159.2815)
				(xy 191.243895 159.502177) (xy 191.320958 159.491552) (xy 191.38266 159.491818) (xy 191.423248 159.495104)
				(xy 191.560584 159.502)
			)
		)
	)
	(zone
		(net 531)
		(net_name "/Com Express 7 Interfaces/SD_CD")
		(layer "In5.Cu")
		(name "$teardrop_padvia$")
		(hatch none 0.1)
		(priority 30264)
		(attr
			(teardrop
				(type padvia)
			)
		)
		(connect_pads yes
			(clearance 0)
		)
		(min_thickness 0.0254)
		(filled_areas_thickness no)
		(fill yes
			(thermal_gap 0.5)
			(thermal_bridge_width 0.5)
			(island_removal_mode 1)
			(island_area_min 10)
		)
		(polygon
			(pts
				(xy 138.022485 151.760873) (xy 138.068181 151.813382) (xy 138.094768 151.859376) (xy 138.115152 151.945825)
				(xy 138.116988 151.961158) (xy 138.129323 152.043895) (xy 138.350707 152.000707) (xy 138.393895 151.779323)
				(xy 138.311158 151.766988) (xy 138.21388 151.746651) (xy 138.16584 151.719943) (xy 138.110873 151.672485)
			)
		)
	)
	(zone
		(net 74)
		(net_name "+1V0")
		(layer "In5.Cu")
		(name "$teardrop_padvia$")
		(hatch none 0.1)
		(priority 30032)
		(attr
			(teardrop
				(type padvia)
			)
		)
		(connect_pads yes
			(clearance 0)
		)
		(min_thickness 0.0254)
		(filled_areas_thickness no)
		(fill yes
			(thermal_gap 0.5)
			(thermal_bridge_width 0.5)
			(island_removal_mode 1)
			(island_area_min 10)
		)
		(polygon
			(pts
				(xy 251.830968 88.237389) (xy 251.882727 88.295813) (xy 251.91511 88.346563) (xy 251.949708 88.440701)
				(xy 251.979741 88.531119) (xy 252.185706 88.450706) (xy 252.266119 88.244741) (xy 252.175701 88.214708)
				(xy 252.079887 88.179236) (xy 252.029884 88.14702) (xy 251.972389 88.095968)
			)
		)
	)
	(zone
		(net 2)
		(net_name "+3V3")
		(layer "In5.Cu")
		(name "$teardrop_padvia$")
		(hatch none 0.1)
		(priority 30007)
		(attr
			(teardrop
				(type padvia)
			)
		)
		(connect_pads yes
			(clearance 0)
		)
		(min_thickness 0.0254)
		(filled_areas_thickness no)
		(fill yes
			(thermal_gap 0.5)
			(thermal_bridge_width 0.5)
			(island_removal_mode 1)
			(island_area_min 10)
		)
		(polygon
			(pts
				(xy 143.655304 149.592565) (xy 143.629282 149.611913) (xy 143.604365 149.618398) (xy 143.557211 149.603608)
				(xy 143.514752 149.572033) (xy 143.446264 149.527831) (xy 143.376293 149.738707) (xy 143.488665 149.930605)
				(xy 143.56923 149.902885) (xy 143.635469 149.896836) (xy 143.74729 149.880618) (xy 143.806081 149.853836)
				(xy 143.867435 149.804696)
			)
		)
	)
	(zone
		(net 44)
		(net_name "/2xUSB3.0+RJ45/USBSS_1.TX+")
		(layer "In5.Cu")
		(name "$teardrop_padvia$")
		(hatch none 0.1)
		(priority 30140)
		(attr
			(teardrop
				(type padvia)
			)
		)
		(connect_pads yes
			(clearance 0)
		)
		(min_thickness 0.0254)
		(filled_areas_thickness no)
		(fill yes
			(thermal_gap 0.5)
			(thermal_bridge_width 0.5)
			(island_removal_mode 1)
			(island_area_min 10)
		)
		(polygon
			(pts
				(xy 180.377 149.198916) (xy 180.383774 149.33169) (xy 180.388077 149.410162) (xy 180.376823 149.506105)
				(xy 180.5975 149.551) (xy 180.722503 149.362919) (xy 180.640957 149.324196) (xy 180.600152 149.307418)
				(xy 180.566785 149.285433) (xy 180.544264 149.251509) (xy 180.536 149.198916)
			)
		)
	)
	(zone
		(net 894)
		(net_name "Net-(J2B-MOD_{ABS})")
		(layer "In5.Cu")
		(name "$teardrop_padvia$")
		(hatch none 0.1)
		(priority 30005)
		(attr
			(teardrop
				(type padvia)
			)
		)
		(connect_pads yes
			(clearance 0)
		)
		(min_thickness 0.0254)
		(filled_areas_thickness no)
		(fill yes
			(thermal_gap 0.5)
			(thermal_bridge_width 0.5)
			(island_removal_mode 1)
			(island_area_min 10)
		)
		(polygon
			(pts
				(xy 143.361388 162.383) (xy 143.327603 162.342368) (xy 143.309295 162.304414) (xy 143.304475 162.272106)
				(xy 143.309242 162.241098) (xy 143.347131 162.174836) (xy 143.429265 162.090363) (xy 143.496711 162.02379)
				(xy 143.557532 161.948895) (xy 143.199293 161.709293) (xy 142.847243 161.95367) (xy 142.878043 161.998319)
				(xy 143.045098 162.228182) (xy 143.273 162.471388)
			)
		)
	)
	(zone
		(net 745)
		(net_name "/2xSFP+/KR to SFI #2/TCK")
		(layer "In5.Cu")
		(name "$teardrop_padvia$")
		(hatch none 0.1)
		(priority 30190)
		(attr
			(teardrop
				(type padvia)
			)
		)
		(connect_pads yes
			(clearance 0)
		)
		(min_thickness 0.0254)
		(filled_areas_thickness no)
		(fill yes
			(thermal_gap 0.5)
			(thermal_bridge_width 0.5)
			(island_removal_mode 1)
			(island_area_min 10)
		)
		(polygon
			(pts
				(xy 134.3525 130.910677) (xy 134.357318 130.841236) (xy 134.37104 130.789912) (xy 134.417755 130.71437)
				(xy 134.427299 130.702229) (xy 134.477081 130.635003) (xy 134.29 130.509) (xy 134.102919 130.635003)
				(xy 134.152701 130.702231) (xy 134.207106 130.785397) (xy 134.22219 130.838251) (xy 134.2275 130.910677)
			)
		)
	)
	(zone
		(net 670)
		(net_name "/2xSFP+/KR to SFI #2/MDIO")
		(layer "In5.Cu")
		(name "$teardrop_padvia$")
		(hatch none 0.1)
		(priority 30272)
		(attr
			(teardrop
				(type padvia)
			)
		)
		(connect_pads yes
			(clearance 0)
		)
		(min_thickness 0.0254)
		(filled_areas_thickness no)
		(fill yes
			(thermal_gap 0.5)
			(thermal_bridge_width 0.5)
			(island_removal_mode 1)
			(island_area_min 10)
		)
		(polygon
			(pts
				(xy 130.050873 138.187515) (xy 130.103382 138.141819) (xy 130.149376 138.115231) (xy 130.235824 138.094847)
				(xy 130.25116 138.093011) (xy 130.333895 138.080677) (xy 130.290707 137.859293) (xy 130.069323 137.816105)
				(xy 130.056988 137.898841) (xy 130.036651 137.996119) (xy 130.009943 138.044159) (xy 129.962485 138.099127)
			)
		)
	)
	(zone
		(net 323)
		(net_name "/Com Express 7 Interfaces/SDIO.DAT2")
		(layer "In5.Cu")
		(name "$teardrop_padvia$")
		(hatch none 0.1)
		(priority 30043)
		(attr
			(teardrop
				(type padvia)
			)
		)
		(connect_pads yes
			(clearance 0)
		)
		(min_thickness 0.0254)
		(filled_areas_thickness no)
		(fill yes
			(thermal_gap 0.5)
			(thermal_bridge_width 0.5)
			(island_removal_mode 1)
			(island_area_min 10)
		)
		(polygon
			(pts
				(xy 164.986879 163.47148) (xy 165.031901 163.523136) (xy 165.059795 163.569182) (xy 165.088406 163.666971)
				(xy 165.119742 163.78112) (xy 165.325707 163.700707) (xy 165.40612 163.494742) (xy 165.291971 163.463406)
				(xy 165.199573 163.4373) (xy 165.151086 163.409044) (xy 165.09648 163.361879)
			)
		)
	)
	(zone
		(net 206)
		(net_name "/Backplane/USB.D+")
		(layer "In5.Cu")
		(name "$teardrop_padvia$")
		(hatch none 0.1)
		(priority 30139)
		(attr
			(teardrop
				(type padvia)
			)
		)
		(connect_pads yes
			(clearance 0)
		)
		(min_thickness 0.0254)
		(filled_areas_thickness no)
		(fill yes
			(thermal_gap 0.5)
			(thermal_bridge_width 0.5)
			(island_removal_mode 1)
			(island_area_min 10)
		)
		(polygon
			(pts
				(xy 198.377 170.148916) (xy 198.383774 170.28169) (xy 198.388077 170.360162) (xy 198.376823 170.456105)
				(xy 198.5975 170.501) (xy 198.722503 170.312919) (xy 198.640957 170.274196) (xy 198.600152 170.257418)
				(xy 198.566785 170.235433) (xy 198.544264 170.201509) (xy 198.536 170.148916)
			)
		)
	)
	(zone
		(net 206)
		(net_name "/Backplane/USB.D+")
		(layer "In5.Cu")
		(name "$teardrop_padvia$")
		(hatch none 0.1)
		(priority 30117)
		(attr
			(teardrop
				(type padvia)
			)
		)
		(connect_pads yes
			(clearance 0)
		)
		(min_thickness 0.0254)
		(filled_areas_thickness no)
		(fill yes
			(thermal_gap 0.5)
			(thermal_bridge_width 0.5)
			(island_removal_mode 1)
			(island_area_min 10)
		)
		(polygon
			(pts
				(xy 213.011 149.446584) (xy 213.015756 149.405895) (xy 213.029046 149.376665) (xy 213.073378 149.342239)
				(xy 213.116411 149.325787) (xy 213.202003 149.287081) (xy 213.077 149.099) (xy 212.856323 149.101749)
				(xy 212.854515 149.265835) (xy 212.852 149.446584)
			)
		)
	)
	(zone
		(net 160)
		(net_name "/2xUSB3.0+RJ45/USBSS_2.RX-")
		(layer "In5.Cu")
		(name "$teardrop_padvia$")
		(hatch none 0.1)
		(priority 30144)
		(attr
			(teardrop
				(type padvia)
			)
		)
		(connect_pads yes
			(clearance 0)
		)
		(min_thickness 0.0254)
		(filled_areas_thickness no)
		(fill yes
			(thermal_gap 0.5)
			(thermal_bridge_width 0.5)
			(island_removal_mode 1)
			(island_area_min 10)
		)
		(polygon
			(pts
				(xy 181.673 158.676084) (xy 181.666226 158.543309) (xy 181.661923 158.464838) (xy 181.673177 158.368895)
				(xy 181.4525 158.324) (xy 181.327497 158.512081) (xy 181.409042 158.550803) (xy 181.449848 158.567581)
				(xy 181.483215 158.589567) (xy 181.505736 158.62349) (xy 181.514 158.676084)
			)
		)
	)
	(zone
		(net 62)
		(net_name "+12V_AON")
		(layer "In5.Cu")
		(name "$teardrop_padvia$")
		(hatch none 0.1)
		(priority 30019)
		(attr
			(teardrop
				(type padvia)
			)
		)
		(connect_pads yes
			(clearance 0)
		)
		(min_thickness 0.0254)
		(filled_areas_thickness no)
		(fill yes
			(thermal_gap 0.5)
			(thermal_bridge_width 0.5)
			(island_removal_mode 1)
			(island_area_min 10)
		)
		(polygon
			(pts
				(xy 186.60861 73.701486) (xy 186.603897 73.779397) (xy 186.59091 73.838181) (xy 186.548809 73.929211)
				(xy 186.50611 74.014384) (xy 186.70861 74.103163) (xy 186.91111 74.014384) (xy 186.868411 73.929213)
				(xy 186.825743 73.83638) (xy 186.813166 73.778241) (xy 186.80861 73.701486)
			)
		)
	)
	(zone
		(net 73)
		(net_name "+3V3_AON")
		(layer "In5.Cu")
		(name "$teardrop_padvia$")
		(hatch none 0.1)
		(priority 30031)
		(attr
			(teardrop
				(type padvia)
			)
		)
		(connect_pads yes
			(clearance 0)
		)
		(min_thickness 0.0254)
		(filled_areas_thickness no)
		(fill yes
			(thermal_gap 0.5)
			(thermal_bridge_width 0.5)
			(island_removal_mode 1)
			(island_area_min 10)
		)
		(polygon
			(pts
				(xy 221.145969 82.44739) (xy 221.197728 82.505814) (xy 221.230111 82.556564) (xy 221.264709 82.650702)
				(xy 221.294742 82.74112) (xy 221.500707 82.660707) (xy 221.58112 82.454742) (xy 221.490702 82.424709)
				(xy 221.394888 82.389237) (xy 221.344885 82.357021) (xy 221.28739 82.305969)
			)
		)
	)
	(zone
		(net 331)
		(net_name "/Com Express 7 Interfaces/PCIe_{B2Ax4}.TX3-")
		(layer "In5.Cu")
		(name "$teardrop_padvia$")
		(hatch none 0.1)
		(priority 30102)
		(attr
			(teardrop
				(type padvia)
			)
		)
		(connect_pads yes
			(clearance 0)
		)
		(min_thickness 0.0254)
		(filled_areas_thickness no)
		(fill yes
			(thermal_gap 0.5)
			(thermal_bridge_width 0.5)
			(island_removal_mode 1)
			(island_area_min 10)
		)
		(polygon
			(pts
				(xy 232.543916 148.702) (xy 232.7104 148.698302) (xy 232.89053 148.697677) (xy 232.901 148.477)
				(xy 232.712919 148.351997) (xy 232.676575 148.42153) (xy 232.657298 148.461496) (xy 232.633213 148.494058)
				(xy 232.597643 148.515974) (xy 232.543916 148.524)
			)
		)
	)
	(zone
		(net 759)
		(net_name "Net-(U45B-LS_OK_{OUT_B})")
		(layer "In5.Cu")
		(name "$teardrop_padvia$")
		(hatch none 0.1)
		(priority 30207)
		(attr
			(teardrop
				(type padvia)
			)
		)
		(connect_pads yes
			(clearance 0)
		)
		(min_thickness 0.0254)
		(filled_areas_thickness no)
		(fill yes
			(thermal_gap 0.5)
			(thermal_bridge_width 0.5)
			(island_removal_mode 1)
			(island_area_min 10)
		)
		(polygon
			(pts
				(xy 129.1525 130.910677) (xy 129.157318 130.841236) (xy 129.17104 130.789912) (xy 129.217755 130.71437)
				(xy 129.227299 130.702229) (xy 129.277081 130.635003) (xy 129.09 130.509) (xy 128.902919 130.635003)
				(xy 128.952701 130.702231) (xy 129.007106 130.785397) (xy 129.02219 130.838251) (xy 129.0275 130.910677)
			)
		)
	)
	(zone
		(net 739)
		(net_name "Net-(U43B-LS_OK_{OUT_B})")
		(layer "In5.Cu")
		(name "$teardrop_padvia$")
		(hatch none 0.1)
		(priority 30130)
		(attr
			(teardrop
				(type padvia)
			)
		)
		(connect_pads yes
			(clearance 0)
		)
		(min_thickness 0.0254)
		(filled_areas_thickness no)
		(fill yes
			(thermal_gap 0.5)
			(thermal_bridge_width 0.5)
			(island_removal_mode 1)
			(island_area_min 10)
		)
		(polygon
			(pts
				(xy 149.348759 139.527147) (xy 149.372014 139.557157) (xy 149.380358 139.584496) (xy 149.366091 139.630084)
				(xy 149.318681 139.68335) (xy 149.270334 139.735708) (xy 149.236416 139.798979) (xy 149.450707 139.860707)
				(xy 149.636206 139.734122) (xy 149.570128 139.620813) (xy 149.522801 139.5389) (xy 149.437147 139.438759)
			)
		)
	)
	(zone
		(net 52)
		(net_name "+5V")
		(layer "In5.Cu")
		(name "$teardrop_padvia$")
		(hatch none 0.1)
		(priority 30235)
		(attr
			(teardrop
				(type padvia)
			)
		)
		(connect_pads yes
			(clearance 0)
		)
		(min_thickness 0.0254)
		(filled_areas_thickness no)
		(fill yes
			(thermal_gap 0.5)
			(thermal_bridge_width 0.5)
			(island_removal_mode 1)
			(island_area_min 10)
		)
		(polygon
			(pts
				(xy 252.424127 86.122484) (xy 252.371618 86.16818) (xy 252.325623 86.194767) (xy 252.239174 86.215151)
				(xy 252.223841 86.216987) (xy 252.141105 86.229322) (xy 252.184293 86.450706) (xy 252.405677 86.493894)
				(xy 252.418011 86.411159) (xy 252.438349 86.31388) (xy 252.465057 86.26584) (xy 252.512515 86.210872)
			)
		)
	)
	(zone
		(net 201)
		(net_name "/OCuLink/~{CPRSNT_D0}")
		(layer "In5.Cu")
		(name "$teardrop_padvia$")
		(hatch none 0.1)
		(priority 30125)
		(attr
			(teardrop
				(type padvia)
			)
		)
		(connect_pads yes
			(clearance 0)
		)
		(min_thickness 0.0254)
		(filled_areas_thickness no)
		(fill yes
			(thermal_gap 0.5)
			(thermal_bridge_width 0.5)
			(island_removal_mode 1)
			(island_area_min 10)
		)
		(polygon
			(pts
				(xy 104.016699 161.4975) (xy 103.952817 161.492732) (xy 103.904948 161.479355) (xy 103.835179 161.433759)
				(xy 103.818703 161.419392) (xy 103.741025 161.35793) (xy 103.615022 161.545011) (xy 103.696151 161.750679)
				(xy 103.797507 161.696455) (xy 103.80949 161.688405) (xy 103.891862 161.642085) (xy 103.945569 161.627785)
				(xy 104.016699 161.6225)
			)
		)
	)
	(zone
		(net 137)
		(net_name "/Com Express 7 MGMT/~{TYPE2}")
		(layer "In5.Cu")
		(name "$teardrop_padvia$")
		(hatch none 0.1)
		(priority 30225)
		(attr
			(teardrop
				(type padvia)
			)
		)
		(connect_pads yes
			(clearance 0)
		)
		(min_thickness 0.0254)
		(filled_areas_thickness no)
		(fill yes
			(thermal_gap 0.5)
			(thermal_bridge_width 0.5)
			(island_removal_mode 1)
			(island_area_min 10)
		)
		(polygon
			(pts
				(xy 216.800677 143.4375) (xy 216.731236 143.432682) (xy 216.679913 143.41896) (xy 216.604371 143.372246)
				(xy 216.592231 143.362701) (xy 216.525003 143.312919) (xy 216.399 143.5) (xy 216.525003 143.687081)
				(xy 216.592229 143.637299) (xy 216.675396 143.582894) (xy 216.728251 143.56781) (xy 216.800677 143.5625)
			)
		)
	)
	(zone
		(net 243)
		(net_name "/Com Express 7 Interfaces/PCIe_{B2Bx4}.RX2-")
		(layer "In5.Cu")
		(name "$teardrop_padvia$")
		(hatch none 0.1)
		(priority 30090)
		(attr
			(teardrop
				(type padvia)
			)
		)
		(connect_pads yes
			(clearance 0)
		)
		(min_thickness 0.0254)
		(filled_areas_thickness no)
		(fill yes
			(thermal_gap 0.5)
			(thermal_bridge_width 0.5)
			(island_removal_mode 1)
			(island_area_min 10)
		)
		(polygon
			(pts
				(xy 192.360584 160.998) (xy 192.223248 161.004896) (xy 192.142061 161.009276) (xy 192.043895 160.997823)
				(xy 191.999 161.2185) (xy 192.152394 161.378189) (xy 192.201472 161.310692) (xy 192.215811 161.28219)
				(xy 192.23711 161.241571) (xy 192.263802 161.207738) (xy 192.302691 161.184583) (xy 192.360584 161.176)
			)
		)
	)
	(zone
		(net 159)
		(net_name "/2xUSB3.0+RJ45/USBSS_1.RX+")
		(layer "In5.Cu")
		(name "$teardrop_padvia$")
		(hatch none 0.1)
		(priority 30143)
		(attr
			(teardrop
				(type padvia)
			)
		)
		(connect_pads yes
			(clearance 0)
		)
		(min_thickness 0.0254)
		(filled_areas_thickness no)
		(fill yes
			(thermal_gap 0.5)
			(thermal_bridge_width 0.5)
			(island_removal_mode 1)
			(island_area_min 10)
		)
		(polygon
			(pts
				(xy 180.377 157.998916) (xy 180.383774 158.13169) (xy 180.388077 158.210162) (xy 180.376823 158.306105)
				(xy 180.5975 158.351) (xy 180.722503 158.162919) (xy 180.640957 158.124196) (xy 180.600152 158.107418)
				(xy 180.566785 158.085433) (xy 180.544264 158.051509) (xy 180.536 157.998916)
			)
		)
	)
	(zone
		(net 744)
		(net_name "/2xSFP+/KR to SFI #2/TMS")
		(layer "In5.Cu")
		(name "$teardrop_padvia$")
		(hatch none 0.1)
		(priority 30191)
		(attr
			(teardrop
				(type padvia)
			)
		)
		(connect_pads yes
			(clearance 0)
		)
		(min_thickness 0.0254)
		(filled_areas_thickness no)
		(fill yes
			(thermal_gap 0.5)
			(thermal_bridge_width 0.5)
			(island_removal_mode 1)
			(island_area_min 10)
		)
		(polygon
			(pts
				(xy 135.6525 130.910677) (xy 135.657318 130.841236) (xy 135.67104 130.789912) (xy 135.717755 130.71437)
				(xy 135.727299 130.702229) (xy 135.777081 130.635003) (xy 135.59 130.509) (xy 135.402919 130.635003)
				(xy 135.452701 130.702231) (xy 135.507106 130.785397) (xy 135.52219 130.838251) (xy 135.5275 130.910677)
			)
		)
	)
	(zone
		(net 14)
		(net_name "/Com Express 7 Interfaces/PCIe_{B1x2}.RX0+")
		(layer "In5.Cu")
		(name "$teardrop_padvia$")
		(hatch none 0.1)
		(priority 30106)
		(attr
			(teardrop
				(type padvia)
			)
		)
		(connect_pads yes
			(clearance 0)
		)
		(min_thickness 0.0254)
		(filled_areas_thickness no)
		(fill yes
			(thermal_gap 0.5)
			(thermal_bridge_width 0.5)
			(island_removal_mode 1)
			(island_area_min 10)
		)
		(polygon
			(pts
				(xy 205.902 131.756084) (xy 205.898302 131.589599) (xy 205.897677 131.40947) (xy 205.677 131.399)
				(xy 205.551997 131.587081) (xy 205.621529 131.623424) (xy 205.661495 131.642701) (xy 205.694058 131.666786)
				(xy 205.715974 131.702356) (xy 205.724 131.756084)
			)
		)
	)
	(zone
		(net 2)
		(net_name "+3V3")
		(layer "In5.Cu")
		(name "$teardrop_padvia$")
		(hatch none 0.1)
		(priority 30018)
		(attr
			(teardrop
				(type padvia)
			)
		)
		(connect_pads yes
			(clearance 0)
		)
		(min_thickness 0.0254)
		(filled_areas_thickness no)
		(fill yes
			(thermal_gap 0.5)
			(thermal_bridge_width 0.5)
			(island_removal_mode 1)
			(island_area_min 10)
		)
		(polygon
			(pts
				(xy 196.55861 77.701486) (xy 196.553897 77.779397) (xy 196.54091 77.838181) (xy 196.498809 77.929211)
				(xy 196.45611 78.014384) (xy 196.65861 78.103163) (xy 196.86111 78.014384) (xy 196.818411 77.929213)
				(xy 196.775743 77.83638) (xy 196.763166 77.778241) (xy 196.75861 77.701486)
			)
		)
	)
	(zone
		(net 357)
		(net_name "/Com Express 7 MGMT/SMBus.SCL")
		(layer "In5.Cu")
		(name "$teardrop_padvia$")
		(hatch none 0.1)
		(priority 30282)
		(attr
			(teardrop
				(type padvia)
			)
		)
		(connect_pads yes
			(clearance 0)
		)
		(min_thickness 0.0254)
		(filled_areas_thickness no)
		(fill yes
			(thermal_gap 0.5)
			(thermal_bridge_width 0.5)
			(island_removal_mode 1)
			(island_area_min 10)
		)
		(polygon
			(pts
				(xy 160.127515 147.239127) (xy 160.081819 147.186618) (xy 160.055231 147.140623) (xy 160.034847 147.054175)
				(xy 160.033011 147.03884) (xy 160.020677 146.956105) (xy 159.799293 146.999293) (xy 159.756105 147.220677)
				(xy 159.83884 147.233011) (xy 159.936119 147.253349) (xy 159.984159 147.280057) (xy 160.039127 147.327515)
			)
		)
	)
	(zone
		(net 165)
		(net_name "/2xSFP+/SCL0")
		(layer "In5.Cu")
		(name "$teardrop_padvia$")
		(hatch none 0.1)
		(priority 30000)
		(attr
			(teardrop
				(type padvia)
			)
		)
		(connect_pads yes
			(clearance 0)
		)
		(min_thickness 0.0254)
		(filled_areas_thickness no)
		(fill yes
			(thermal_gap 0.5)
			(thermal_bridge_width 0.5)
			(island_removal_mode 1)
			(island_area_min 10)
		)
		(polygon
			(pts
				(xy 146.717627 161.617501) (xy 146.465262 161.623299) (xy 146.287407 161.643888) (xy 146.136944 161.671687)
				(xy 146.050254 161.688262) (xy 146.129 162.11) (xy 146.551738 162.193889) (xy 146.561801 162.064849)
				(xy 146.560194 161.998653) (xy 146.559472 161.899451) (xy 146.574905 161.817974) (xy 146.593631 161.786563)
				(xy 146.62234 161.762799) (xy 146.663012 161.747754) (xy 146.717627 161.742501)
			)
		)
	)
	(zone
		(net 74)
		(net_name "+1V0")
		(layer "In5.Cu")
		(name "$teardrop_padvia$")
		(hatch none 0.1)
		(priority 30024)
		(attr
			(teardrop
				(type padvia)
			)
		)
		(connect_pads yes
			(clearance 0)
		)
		(min_thickness 0.0254)
		(filled_areas_thickness no)
		(fill yes
			(thermal_gap 0.5)
			(thermal_bridge_width 0.5)
			(island_removal_mode 1)
			(island_area_min 10)
		)
		(polygon
			(pts
				(xy 203.012641 73.014773) (xy 202.960882 72.956349) (xy 202.928499 72.905599) (xy 202.8939 72.81146)
				(xy 202.863867 72.721042) (xy 202.657903 72.801456) (xy 202.577489 73.00742) (xy 202.667907 73.037453)
				(xy 202.763721 73.072925) (xy 202.813724 73.105142) (xy 202.87122 73.156194)
			)
		)
	)
	(zone
		(net 722)
		(net_name "/2xSFP+/KR to SFI #1/TDI")
		(layer "In5.Cu")
		(name "$teardrop_padvia$")
		(hatch none 0.1)
		(priority 30213)
		(attr
			(teardrop
				(type padvia)
			)
		)
		(connect_pads yes
			(clearance 0)
		)
		(min_thickness 0.0254)
		(filled_areas_thickness no)
		(fill yes
			(thermal_gap 0.5)
			(thermal_bridge_width 0.5)
			(island_removal_mode 1)
			(island_area_min 10)
		)
		(polygon
			(pts
				(xy 153.1625 130.540677) (xy 153.167318 130.471236) (xy 153.18104 130.419912) (xy 153.227755 130.34437)
				(xy 153.237299 130.332229) (xy 153.287081 130.265003) (xy 153.1 130.139) (xy 152.912919 130.265003)
				(xy 152.962701 130.332231) (xy 153.017106 130.415397) (xy 153.03219 130.468251) (xy 153.0375 130.540677)
			)
		)
	)
	(zone
		(net 254)
		(net_name "/Com Express 7 Interfaces/PCIe_{B2Bx4}.RX1+")
		(layer "In5.Cu")
		(name "$teardrop_padvia$")
		(hatch none 0.1)
		(priority 30073)
		(attr
			(teardrop
				(type padvia)
			)
		)
		(connect_pads yes
			(clearance 0)
		)
		(min_thickness 0.0254)
		(filled_areas_thickness no)
		(fill yes
			(thermal_gap 0.5)
			(thermal_bridge_width 0.5)
			(island_removal_mode 1)
			(island_area_min 10)
		)
		(polygon
			(pts
				(xy 194.659809 159.449868) (xy 194.624827 159.478144) (xy 194.591838 159.49248) (xy 194.529418 159.491596)
				(xy 194.482353 159.477149) (xy 194.429381 159.460912) (xy 194.369629 159.454109) (xy 194.374079 159.675493)
				(xy 194.561867 159.799789) (xy 194.608845 159.737785) (xy 194.652661 159.694344) (xy 194.683687 159.667966)
				(xy 194.785674 159.575733)
			)
		)
	)
	(zone
		(net 2)
		(net_name "+3V3")
		(layer "In5.Cu")
		(name "$teardrop_padvia$")
		(hatch none 0.1)
		(priority 30011)
		(attr
			(teardrop
				(type padvia)
			)
		)
		(connect_pads yes
			(clearance 0)
		)
		(min_thickness 0.0254)
		(filled_areas_thickness no)
		(fill yes
			(thermal_gap 0.5)
			(thermal_bridge_width 0.5)
			(island_removal_mode 1)
			(island_area_min 10)
		)
		(polygon
			(pts
				(xy 197.80861 74.50284) (xy 197.813323 74.424927) (xy 197.82631 74.366143) (xy 197.868412 74.27511)
				(xy 197.91111 74.189941) (xy 197.70861 74.101163) (xy 197.50611 74.189941) (xy 197.548808 74.275112)
				(xy 197.591477 74.367946) (xy 197.604054 74.426085) (xy 197.60861 74.50284)
			)
		)
	)
	(zone
		(net 400)
		(net_name "/Com Express 7 MGMT/FAN_PWM")
		(layer "In5.Cu")
		(name "$teardrop_padvia$")
		(hatch none 0.1)
		(priority 30188)
		(attr
			(teardrop
				(type padvia)
			)
		)
		(connect_pads yes
			(clearance 0)
		)
		(min_thickness 0.0254)
		(filled_areas_thickness no)
		(fill yes
			(thermal_gap 0.5)
			(thermal_bridge_width 0.5)
			(island_removal_mode 1)
			(island_area_min 10)
		)
		(polygon
			(pts
				(xy 254.75003 77.2475) (xy 254.819471 77.252318) (xy 254.870795 77.26604) (xy 254.946336 77.312755)
				(xy 254.958476 77.322299) (xy 255.025704 77.372081) (xy 255.151707 77.185) (xy 255.025704 76.997919)
				(xy 254.958475 77.047702) (xy 254.875309 77.102106) (xy 254.822455 77.11719) (xy 254.75003 77.1225)
			)
		)
	)
	(zone
		(net 670)
		(net_name "/2xSFP+/KR to SFI #2/MDIO")
		(layer "In5.Cu")
		(name "$teardrop_padvia$")
		(hatch none 0.1)
		(priority 30242)
		(attr
			(teardrop
				(type padvia)
			)
		)
		(connect_pads yes
			(clearance 0)
		)
		(min_thickness 0.0254)
		(filled_areas_thickness no)
		(fill yes
			(thermal_gap 0.5)
			(thermal_bridge_width 0.5)
			(island_removal_mode 1)
			(island_area_min 10)
		)
		(polygon
			(pts
				(xy 125.179127 142.77465) (xy 125.126618 142.820346) (xy 125.080623 142.846933) (xy 124.994174 142.867317)
				(xy 124.978841 142.869153) (xy 124.896105 142.881488) (xy 124.939293 143.102872) (xy 125.160677 143.14606)
				(xy 125.173011 143.063325) (xy 125.193349 142.966046) (xy 125.220057 142.918006) (xy 125.267515 142.863038)
			)
		)
	)
	(zone
		(net 672)
		(net_name "/2xSFP+/KR to SFI #2/MDC")
		(layer "In5.Cu")
		(name "$teardrop_padvia$")
		(hatch none 0.1)
		(priority 30229)
		(attr
			(teardrop
				(type padvia)
			)
		)
		(connect_pads yes
			(clearance 0)
		)
		(min_thickness 0.0254)
		(filled_areas_thickness no)
		(fill yes
			(thermal_gap 0.5)
			(thermal_bridge_width 0.5)
			(island_removal_mode 1)
			(island_area_min 10)
		)
		(polygon
			(pts
				(xy 125.929127 142.782485) (xy 125.876618 142.828181) (xy 125.830623 142.854768) (xy 125.744174 142.875152)
				(xy 125.728841 142.876988) (xy 125.646105 142.889323) (xy 125.689293 143.110707) (xy 125.910677 143.153895)
				(xy 125.923011 143.07116) (xy 125.943349 142.973881) (xy 125.970057 142.925841) (xy 126.017515 142.870873)
			)
		)
	)
	(zone
		(net 595)
		(net_name "/Misc/PWM_{SRCSEL}")
		(layer "In5.Cu")
		(name "$teardrop_padvia$")
		(hatch none 0.1)
		(priority 30231)
		(attr
			(teardrop
				(type padvia)
			)
		)
		(connect_pads yes
			(clearance 0)
		)
		(min_thickness 0.0254)
		(filled_areas_thickness no)
		(fill yes
			(thermal_gap 0.5)
			(thermal_bridge_width 0.5)
			(island_removal_mode 1)
			(island_area_min 10)
		)
		(polygon
			(pts
				(xy 244.059835 76.857485) (xy 244.007326 76.903181) (xy 243.961331 76.929768) (xy 243.874882 76.950152)
				(xy 243.859549 76.951988) (xy 243.776813 76.964323) (xy 243.820001 77.185707) (xy 244.041385 77.228895)
				(xy 244.053719 77.14616) (xy 244.074057 77.048881) (xy 244.100765 77.000841) (xy 244.148223 76.945873)
			)
		)
	)
	(zone
		(net 205)
		(net_name "/Backplane/PCIe_{REF}.CK-")
		(layer "In5.Cu")
		(name "$teardrop_padvia$")
		(hatch none 0.1)
		(priority 30108)
		(attr
			(teardrop
				(type padvia)
			)
		)
		(connect_pads yes
			(clearance 0)
		)
		(min_thickness 0.0254)
		(filled_areas_thickness no)
		(fill yes
			(thermal_gap 0.5)
			(thermal_bridge_width 0.5)
			(island_removal_mode 1)
			(island_area_min 10)
		)
		(polygon
			(pts
				(xy 258.802 137.456084) (xy 258.798302 137.289599) (xy 258.797677 137.10947) (xy 258.577 137.099)
				(xy 258.451997 137.287081) (xy 258.521529 137.323424) (xy 258.561495 137.342701) (xy 258.594058 137.366786)
				(xy 258.615974 137.402356) (xy 258.624 137.456084)
			)
		)
	)
	(zone
		(net 329)
		(net_name "/Com Express 7 Interfaces/PCIe_{B2Ax4}.TX2-")
		(layer "In5.Cu")
		(name "$teardrop_padvia$")
		(hatch none 0.1)
		(priority 30100)
		(attr
			(teardrop
				(type padvia)
			)
		)
		(connect_pads yes
			(clearance 0)
		)
		(min_thickness 0.0254)
		(filled_areas_thickness no)
		(fill yes
			(thermal_gap 0.5)
			(thermal_bridge_width 0.5)
			(island_removal_mode 1)
			(island_area_min 10)
		)
		(polygon
			(pts
				(xy 231.226 147.156084) (xy 231.230759 147.113152) (xy 231.244072 147.081738) (xy 231.288959 147.042447)
				(xy 231.328471 147.023424) (xy 231.398003 146.987081) (xy 231.273 146.799) (xy 231.052323 146.80947)
				(xy 231.051698 146.989597) (xy 231.048 147.156084)
			)
		)
	)
	(zone
		(net 241)
		(net_name "/Com Express 7 Interfaces/PCIe_{B2Bx4}.TX3-")
		(layer "In5.Cu")
		(name "$teardrop_padvia$")
		(hatch none 0.1)
		(priority 30063)
		(attr
			(teardrop
				(type padvia)
			)
		)
		(connect_pads yes
			(clearance 0)
		)
		(min_thickness 0.0254)
		(filled_areas_thickness no)
		(fill yes
			(thermal_gap 0.5)
			(thermal_bridge_width 0.5)
			(island_removal_mode 1)
			(island_area_min 10)
		)
		(polygon
			(pts
				(xy 173.939416 95.886) (xy 173.984146 95.890741) (xy 174.017611 95.903931) (xy 174.061124 95.948694)
				(xy 174.084188 95.99219) (xy 174.110165 96.041127) (xy 174.147605 96.088189) (xy 174.301 95.9285)
				(xy 174.256105 95.707823) (xy 174.17904 95.718447) (xy 174.117337 95.718182) (xy 174.076751 95.714896)
				(xy 173.939416 95.708)
			)
		)
	)
	(zone
		(net 336)
		(net_name "/Com Express 7 Interfaces/PCIE_{REF}.CK+")
		(layer "In5.Cu")
		(name "$teardrop_padvia$")
		(hatch none 0.1)
		(priority 30134)
		(attr
			(teardrop
				(type padvia)
			)
		)
		(connect_pads yes
			(clearance 0)
		)
		(min_thickness 0.0254)
		(filled_areas_thickness no)
		(fill yes
			(thermal_gap 0.5)
			(thermal_bridge_width 0.5)
			(island_removal_mode 1)
			(island_area_min 10)
		)
		(polygon
			(pts
				(xy 219.64171 170.419696) (xy 219.675396 170.37929) (xy 219.694835 170.341097) (xy 219.702542 170.269116)
				(xy 219.689099 170.201421) (xy 219.674297 170.127791) (xy 219.677177 170.043895) (xy 219.457207 169.999293)
				(xy 219.331497 170.187081) (xy 219.398109 170.21303) (xy 219.444041 170.223083) (xy 219.521804 170.245939)
				(xy 219.533438 170.264969) (xy 219.515846 170.293832)
			)
		)
	)
	(zone
		(net 45)
		(net_name "/2xUSB3.0+RJ45/USBSS_2.TX+")
		(layer "In5.Cu")
		(name "$teardrop_padvia$")
		(hatch none 0.1)
		(priority 30142)
		(attr
			(teardrop
				(type padvia)
			)
		)
		(connect_pads yes
			(clearance 0)
		)
		(min_thickness 0.0254)
		(filled_areas_thickness no)
		(fill yes
			(thermal_gap 0.5)
			(thermal_bridge_width 0.5)
			(island_removal_mode 1)
			(island_area_min 10)
		)
		(polygon
			(pts
				(xy 181.877 149.223916) (xy 181.883774 149.35669) (xy 181.888077 149.435162) (xy 181.876823 149.531105)
				(xy 182.0975 149.576) (xy 182.222503 149.387919) (xy 182.140957 149.349196) (xy 182.100152 149.332418)
				(xy 182.066785 149.310433) (xy 182.044264 149.276509) (xy 182.036 149.223916)
			)
		)
	)
	(zone
		(net 874)
		(net_name "/2xSFP+/SDA1")
		(layer "In5.Cu")
		(name "$teardrop_padvia$")
		(hatch none 0.1)
		(priority 30003)
		(attr
			(teardrop
				(type padvia)
			)
		)
		(connect_pads yes
			(clearance 0)
		)
		(min_thickness 0.0254)
		(filled_areas_thickness no)
		(fill yes
			(thermal_gap 0.5)
			(thermal_bridge_width 0.5)
			(island_removal_mode 1)
			(island_area_min 10)
		)
		(polygon
			(pts
				(xy 142.614348 162.812736) (xy 142.672405 162.877615) (xy 142.712415 162.937096) (xy 142.750886 163.042061)
				(xy 142.760127 163.178355) (xy 142.763033 163.27714) (xy 142.778262 163.393889) (xy 143.200707 163.310707)
				(xy 143.283889 162.888262) (xy 143.121651 162.870953) (xy 143.068355 162.870127) (xy 142.978002 162.867095)
				(xy 142.891963 162.85074) (xy 142.802715 162.807634) (xy 142.702736 162.724348)
			)
		)
	)
	(zone
		(net 371)
		(net_name "/Com Express 7 MGMT/I2C.SCL")
		(layer "In5.Cu")
		(name "$teardrop_padvia$")
		(hatch none 0.1)
		(priority 30252)
		(attr
			(teardrop
				(type padvia)
			)
		)
		(connect_pads yes
			(clearance 0)
		)
		(min_thickness 0.0254)
		(filled_areas_thickness no)
		(fill yes
			(thermal_gap 0.5)
			(thermal_bridge_width 0.5)
			(island_removal_mode 1)
			(island_area_min 10)
		)
		(polygon
			(pts
				(xy 301.849485 94.450873) (xy 301.895181 94.503382) (xy 301.921768 94.549376) (xy 301.942152 94.635825)
				(xy 301.943988 94.651158) (xy 301.956323 94.733895) (xy 302.177707 94.690707) (xy 302.220895 94.469323)
				(xy 302.138158 94.456988) (xy 302.04088 94.436651) (xy 301.99284 94.409943) (xy 301.937873 94.362485)
			)
		)
	)
	(zone
		(net 164)
		(net_name "/2xSFP+/SDA0")
		(layer "In5.Cu")
		(name "$teardrop_padvia$")
		(hatch none 0.1)
		(priority 30187)
		(attr
			(teardrop
				(type padvia)
			)
		)
		(connect_pads yes
			(clearance 0)
		)
		(min_thickness 0.0254)
		(filled_areas_thickness no)
		(fill yes
			(thermal_gap 0.5)
			(thermal_bridge_width 0.5)
			(island_removal_mode 1)
			(island_area_min 10)
		)
		(polygon
			(pts
				(xy 165.099323 146.1625) (xy 165.168764 146.167318) (xy 165.220088 146.18104) (xy 165.295629 146.227755)
				(xy 165.307769 146.237299) (xy 165.374997 146.287081) (xy 165.501 146.1) (xy 165.374997 145.912919)
				(xy 165.307768 145.962702) (xy 165.224602 146.017106) (xy 165.171748 146.03219) (xy 165.099323 146.0375)
			)
		)
	)
	(zone
		(net 528)
		(net_name "/Backplane/~{PERST}")
		(layer "In5.Cu")
		(name "$teardrop_padvia$")
		(hatch none 0.1)
		(priority 30173)
		(attr
			(teardrop
				(type padvia)
			)
		)
		(connect_pads yes
			(clearance 0)
		)
		(min_thickness 0.0254)
		(filled_areas_thickness no)
		(fill yes
			(thermal_gap 0.5)
			(thermal_bridge_width 0.5)
			(island_removal_mode 1)
			(island_area_min 10)
		)
		(polygon
			(pts
				(xy 313.3375 162.709323) (xy 313.332682 162.778763) (xy 313.31896 162.830087) (xy 313.272245 162.905628)
				(xy 313.262702 162.917768) (xy 313.212919 162.984997) (xy 313.4 163.111) (xy 313.587081 162.984997)
				(xy 313.537299 162.917769) (xy 313.482894 162.834603) (xy 313.46781 162.781748) (xy 313.4625 162.709323)
			)
		)
	)
	(zone
		(net 359)
		(net_name "/Com Express 7 MGMT/SMBus.~{INT}")
		(layer "In5.Cu")
		(name "$teardrop_padvia$")
		(hatch none 0.1)
		(priority 30109)
		(attr
			(teardrop
				(type padvia)
			)
		)
		(connect_pads yes
			(clearance 0)
		)
		(min_thickness 0.0254)
		(filled_areas_thickness no)
		(fill yes
			(thermal_gap 0.5)
			(thermal_bridge_width 0.5)
			(island_removal_mode 1)
			(island_area_min 10)
		)
		(polygon
			(pts
				(xy 130.102486 80.919126) (xy 130.044742 80.970301) (xy 129.994858 81.002486) (xy 129.913011 81.035505)
				(xy 129.795552 81.084405) (xy 129.899293 81.280708) (xy 130.120677 81.323896) (xy 130.126499 81.222014)
				(xy 130.125085 81.200215) (xy 130.128513 81.10711) (xy 130.148722 81.059663) (xy 130.190874 81.007514)
			)
		)
	)
	(zone
		(net 385)
		(net_name "/Com Express 7 Interfaces/SDIO.CMD")
		(layer "In5.Cu")
		(name "$teardrop_padvia$")
		(hatch none 0.1)
		(priority 30038)
		(attr
			(teardrop
				(type padvia)
			)
		)
		(connect_pads yes
			(clearance 0)
		)
		(min_thickness 0.0254)
		(filled_areas_thickness no)
		(fill yes
			(thermal_gap 0.5)
			(thermal_bridge_width 0.5)
			(island_removal_mode 1)
			(island_area_min 10)
		)
		(polygon
			(pts
				(xy 113.900677 136.5825) (xy 113.832314 136.577809) (xy 113.78003 136.564974) (xy 113.690652 136.516057)
				(xy 113.587778 136.4575) (xy 113.499 136.66) (xy 113.587778 136.8625) (xy 113.690651 136.803943)
				(xy 113.774447 136.757067) (xy 113.828713 136.742761) (xy 113.900677 136.7375)
			)
		)
	)
	(zone
		(net 337)
		(net_name "/Com Express 7 Interfaces/PCIE_{REF}.CK-")
		(layer "In5.Cu")
		(name "$teardrop_padvia$")
		(hatch none 0.1)
		(priority 30069)
		(attr
			(teardrop
				(type padvia)
			)
		)
		(connect_pads yes
			(clearance 0)
		)
		(min_thickness 0.0254)
		(filled_areas_thickness no)
		(fill yes
			(thermal_gap 0.5)
			(thermal_bridge_width 0.5)
			(island_removal_mode 1)
			(island_area_min 10)
		)
		(polygon
			(pts
				(xy 220.051 170.360584) (xy 220.055741 170.315854) (xy 220.068931 170.282389) (xy 220.113694 170.238875)
				(xy 220.15719 170.215811) (xy 220.206128 170.189834) (xy 220.253189 170.152394) (xy 220.0935 169.999)
				(xy 219.872823 170.043895) (xy 219.883447 170.120959) (xy 219.883182 170.182662) (xy 219.879896 170.223248)
				(xy 219.873 170.360584)
			)
		)
	)
	(zone
		(net 137)
		(net_name "/Com Express 7 MGMT/~{TYPE2}")
		(layer "In5.Cu")
		(name "$teardrop_padvia$")
		(hatch none 0.1)
		(priority 30263)
		(attr
			(teardrop
				(type padvia)
			)
		)
		(connect_pads yes
			(clearance 0)
		)
		(min_thickness 0.0254)
		(filled_areas_thickness no)
		(fill yes
			(thermal_gap 0.5)
			(thermal_bridge_width 0.5)
			(island_removal_mode 1)
			(island_area_min 10)
		)
		(polygon
			(pts
				(xy 254.396485 132.370873) (xy 254.442181 132.423382) (xy 254.468768 132.469376) (xy 254.489152 132.555825)
				(xy 254.490988 132.571158) (xy 254.503323 132.653895) (xy 254.724707 132.610707) (xy 254.767895 132.389323)
				(xy 254.685158 132.376988) (xy 254.58788 132.356651) (xy 254.53984 132.329943) (xy 254.484873 132.282485)
			)
		)
	)
	(zone
		(net 237)
		(net_name "/Com Express 7 Interfaces/PCIe_{B2Bx4}.RX3-")
		(layer "In5.Cu")
		(name "$teardrop_padvia$")
		(hatch none 0.1)
		(priority 30093)
		(attr
			(teardrop
				(type padvia)
			)
		)
		(connect_pads yes
			(clearance 0)
		)
		(min_thickness 0.0254)
		(filled_areas_thickness no)
		(fill yes
			(thermal_gap 0.5)
			(thermal_bridge_width 0.5)
			(island_removal_mode 1)
			(island_area_min 10)
		)
		(polygon
			(pts
				(xy 191.560584 159.698) (xy 191.423248 159.704896) (xy 191.342061 159.709276) (xy 191.243895 159.697823)
				(xy 191.199 159.9185) (xy 191.352394 160.078189) (xy 191.401472 160.010692) (xy 191.415811 159.98219)
				(xy 191.43711 159.941571) (xy 191.463802 159.907738) (xy 191.502691 159.884583) (xy 191.560584 159.876)
			)
		)
	)
	(zone
		(net 875)
		(net_name "/2xSFP+/SCL1")
		(layer "In5.Cu")
		(name "$teardrop_padvia$")
		(hatch none 0.1)
		(priority 30002)
		(attr
			(teardrop
				(type padvia)
			)
		)
		(connect_pads yes
			(clearance 0)
		)
		(min_thickness 0.0254)
		(filled_areas_thickness no)
		(fill yes
			(thermal_gap 0.5)
			(thermal_bridge_width 0.5)
			(island_removal_mode 1)
			(island_area_min 10)
		)
		(polygon
			(pts
				(xy 141.965653 163.185375) (xy 141.931823 163.144697) (xy 141.913524 163.106747) (xy 141.908756 163.074532)
				(xy 141.913588 163.043648) (xy 141.95163 162.977845) (xy 142.035459 162.892926) (xy 142.10504 162.825283)
				(xy 142.167532 162.748895) (xy 141.809293 162.509293) (xy 141.455397 162.751824) (xy 141.504983 162.824853)
				(xy 141.658158 163.038419) (xy 141.877264 163.273764)
			)
		)
	)
	(zone
		(net 736)
		(net_name "Net-(U43A-LS_OK_{OUT_A})")
		(layer "In5.Cu")
		(name "$teardrop_padvia$")
		(hatch none 0.1)
		(priority 30111)
		(attr
			(teardrop
				(type padvia)
			)
		)
		(connect_pads yes
			(clearance 0)
		)
		(min_thickness 0.0254)
		(filled_areas_thickness no)
		(fill yes
			(thermal_gap 0.5)
			(thermal_bridge_width 0.5)
			(island_removal_mode 1)
			(island_area_min 10)
		)
		(polygon
			(pts
				(xy 150.6325 130.529864) (xy 150.637117 130.446717) (xy 150.649439 130.38511) (xy 150.675505 130.31324)
				(xy 150.715849 130.195549) (xy 150.5 130.139) (xy 150.317699 130.269783) (xy 150.384195 130.337619)
				(xy 150.410898 130.357543) (xy 150.44818 130.386306) (xy 150.478922 130.419857) (xy 150.499802 130.465332)
				(xy 150.5075 130.529864)
			)
		)
	)
	(zone
		(net 531)
		(net_name "/Com Express 7 Interfaces/SD_CD")
		(layer "In5.Cu")
		(name "$teardrop_padvia$")
		(hatch none 0.1)
		(priority 30276)
		(attr
			(teardrop
				(type padvia)
			)
		)
		(connect_pads yes
			(clearance 0)
		)
		(min_thickness 0.0254)
		(filled_areas_thickness no)
		(fill yes
			(thermal_gap 0.5)
			(thermal_bridge_width 0.5)
			(island_removal_mode 1)
			(island_area_min 10)
		)
		(polygon
			(pts
				(xy 166.310873 158.027515) (xy 166.363382 157.981819) (xy 166.409376 157.955231) (xy 166.495824 157.934847)
				(xy 166.51116 157.933011) (xy 166.593895 157.920677) (xy 166.550707 157.699293) (xy 166.329323 157.656105)
				(xy 166.316988 157.738841) (xy 166.296651 157.836119) (xy 166.269943 157.884159) (xy 166.222485 157.939127)
			)
		)
	)
	(zone
		(net 11)
		(net_name "/Com Express 7 Interfaces/PCIe_{B1x2}.TX0-")
		(layer "In5.Cu")
		(name "$teardrop_padvia$")
		(hatch none 0.1)
		(priority 30047)
		(attr
			(teardrop
				(type padvia)
			)
		)
		(connect_pads yes
			(clearance 0)
		)
		(min_thickness 0.0254)
		(filled_areas_thickness no)
		(fill yes
			(thermal_gap 0.5)
			(thermal_bridge_width 0.5)
			(island_removal_mode 1)
			(island_area_min 10)
		)
		(polygon
			(pts
				(xy 203.385 166.63064) (xy 203.387373 166.747341) (xy 203.388021 166.844077) (xy 203.372823 166.956105)
				(xy 203.5935 167.001) (xy 203.758499 166.852915) (xy 203.690487 166.798722) (xy 203.66634 166.784747)
				(xy 203.626746 166.760795) (xy 203.593828 166.731678) (xy 203.571331 166.690569) (xy 203.563 166.63064)
			)
		)
	)
	(zone
		(net 249)
		(net_name "/Com Express 7 Interfaces/PCIe_{B2Bx4}.TX2+")
		(layer "In5.Cu")
		(name "$teardrop_padvia$")
		(hatch none 0.1)
		(priority 30076)
		(attr
			(teardrop
				(type padvia)
			)
		)
		(connect_pads yes
			(clearance 0)
		)
		(min_thickness 0.0254)
		(filled_areas_thickness no)
		(fill yes
			(thermal_gap 0.5)
			(thermal_bridge_width 0.5)
			(island_removal_mode 1)
			(island_area_min 10)
		)
		(polygon
			(pts
				(xy 173.939416 98.512) (xy 174.076751 98.505104) (xy 174.157939 98.500724) (xy 174.256105 98.512177)
				(xy 174.301 98.2915) (xy 174.147605 98.13181) (xy 174.098527 98.199306) (xy 174.084187 98.22781)
				(xy 174.062888 98.268429) (xy 174.036197 98.302262) (xy 173.997308 98.325417) (xy 173.939416 98.334)
			)
		)
	)
	(zone
		(net 136)
		(net_name "/Com Express 7 MGMT/~{TYPE0}")
		(layer "In5.Cu")
		(name "$teardrop_padvia$")
		(hatch none 0.1)
		(priority 30194)
		(attr
			(teardrop
				(type padvia)
			)
		)
		(connect_pads yes
			(clearance 0)
		)
		(min_thickness 0.0254)
		(filled_areas_thickness no)
		(fill yes
			(thermal_gap 0.5)
			(thermal_bridge_width 0.5)
			(island_removal_mode 1)
			(island_area_min 10)
		)
		(polygon
			(pts
				(xy 252.8865 133.010677) (xy 252.891318 132.941236) (xy 252.90504 132.889912) (xy 252.951755 132.81437)
				(xy 252.961299 132.802229) (xy 253.011081 132.735003) (xy 252.824 132.609) (xy 252.636919 132.735003)
				(xy 252.686701 132.802231) (xy 252.741106 132.885397) (xy 252.75619 132.938251) (xy 252.7615 133.010677)
			)
		)
	)
	(zone
		(net 743)
		(net_name "/2xSFP+/KR to SFI #2/TDO")
		(layer "In5.Cu")
		(name "$teardrop_padvia$")
		(hatch none 0.1)
		(priority 30158)
		(attr
			(teardrop
				(type padvia)
			)
		)
		(connect_pads yes
			(clearance 0)
		)
		(min_thickness 0.0254)
		(filled_areas_thickness no)
		(fill yes
			(thermal_gap 0.5)
			(thermal_bridge_width 0.5)
			(island_removal_mode 1)
			(island_area_min 10)
		)
		(polygon
			(pts
				(xy 135.249821 136.416792) (xy 135.208969 136.464181) (xy 135.183429 136.5072) (xy 135.15727 136.594462)
				(xy 135.140444 136.660139) (xy 135.102919 136.734997) (xy 135.289293 136.860707) (xy 135.477081 136.734997)
				(xy 135.418788 136.674961) (xy 135.387138 136.650537) (xy 135.345317 136.617307) (xy 135.316836 136.583967)
				(xy 135.311273 136.547573) (xy 135.338208 136.505179)
			)
		)
	)
	(zone
		(net 672)
		(net_name "/2xSFP+/KR to SFI #2/MDC")
		(layer "In5.Cu")
		(name "$teardrop_padvia$")
		(hatch none 0.1)
		(priority 30132)
		(attr
			(teardrop
				(type padvia)
			)
		)
		(connect_pads yes
			(clearance 0)
		)
		(min_thickness 0.0254)
		(filled_areas_thickness no)
		(fill yes
			(thermal_gap 0.5)
			(thermal_bridge_width 0.5)
			(island_removal_mode 1)
			(island_area_min 10)
		)
		(polygon
			(pts
				(xy 130.391241 139.192853) (xy 130.367985 139.162843) (xy 130.359642 139.135504) (xy 130.373908 139.089915)
				(xy 130.42132 139.036647) (xy 130.469666 138.984289) (xy 130.503583 138.92102) (xy 130.289293 138.859293)
				(xy 130.103793 138.985877) (xy 130.169868 139.099182) (xy 130.217196 139.181096) (xy 130.302853 139.281241)
			)
		)
	)
	(zone
		(net 758)
		(net_name "Net-(U45B-LS_OK_{IN_B})")
		(layer "In5.Cu")
		(name "$teardrop_padvia$")
		(hatch none 0.1)
		(priority 30206)
		(attr
			(teardrop
				(type padvia)
			)
		)
		(connect_pads yes
			(clearance 0)
		)
		(min_thickness 0.0254)
		(filled_areas_thickness no)
		(fill yes
			(thermal_gap 0.5)
			(thermal_bridge_width 0.5)
			(island_removal_mode 1)
			(island_area_min 10)
		)
		(polygon
			(pts
				(xy 127.8525 130.910677) (xy 127.857318 130.841236) (xy 127.87104 130.789912) (xy 127.917755 130.71437)
				(xy 127.927299 130.702229) (xy 127.977081 130.635003) (xy 127.79 130.509) (xy 127.602919 130.635003)
				(xy 127.652701 130.702231) (xy 127.707106 130.785397) (xy 127.72219 130.838251) (xy 127.7275 130.910677)
			)
		)
	)
	(zone
		(net 313)
		(net_name "/2xUSB3.0+RJ45/USB_1.D+")
		(layer "In5.Cu")
		(name "$teardrop_padvia$")
		(hatch none 0.1)
		(priority 30154)
		(attr
			(teardrop
				(type padvia)
			)
		)
		(connect_pads yes
			(clearance 0)
		)
		(min_thickness 0.0254)
		(filled_areas_thickness no)
		(fill yes
			(thermal_gap 0.5)
			(thermal_bridge_width 0.5)
			(island_removal_mode 1)
			(island_area_min 10)
		)
		(polygon
			(pts
				(xy 197.036 167.351084) (xy 197.040758 167.309513) (xy 197.054064 167.279455) (xy 197.098576 167.243353)
				(xy 197.140958 167.225803) (xy 197.222503 167.187081) (xy 197.0975 166.999) (xy 196.876823 167.043895)
				(xy 196.887325 167.120315) (xy 196.886886 167.180935) (xy 196.883774 167.218309) (xy 196.877 167.351084)
			)
		)
	)
	(zone
		(net 84)
		(net_name "/Com Express 7 MGMT/PWRBTN")
		(layer "In5.Cu")
		(name "$teardrop_padvia$")
		(hatch none 0.1)
		(priority 30222)
		(attr
			(teardrop
				(type padvia)
			)
		)
		(connect_pads yes
			(clearance 0)
		)
		(min_thickness 0.0254)
		(filled_areas_thickness no)
		(fill yes
			(thermal_gap 0.5)
			(thermal_bridge_width 0.5)
			(island_removal_mode 1)
			(island_area_min 10)
		)
		(polygon
			(pts
				(xy 182.150677 84.8375) (xy 182.081236 84.832682) (xy 182.029913 84.81896) (xy 181.954371 84.772246)
				(xy 181.942231 84.762701) (xy 181.875003 84.712919) (xy 181.749 84.9) (xy 181.875003 85.087081)
				(xy 181.942229 85.037299) (xy 182.025396 84.982894) (xy 182.078251 84.96781) (xy 182.150677 84.9625)
			)
		)
	)
	(zone
		(net 743)
		(net_name "/2xSFP+/KR to SFI #2/TDO")
		(layer "In5.Cu")
		(name "$teardrop_padvia$")
		(hatch none 0.1)
		(priority 30192)
		(attr
			(teardrop
				(type padvia)
			)
		)
		(connect_pads yes
			(clearance 0)
		)
		(min_thickness 0.0254)
		(filled_areas_thickness no)
		(fill yes
			(thermal_gap 0.5)
			(thermal_bridge_width 0.5)
			(island_removal_mode 1)
			(island_area_min 10)
		)
		(polygon
			(pts
				(xy 133.7025 130.540677) (xy 133.707318 130.471236) (xy 133.72104 130.419912) (xy 133.767755 130.34437)
				(xy 133.777299 130.332229) (xy 133.827081 130.265003) (xy 133.64 130.139) (xy 133.452919 130.265003)
				(xy 133.502701 130.332231) (xy 133.557106 130.415397) (xy 133.57219 130.468251) (xy 133.5775 130.540677)
			)
		)
	)
	(zone
		(net 345)
		(net_name "/Com Express 7 MGMT/SER0.RX")
		(layer "In5.Cu")
		(name "$teardrop_padvia$")
		(hatch none 0.1)
		(priority 30227)
		(attr
			(teardrop
				(type padvia)
			)
		)
		(connect_pads yes
			(clearance 0)
		)
		(min_thickness 0.0254)
		(filled_areas_thickness no)
		(fill yes
			(thermal_gap 0.5)
			(thermal_bridge_width 0.5)
			(island_removal_mode 1)
			(island_area_min 10)
		)
		(polygon
			(pts
				(xy 225.750677 170.2375) (xy 225.681236 170.232682) (xy 225.629913 170.21896) (xy 225.554371 170.172246)
				(xy 225.542231 170.162701) (xy 225.475003 170.112919) (xy 225.349 170.3) (xy 225.475003 170.487081)
				(xy 225.542229 170.437299) (xy 225.625396 170.382894) (xy 225.678251 170.36781) (xy 225.750677 170.3625)
			)
		)
	)
	(zone
		(net 573)
		(net_name "/GPIO expander/GPIOEX0")
		(layer "In5.Cu")
		(name "$teardrop_padvia$")
		(hatch none 0.1)
		(priority 30289)
		(attr
			(teardrop
				(type padvia)
			)
		)
		(connect_pads yes
			(clearance 0)
		)
		(min_thickness 0.0254)
		(filled_areas_thickness no)
		(fill yes
			(thermal_gap 0.5)
			(thermal_bridge_width 0.5)
			(island_removal_mode 1)
			(island_area_min 10)
		)
		(polygon
			(pts
				(xy 99.147515 77.049127) (xy 99.101819 76.996618) (xy 99.075231 76.950623) (xy 99.054847 76.864175)
				(xy 99.053011 76.84884) (xy 99.040677 76.766105) (xy 98.819293 76.809293) (xy 98.776105 77.030677)
				(xy 98.85884 77.043011) (xy 98.956119 77.063349) (xy 99.004159 77.090057) (xy 99.059127 77.137515)
			)
		)
	)
	(zone
		(net 490)
		(net_name "/2xSFP+/MDIO1.MDIO")
		(layer "In5.Cu")
		(name "$teardrop_padvia$")
		(hatch none 0.1)
		(priority 30161)
		(attr
			(teardrop
				(type padvia)
			)
		)
		(connect_pads yes
			(clearance 0)
		)
		(min_thickness 0.0254)
		(filled_areas_thickness no)
		(fill yes
			(thermal_gap 0.5)
			(thermal_bridge_width 0.5)
			(island_removal_mode 1)
			(island_area_min 10)
		)
		(polygon
			(pts
				(xy 138.674323 153.5725) (xy 138.748953 153.577387) (xy 138.803392 153.591599) (xy 138.892929 153.646498)
				(xy 138.949997 153.687081) (xy 139.076 153.5) (xy 138.949997 153.312919) (xy 138.875321 153.370692)
				(xy 138.796254 153.426019) (xy 138.744813 153.441845) (xy 138.674323 153.4475)
			)
		)
	)
	(zone
		(net 77)
		(net_name "+5V_AON")
		(layer "In5.Cu")
		(name "$teardrop_padvia$")
		(hatch none 0.1)
		(priority 30010)
		(attr
			(teardrop
				(type padvia)
			)
		)
		(connect_pads yes
			(clearance 0)
		)
		(min_thickness 0.0254)
		(filled_areas_thickness no)
		(fill yes
			(thermal_gap 0.5)
			(thermal_bridge_width 0.5)
			(island_removal_mode 1)
			(island_area_min 10)
		)
		(polygon
			(pts
				(xy 102.809323 73.665) (xy 102.887235 73.669713) (xy 102.94602 73.6827) (xy 103.037051 73.724802)
				(xy 103.122222 73.7675) (xy 103.211 73.565) (xy 103.122222 73.3625) (xy 103.03705 73.405199) (xy 102.944217 73.447867)
				(xy 102.886078 73.460444) (xy 102.809323 73.465)
			)
		)
	)
	(zone
		(net 742)
		(net_name "/2xSFP+/KR to SFI #2/TDI")
		(layer "In5.Cu")
		(name "$teardrop_padvia$")
		(hatch none 0.1)
		(priority 30189)
		(attr
			(teardrop
				(type padvia)
			)
		)
		(connect_pads yes
			(clearance 0)
		)
		(min_thickness 0.0254)
		(filled_areas_thickness no)
		(fill yes
			(thermal_gap 0.5)
			(thermal_bridge_width 0.5)
			(island_removal_mode 1)
			(island_area_min 10)
		)
		(polygon
			(pts
				(xy 135.0025 130.540677) (xy 135.007318 130.471236) (xy 135.02104 130.419912) (xy 135.067755 130.34437)
				(xy 135.077299 130.332229) (xy 135.127081 130.265003) (xy 134.94 130.139) (xy 134.752919 130.265003)
				(xy 134.802701 130.332231) (xy 134.857106 130.415397) (xy 134.87219 130.468251) (xy 134.8775 130.540677)
			)
		)
	)
	(zone
		(net 84)
		(net_name "/Com Express 7 MGMT/PWRBTN")
		(layer "In5.Cu")
		(name "$teardrop_padvia$")
		(hatch none 0.1)
		(priority 30178)
		(attr
			(teardrop
				(type padvia)
			)
		)
		(connect_pads yes
			(clearance 0)
		)
		(min_thickness 0.0254)
		(filled_areas_thickness no)
		(fill yes
			(thermal_gap 0.5)
			(thermal_bridge_width 0.5)
			(island_removal_mode 1)
			(island_area_min 10)
		)
		(polygon
			(pts
				(xy 222.749323 124.9725) (xy 222.818764 124.977318) (xy 222.870088 124.99104) (xy 222.945629 125.037755)
				(xy 222.957769 125.047299) (xy 223.024997 125.097081) (xy 223.151 124.91) (xy 223.024997 124.722919)
				(xy 222.957768 124.772702) (xy 222.874602 124.827106) (xy 222.821748 124.84219) (xy 222.749323 124.8475)
			)
		)
	)
	(zone
		(net 312)
		(net_name "/2xUSB3.0+RJ45/USB_1.D-")
		(layer "In5.Cu")
		(name "$teardrop_padvia$")
		(hatch none 0.1)
		(priority 30146)
		(attr
			(teardrop
				(type padvia)
			)
		)
		(connect_pads yes
			(clearance 0)
		)
		(min_thickness 0.0254)
		(filled_areas_thickness no)
		(fill yes
			(thermal_gap 0.5)
			(thermal_bridge_width 0.5)
			(island_removal_mode 1)
			(island_area_min 10)
		)
		(polygon
			(pts
				(xy 196.673 167.351084) (xy 196.666226 167.218309) (xy 196.661923 167.139838) (xy 196.673177 167.043895)
				(xy 196.4525 166.999) (xy 196.327497 167.187081) (xy 196.409042 167.225803) (xy 196.449848 167.242581)
				(xy 196.483215 167.264567) (xy 196.505736 167.29849) (xy 196.514 167.351084)
			)
		)
	)
	(zone
		(net 329)
		(net_name "/Com Express 7 Interfaces/PCIe_{B2Ax4}.TX2-")
		(layer "In5.Cu")
		(name "$teardrop_padvia$")
		(hatch none 0.1)
		(priority 30088)
		(attr
			(teardrop
				(type padvia)
			)
		)
		(connect_pads yes
			(clearance 0)
		)
		(min_thickness 0.0254)
		(filled_areas_thickness no)
		(fill yes
			(thermal_gap 0.5)
			(thermal_bridge_width 0.5)
			(island_removal_mode 1)
			(island_area_min 10)
		)
		(polygon
			(pts
				(xy 214.373 166.639416) (xy 214.379896 166.776751) (xy 214.384276 166.857939) (xy 214.372823 166.956105)
				(xy 214.5935 167.001) (xy 214.753189 166.847605) (xy 214.685691 166.798527) (xy 214.65719 166.784188)
				(xy 214.616571 166.762889) (xy 214.582738 166.736198) (xy 214.559583 166.697309) (xy 214.551 166.639416)
			)
		)
	)
	(zone
		(net 526)
		(net_name "/Backplane/~{PRSNT}")
		(layer "In5.Cu")
		(name "$teardrop_padvia$")
		(hatch none 0.1)
		(priority 30167)
		(attr
			(teardrop
				(type padvia)
			)
		)
		(connect_pads yes
			(clearance 0)
		)
		(min_thickness 0.0254)
		(filled_areas_thickness no)
		(fill yes
			(thermal_gap 0.5)
			(thermal_bridge_width 0.5)
			(island_removal_mode 1)
			(island_area_min 10)
		)
		(polygon
			(pts
				(xy 222.0375 133.159323) (xy 222.032682 133.228763) (xy 222.01896 133.280087) (xy 221.972245 133.355628)
				(xy 221.962702 133.367768) (xy 221.912919 133.434997) (xy 222.1 133.561) (xy 222.287081 133.434997)
				(xy 222.237299 133.367769) (xy 222.182894 133.284603) (xy 222.16781 133.231748) (xy 222.1625 133.159323)
			)
		)
	)
	(zone
		(net 375)
		(net_name "/2xUSB3.0+RJ45/USB_2.D+")
		(layer "In5.Cu")
		(name "$teardrop_padvia$")
		(hatch none 0.1)
		(priority 30121)
		(attr
			(teardrop
				(type padvia)
			)
		)
		(connect_pads yes
			(clearance 0)
		)
		(min_thickness 0.0254)
		(filled_areas_thickness no)
		(fill yes
			(thermal_gap 0.5)
			(thermal_bridge_width 0.5)
			(island_removal_mode 1)
			(island_area_min 10)
		)
		(polygon
			(pts
				(xy 154.998 123.346584) (xy 154.995484 123.165841) (xy 154.993677 123.001749) (xy 154.773 122.999)
				(xy 154.647997 123.187081) (xy 154.733589 123.225787) (xy 154.774472 123.241256) (xy 154.807994 123.26208)
				(xy 154.830667 123.294958) (xy 154.839 123.346584)
			)
		)
	)
	(zone
		(net 203)
		(net_name "/Backplane/PCIe_{REF}.CK+")
		(layer "In5.Cu")
		(name "$teardrop_padvia$")
		(hatch none 0.1)
		(priority 30101)
		(attr
			(teardrop
				(type padvia)
			)
		)
		(connect_pads yes
			(clearance 0)
		)
		(min_thickness 0.0254)
		(filled_areas_thickness no)
		(fill yes
			(thermal_gap 0.5)
			(thermal_bridge_width 0.5)
			(island_removal_mode 1)
			(island_area_min 10)
		)
		(polygon
			(pts
				(xy 259.176 137.456084) (xy 259.180759 137.413152) (xy 259.194072 137.381738) (xy 259.238959 137.342447)
				(xy 259.278471 137.323424) (xy 259.348003 137.287081) (xy 259.223 137.099) (xy 259.002323 137.10947)
				(xy 259.001698 137.289597) (xy 258.998 137.456084)
			)
		)
	)
	(zone
		(net 200)
		(net_name "/OCuLink/~{PERST_D0}")
		(layer "In5.Cu")
		(name "$teardrop_padvia$")
		(hatch none 0.1)
		(priority 30126)
		(attr
			(teardrop
				(type padvia)
			)
		)
		(connect_pads yes
			(clearance 0)
		)
		(min_thickness 0.0254)
		(filled_areas_thickness no)
		(fill yes
			(thermal_gap 0.5)
			(thermal_bridge_width 0.5)
			(island_removal_mode 1)
			(island_area_min 10)
		)
		(polygon
			(pts
				(xy 103.869127 161.802485) (xy 103.820397 161.844469) (xy 103.776963 161.868968) (xy 103.695157 161.886233)
				(xy 103.673715 161.887763) (xy 103.576105 161.899323) (xy 103.619293 162.120707) (xy 103.822261 162.208354)
				(xy 103.855226 162.09854) (xy 103.858021 162.084054) (xy 103.883239 161.992991) (xy 103.91101 161.944891)
				(xy 103.957515 161.890873)
			)
		)
	)
	(zone
		(net 65)
		(net_name "+12V")
		(layer "In5.Cu")
		(name "$teardrop_padvia$")
		(hatch none 0.1)
		(priority 30016)
		(attr
			(teardrop
				(type padvia)
			)
		)
		(connect_pads yes
			(clearance 0)
		)
		(min_thickness 0.0254)
		(filled_areas_thickness no)
		(fill yes
			(thermal_gap 0.5)
			(thermal_bridge_width 0.5)
			(island_removal_mode 1)
			(island_area_min 10)
		)
		(polygon
			(pts
				(xy 252.585678 87.349999) (xy 252.507766 87.345286) (xy 252.448982 87.332299) (xy 252.35795 87.290197)
				(xy 252.272779 87.247499) (xy 252.184001 87.449999) (xy 252.272779 87.652499) (xy 252.357948 87.609801)
				(xy 252.450783 87.567132) (xy 252.508922 87.554555) (xy 252.585678 87.549999)
			)
		)
	)
	(zone
		(net 649)
		(net_name "/2xSFP+/KR to SFI #1/MDIO")
		(layer "In5.Cu")
		(name "$teardrop_padvia$")
		(hatch none 0.1)
		(priority 30248)
		(attr
			(teardrop
				(type padvia)
			)
		)
		(connect_pads yes
			(clearance 0)
		)
		(min_thickness 0.0254)
		(filled_areas_thickness no)
		(fill yes
			(thermal_gap 0.5)
			(thermal_bridge_width 0.5)
			(island_removal_mode 1)
			(island_area_min 10)
		)
		(polygon
			(pts
				(xy 143.339127 142.77465) (xy 143.286618 142.820346) (xy 143.240623 142.846933) (xy 143.154174 142.867317)
				(xy 143.138841 142.869153) (xy 143.056105 142.881488) (xy 143.099293 143.102872) (xy 143.320677 143.14606)
				(xy 143.333011 143.063325) (xy 143.353349 142.966046) (xy 143.380057 142.918006) (xy 143.427515 142.863038)
			)
		)
	)
	(zone
		(net 62)
		(net_name "+12V_AON")
		(layer "In5.Cu")
		(name "$teardrop_padvia$")
		(hatch none 0.1)
		(priority 30020)
		(attr
			(teardrop
				(type padvia)
			)
		)
		(connect_pads yes
			(clearance 0)
		)
		(min_thickness 0.0254)
		(filled_areas_thickness no)
		(fill yes
			(thermal_gap 0.5)
			(thermal_bridge_width 0.5)
			(island_removal_mode 1)
			(island_area_min 10)
		)
		(polygon
			(pts
				(xy 198.94622 69.198132) (xy 198.887796 69.249891) (xy 198.837046 69.282273) (xy 198.742909 69.316871)
				(xy 198.65249 69.346904) (xy 198.732903 69.55287) (xy 198.938867 69.633284) (xy 198.9689 69.542866)
				(xy 199.004372 69.447052) (xy 199.036589 69.397048) (xy 199.087641 69.339553)
			)
		)
	)
	(zone
		(net 259)
		(net_name "/Com Express 7 Interfaces/PCIe_{B2Bx4}.TX1+")
		(layer "In5.Cu")
		(name "$teardrop_padvia$")
		(hatch none 0.1)
		(priority 30066)
		(attr
			(teardrop
				(type padvia)
			)
		)
		(connect_pads yes
			(clearance 0)
		)
		(min_thickness 0.0254)
		(filled_areas_thickness no)
		(fill yes
			(thermal_gap 0.5)
			(thermal_bridge_width 0.5)
			(island_removal_mode 1)
			(island_area_min 10)
		)
		(polygon
			(pts
				(xy 189.639416 166.676) (xy 189.684146 166.680741) (xy 189.717611 166.693931) (xy 189.761124 166.738694)
				(xy 189.784188 166.78219) (xy 189.810165 166.831127) (xy 189.847605 166.878189) (xy 190.001 166.7185)
				(xy 189.956105 166.497823) (xy 189.87904 166.508447) (xy 189.817337 166.508182) (xy 189.776751 166.504896)
				(xy 189.639416 166.498)
			)
		)
	)
	(zone
		(net 326)
		(net_name "/Com Express 7 Interfaces/PCIe_{B2Ax4}.TX1+")
		(layer "In5.Cu")
		(name "$teardrop_padvia$")
		(hatch none 0.1)
		(priority 30052)
		(attr
			(teardrop
				(type padvia)
			)
		)
		(connect_pads yes
			(clearance 0)
		)
		(min_thickness 0.0254)
		(filled_areas_thickness no)
		(fill yes
			(thermal_gap 0.5)
			(thermal_bridge_width 0.5)
			(island_removal_mode 1)
			(island_area_min 10)
		)
		(polygon
			(pts
				(xy 212.499 166.639416) (xy 212.494259 166.684146) (xy 212.481069 166.71761) (xy 212.436306 166.761123)
				(xy 212.39281 166.784187) (xy 212.343872 166.810164) (xy 212.29681 166.847605) (xy 212.4565 167.001)
				(xy 212.677177 166.956105) (xy 212.666552 166.879042) (xy 212.666818 166.817339) (xy 212.670104 166.776751)
				(xy 212.677 166.639416)
			)
		)
	)
	(zone
		(net 269)
		(net_name "/Com Express 7 Interfaces/PCIe_{B2Bx4}.TX0+")
		(layer "In5.Cu")
		(name "$teardrop_padvia$")
		(hatch none 0.1)
		(priority 30064)
		(attr
			(teardrop
				(type padvia)
			)
		)
		(connect_pads yes
			(clearance 0)
		)
		(min_thickness 0.0254)
		(filled_areas_thickness no)
		(fill yes
			(thermal_gap 0.5)
			(thermal_bridge_width 0.5)
			(island_removal_mode 1)
			(island_area_min 10)
		)
		(polygon
			(pts
				(xy 190.789416 165.376) (xy 190.834146 165.380741) (xy 190.867611 165.393931) (xy 190.911124 165.438694)
				(xy 190.934188 165.48219) (xy 190.960165 165.531127) (xy 190.997605 165.578189) (xy 191.151 165.4185)
				(xy 191.106105 165.197823) (xy 191.02904 165.208447) (xy 190.967337 165.208182) (xy 190.926751 165.204896)
				(xy 190.789416 165.198)
			)
		)
	)
	(zone
		(net 252)
		(net_name "/Com Express 7 Interfaces/PCIe_{B2Bx4}.RX1-")
		(layer "In5.Cu")
		(name "$teardrop_padvia$")
		(hatch none 0.1)
		(priority 30059)
		(attr
			(teardrop
				(type padvia)
			)
		)
		(connect_pads yes
			(clearance 0)
		)
		(min_thickness 0.0254)
		(filled_areas_thickness no)
		(fill yes
			(thermal_gap 0.5)
			(thermal_bridge_width 0.5)
			(island_removal_mode 1)
			(island_area_min 10)
		)
		(polygon
			(pts
				(xy 187.160584 124.024) (xy 187.115854 124.019259) (xy 187.082389 124.006069) (xy 187.038876 123.961306)
				(xy 187.015811 123.917809) (xy 186.989834 123.868871) (xy 186.952394 123.82181) (xy 186.799 123.9815)
				(xy 186.843895 124.202177) (xy 186.920958 124.191552) (xy 186.98266 124.191818) (xy 187.023248 124.195104)
				(xy 187.160584 124.202)
			)
		)
	)
	(zone
		(net 49)
		(net_name "/2xUSB3.0+RJ45/USBSS_2.TX-")
		(layer "In5.Cu")
		(name "$teardrop_padvia$")
		(hatch none 0.1)
		(priority 30151)
		(attr
			(teardrop
				(type padvia)
			)
		)
		(connect_pads yes
			(clearance 0)
		)
		(min_thickness 0.0254)
		(filled_areas_thickness no)
		(fill yes
			(thermal_gap 0.5)
			(thermal_bridge_width 0.5)
			(island_removal_mode 1)
			(island_area_min 10)
		)
		(polygon
			(pts
				(xy 181.514 149.223916) (xy 181.509242 149.265486) (xy 181.495936 149.295544) (xy 181.451424 149.331646)
				(xy 181.409043 149.349196) (xy 181.327497 149.387919) (xy 181.4525 149.576) (xy 181.673177 149.531105)
				(xy 181.662675 149.454686) (xy 181.663114 149.394066) (xy 181.666226 149.35669) (xy 181.673 149.223916)
			)
		)
	)
	(zone
		(net 325)
		(net_name "/Com Express 7 Interfaces/PCIe_{B2Ax4}.TX0-")
		(layer "In5.Cu")
		(name "$teardrop_padvia$")
		(hatch none 0.1)
		(priority 30086)
		(attr
			(teardrop
				(type padvia)
			)
		)
		(connect_pads yes
			(clearance 0)
		)
		(min_thickness 0.0254)
		(filled_areas_thickness no)
		(fill yes
			(thermal_gap 0.5)
			(thermal_bridge_width 0.5)
			(island_removal_mode 1)
			(island_area_min 10)
		)
		(polygon
			(pts
				(xy 211.373 166.639416) (xy 211.379896 166.776751) (xy 211.384276 166.857939) (xy 211.372823 166.956105)
				(xy 211.5935 167.001) (xy 211.753189 166.847605) (xy 211.685691 166.798527) (xy 211.65719 166.784188)
				(xy 211.616571 166.762889) (xy 211.582738 166.736198) (xy 211.559583 166.697309) (xy 211.551 166.639416)
			)
		)
	)
	(zone
		(net 527)
		(net_name "/Backplane/GPIO")
		(layer "In5.Cu")
		(name "$teardrop_padvia$")
		(hatch none 0.1)
		(priority 30163)
		(attr
			(teardrop
				(type padvia)
			)
		)
		(connect_pads yes
			(clearance 0)
		)
		(min_thickness 0.0254)
		(filled_areas_thickness no)
		(fill yes
			(thermal_gap 0.5)
			(thermal_bridge_width 0.5)
			(island_removal_mode 1)
			(island_area_min 10)
		)
		(polygon
			(pts
				(xy 129.0875 89.589324) (xy 129.082682 89.658764) (xy 129.06896 89.710088) (xy 129.022245 89.785629)
				(xy 129.012702 89.797769) (xy 128.962919 89.864998) (xy 129.15 89.991001) (xy 129.337081 89.864998)
				(xy 129.287299 89.79777) (xy 129.232894 89.714604) (xy 129.21781 89.661749) (xy 129.2125 89.589324)
			)
		)
	)
	(zone
		(net 544)
		(net_name "Net-(Q10-E)")
		(layer "In5.Cu")
		(name "$teardrop_padvia$")
		(hatch none 0.1)
		(priority 30179)
		(attr
			(teardrop
				(type padvia)
			)
		)
		(connect_pads yes
			(clearance 0)
		)
		(min_thickness 0.0254)
		(filled_areas_thickness no)
		(fill yes
			(thermal_gap 0.5)
			(thermal_bridge_width 0.5)
			(island_removal_mode 1)
			(island_area_min 10)
		)
		(polygon
			(pts
				(xy 315.599323 113.6715) (xy 315.668764 113.676318) (xy 315.720088 113.69004) (xy 315.795629 113.736755)
				(xy 315.807769 113.746299) (xy 315.874997 113.796081) (xy 316.001 113.609) (xy 315.874997 113.421919)
				(xy 315.807768 113.471702) (xy 315.724602 113.526106) (xy 315.671748 113.54119) (xy 315.599323 113.5465)
			)
		)
	)
	(zone
		(net 728)
		(net_name "Net-(U43C-AMUXA)")
		(layer "In5.Cu")
		(name "$teardrop_padvia$")
		(hatch none 0.1)
		(priority 30210)
		(attr
			(teardrop
				(type padvia)
			)
		)
		(connect_pads yes
			(clearance 0)
		)
		(min_thickness 0.0254)
		(filled_areas_thickness no)
		(fill yes
			(thermal_gap 0.5)
			(thermal_bridge_width 0.5)
			(island_removal_mode 1)
			(island_area_min 10)
		)
		(polygon
			(pts
				(xy 147.9625 130.540677) (xy 147.967318 130.471236) (xy 147.98104 130.419912) (xy 148.027755 130.34437)
				(xy 148.037299 130.332229) (xy 148.087081 130.265003) (xy 147.9 130.139) (xy 147.712919 130.265003)
				(xy 147.762701 130.332231) (xy 147.817106 130.415397) (xy 147.83219 130.468251) (xy 147.8375 130.540677)
			)
		)
	)
	(zone
		(net 328)
		(net_name "/Com Express 7 Interfaces/PCIe_{B2Ax4}.TX2+")
		(layer "In5.Cu")
		(name "$teardrop_padvia$")
		(hatch none 0.1)
		(priority 30107)
		(attr
			(teardrop
				(type padvia)
			)
		)
		(connect_pads yes
			(clearance 0)
		)
		(min_thickness 0.0254)
		(filled_areas_thickness no)
		(fill yes
			(thermal_gap 0.5)
			(thermal_bridge_width 0.5)
			(island_removal_mode 1)
			(island_area_min 10)
		)
		(polygon
			(pts
				(xy 230.852 147.156084) (xy 230.848302 146.989599) (xy 230.847677 146.80947) (xy 230.627 146.799)
				(xy 230.501997 146.987081) (xy 230.571529 147.023424) (xy 230.611495 147.042701) (xy 230.644058 147.066786)
				(xy 230.665974 147.102356) (xy 230.674 147.156084)
			)
		)
	)
	(zone
		(net 724)
		(net_name "/2xSFP+/KR to SFI #1/TMS")
		(layer "In5.Cu")
		(name "$teardrop_padvia$")
		(hatch none 0.1)
		(priority 30215)
		(attr
			(teardrop
				(type padvia)
			)
		)
		(connect_pads yes
			(clearance 0)
		)
		(min_thickness 0.0254)
		(filled_areas_thickness no)
		(fill yes
			(thermal_gap 0.5)
			(thermal_bridge_width 0.5)
			(island_removal_mode 1)
			(island_area_min 10)
		)
		(polygon
			(pts
				(xy 153.8125 130.910677) (xy 153.817318 130.841236) (xy 153.83104 130.789912) (xy 153.877755 130.71437)
				(xy 153.887299 130.702229) (xy 153.937081 130.635003) (xy 153.75 130.509) (xy 153.562919 130.635003)
				(xy 153.612701 130.702231) (xy 153.667106 130.785397) (xy 153.68219 130.838251) (xy 153.6875 130.910677)
			)
		)
	)
	(zone
		(net 528)
		(net_name "/Backplane/~{PERST}")
		(layer "In5.Cu")
		(name "$teardrop_padvia$")
		(hatch none 0.1)
		(priority 30198)
		(attr
			(teardrop
				(type padvia)
			)
		)
		(connect_pads yes
			(clearance 0)
		)
		(min_thickness 0.0254)
		(filled_areas_thickness no)
		(fill yes
			(thermal_gap 0.5)
			(thermal_bridge_width 0.5)
			(island_removal_mode 1)
			(island_area_min 10)
		)
		(polygon
			(pts
				(xy 158.6125 150.710677) (xy 158.617318 150.641236) (xy 158.63104 150.589912) (xy 158.677755 150.51437)
				(xy 158.687299 150.502229) (xy 158.737081 150.435003) (xy 158.55 150.309) (xy 158.362919 150.435003)
				(xy 158.412701 150.502231) (xy 158.467106 150.585397) (xy 158.48219 150.638251) (xy 158.4875 150.710677)
			)
		)
	)
	(zone
		(net 372)
		(net_name "/Com Express 7 MGMT/I2C.SDA")
		(layer "In5.Cu")
		(name "$teardrop_padvia$")
		(hatch none 0.1)
		(priority 30208)
		(attr
			(teardrop
				(type padvia)
			)
		)
		(connect_pads yes
			(clearance 0)
		)
		(min_thickness 0.0254)
		(filled_areas_thickness no)
		(fill yes
			(thermal_gap 0.5)
			(thermal_bridge_width 0.5)
			(island_removal_mode 1)
			(island_area_min 10)
		)
		(polygon
			(pts
				(xy 302.8875 108.640677) (xy 302.892318 108.571236) (xy 302.90604 108.519912) (xy 302.952755 108.44437)
				(xy 302.962299 108.432229) (xy 303.012081 108.365003) (xy 302.825 108.239) (xy 302.637919 108.365003)
				(xy 302.687701 108.432231) (xy 302.742106 108.515397) (xy 302.75719 108.568251) (xy 302.7625 108.640677)
			)
		)
	)
	(zone
		(net 339)
		(net_name "/Com Express 7 Interfaces/SDIO.CLK")
		(layer "In5.Cu")
		(name "$teardrop_padvia$")
		(hatch none 0.1)
		(priority 30039)
		(attr
			(teardrop
				(type padvia)
			)
		)
		(connect_pads yes
			(clearance 0)
		)
		(min_thickness 0.0254)
		(filled_areas_thickness no)
		(fill yes
			(thermal_gap 0.5)
			(thermal_bridge_width 0.5)
			(island_removal_mode 1)
			(island_area_min 10)
		)
		(polygon
			(pts
				(xy 113.970677 133.7325) (xy 113.902314 133.727809) (xy 113.85003 133.714974) (xy 113.760652 133.666057)
				(xy 113.657778 133.6075) (xy 113.569 133.81) (xy 113.657778 134.0125) (xy 113.760651 133.953943)
				(xy 113.844447 133.907067) (xy 113.898713 133.892761) (xy 113.970677 133.8875)
			)
		)
	)
	(zone
		(net 78)
		(net_name "+1V8")
		(layer "In5.Cu")
		(name "$teardrop_padvia$")
		(hatch none 0.1)
		(priority 30013)
		(attr
			(teardrop
				(type padvia)
			)
		)
		(connect_pads yes
			(clearance 0)
		)
		(min_thickness 0.0254)
		(filled_areas_thickness no)
		(fill yes
			(thermal_gap 0.5)
			(thermal_bridge_width 0.5)
			(island_removal_mode 1)
			(island_area_min 10)
		)
		(polygon
			(pts
				(xy 204.009287 75.702163) (xy 203.931375 75.69745) (xy 203.872591 75.684463) (xy 203.781559 75.642361)
				(xy 203.696388 75.599663) (xy 203.60761 75.802163) (xy 203.696388 76.004663) (xy 203.781557 75.961965)
				(xy 203.874392 75.919296) (xy 203.932531 75.906719) (xy 204.009287 75.902163)
			)
		)
	)
	(zone
		(net 254)
		(net_name "/Com Express 7 Interfaces/PCIe_{B2Bx4}.RX1+")
		(layer "In5.Cu")
		(name "$teardrop_padvia$")
		(hatch none 0.1)
		(priority 30091)
		(attr
			(teardrop
				(type padvia)
			)
		)
		(connect_pads yes
			(clearance 0)
		)
		(min_thickness 0.0254)
		(filled_areas_thickness no)
		(fill yes
			(thermal_gap 0.5)
			(thermal_bridge_width 0.5)
			(island_removal_mode 1)
			(island_area_min 10)
		)
		(polygon
			(pts
				(xy 187.160584 124.398) (xy 187.023248 124.404896) (xy 186.942061 124.409276) (xy 186.843895 124.397823)
				(xy 186.799 124.6185) (xy 186.952394 124.778189) (xy 187.001472 124.710692) (xy 187.015811 124.68219)
				(xy 187.03711 124.641571) (xy 187.063802 124.607738) (xy 187.102691 124.584583) (xy 187.160584 124.576)
			)
		)
	)
	(zone
		(net 242)
		(net_name "/Com Express 7 Interfaces/PCIe_{B2Bx4}.TX3+")
		(layer "In5.Cu")
		(name "$teardrop_padvia$")
		(hatch none 0.1)
		(priority 30057)
		(attr
			(teardrop
				(type padvia)
			)
		)
		(connect_pads yes
			(clearance 0)
		)
		(min_thickness 0.0254)
		(filled_areas_thickness no)
		(fill yes
			(thermal_gap 0.5)
			(thermal_bridge_width 0.5)
			(island_removal_mode 1)
			(island_area_min 10)
		)
		(polygon
			(pts
				(xy 186.499 166.639416) (xy 186.494259 166.684146) (xy 186.481069 166.71761) (xy 186.436306 166.761123)
				(xy 186.39281 166.784187) (xy 186.343872 166.810164) (xy 186.29681 166.847605) (xy 186.4565 167.001)
				(xy 186.677177 166.956105) (xy 186.666552 166.879042) (xy 186.666818 166.817339) (xy 186.670104 166.776751)
				(xy 186.677 166.639416)
			)
		)
	)
	(zone
		(net 400)
		(net_name "/Com Express 7 MGMT/FAN_PWM")
		(layer "In5.Cu")
		(name "$teardrop_padvia$")
		(hatch none 0.1)
		(priority 30181)
		(attr
			(teardrop
				(type padvia)
			)
		)
		(connect_pads yes
			(clearance 0)
		)
		(min_thickness 0.0254)
		(filled_areas_thickness no)
		(fill yes
			(thermal_gap 0.5)
			(thermal_bridge_width 0.5)
			(island_removal_mode 1)
			(island_area_min 10)
		)
		(polygon
			(pts
				(xy 241.020031 77.2475) (xy 241.089472 77.252318) (xy 241.140796 77.26604) (xy 241.216337 77.312755)
				(xy 241.228477 77.322299) (xy 241.295705 77.372081) (xy 241.421708 77.185) (xy 241.295705 76.997919)
				(xy 241.228476 77.047702) (xy 241.14531 77.102106) (xy 241.092456 77.11719) (xy 241.020031 77.1225)
			)
		)
	)
	(zone
		(net 14)
		(net_name "/Com Express 7 Interfaces/PCIe_{B1x2}.RX0+")
		(layer "In5.Cu")
		(name "$teardrop_padvia$")
		(hatch none 0.1)
		(priority 30054)
		(attr
			(teardrop
				(type padvia)
			)
		)
		(connect_pads yes
			(clearance 0)
		)
		(min_thickness 0.0254)
		(filled_areas_thickness no)
		(fill yes
			(thermal_gap 0.5)
			(thermal_bridge_width 0.5)
			(island_removal_mode 1)
			(island_area_min 10)
		)
		(polygon
			(pts
				(xy 202.999 163.989416) (xy 202.994259 164.034146) (xy 202.981069 164.06761) (xy 202.936306 164.111123)
				(xy 202.89281 164.134187) (xy 202.843872 164.160164) (xy 202.79681 164.197605) (xy 202.9565 164.351)
				(xy 203.177177 164.306105) (xy 203.166552 164.229042) (xy 203.166818 164.167339) (xy 203.170104 164.126751)
				(xy 203.177 163.989416)
			)
		)
	)
	(zone
		(net 303)
		(net_name "/Com Express 7 MGMT/~{SUS_S5}")
		(layer "In5.Cu")
		(name "$teardrop_padvia$")
		(hatch none 0.1)
		(priority 30183)
		(attr
			(teardrop
				(type padvia)
			)
		)
		(connect_pads yes
			(clearance 0)
		)
		(min_thickness 0.0254)
		(filled_areas_thickness no)
		(fill yes
			(thermal_gap 0.5)
			(thermal_bridge_width 0.5)
			(island_removal_mode 1)
			(island_area_min 10)
		)
		(polygon
			(pts
				(xy 166.849323 141.9375) (xy 166.918764 141.942318) (xy 166.970088 141.95604) (xy 167.045629 142.002755)
				(xy 167.057769 142.012299) (xy 167.124997 142.062081) (xy 167.251 141.875) (xy 167.124997 141.687919)
				(xy 167.057768 141.737702) (xy 166.974602 141.792106) (xy 166.921748 141.80719) (xy 166.849323 141.8125)
			)
		)
	)
	(zone
		(net 242)
		(net_name "/Com Express 7 Interfaces/PCIe_{B2Bx4}.TX3+")
		(layer "In5.Cu")
		(name "$teardrop_padvia$")
		(hatch none 0.1)
		(priority 30079)
		(attr
			(teardrop
				(type padvia)
			)
		)
		(connect_pads yes
			(clearance 0)
		)
		(min_thickness 0.0254)
		(filled_areas_thickness no)
		(fill yes
			(thermal_gap 0.5)
			(thermal_bridge_width 0.5)
			(island_removal_mode 1)
			(island_area_min 10)
		)
		(polygon
			(pts
				(xy 173.939416 95.512) (xy 174.076751 95.505104) (xy 174.157939 95.500724) (xy 174.256105 95.512177)
				(xy 174.301 95.2915) (xy 174.147605 95.13181) (xy 174.098527 95.199306) (xy 174.084187 95.22781)
				(xy 174.062888 95.268429) (xy 174.036197 95.302262) (xy 173.997308 95.325417) (xy 173.939416 95.334)
			)
		)
	)
	(zone
		(net 161)
		(net_name "/2xUSB3.0+RJ45/USBSS_2.RX+")
		(layer "In5.Cu")
		(name "$teardrop_padvia$")
		(hatch none 0.1)
		(priority 30141)
		(attr
			(teardrop
				(type padvia)
			)
		)
		(connect_pads yes
			(clearance 0)
		)
		(min_thickness 0.0254)
		(filled_areas_thickness no)
		(fill yes
			(thermal_gap 0.5)
			(thermal_bridge_width 0.5)
			(island_removal_mode 1)
			(island_area_min 10)
		)
		(polygon
			(pts
				(xy 127.927 107.398916) (xy 127.933774 107.53169) (xy 127.938077 107.610162) (xy 127.926823 107.706105)
				(xy 128.1475 107.751) (xy 128.272503 107.562919) (xy 128.190957 107.524196) (xy 128.150152 107.507418)
				(xy 128.116785 107.485433) (xy 128.094264 107.451509) (xy 128.086 107.398916)
			)
		)
	)
	(zone
		(net 740)
		(net_name "Net-(U45C-REFCLK1+)")
		(layer "In5.Cu")
		(name "$teardrop_padvia$")
		(hatch none 0.1)
		(priority 30261)
		(attr
			(teardrop
				(type padvia)
			)
		)
		(connect_pads yes
			(clearance 0)
		)
		(min_thickness 0.0254)
		(filled_areas_thickness no)
		(fill yes
			(thermal_gap 0.5)
			(thermal_bridge_width 0.5)
			(island_removal_mode 1)
			(island_area_min 10)
		)
		(polygon
			(pts
				(xy 128.962485 139.620873) (xy 129.008181 139.673382) (xy 129.034768 139.719376) (xy 129.055152 139.805825)
				(xy 129.056988 139.821158) (xy 129.069323 139.903895) (xy 129.290707 139.860707) (xy 129.333895 139.639323)
				(xy 129.251158 139.626988) (xy 129.15388 139.606651) (xy 129.10584 139.579943) (xy 129.050873 139.532485)
			)
		)
	)
	(zone
		(net 136)
		(net_name "/Com Express 7 MGMT/~{TYPE0}")
		(layer "In5.Cu")
		(name "$teardrop_padvia$")
		(hatch none 0.1)
		(priority 30223)
		(attr
			(teardrop
				(type padvia)
			)
		)
		(connect_pads yes
			(clearance 0)
		)
		(min_thickness 0.0254)
		(filled_areas_thickness no)
		(fill yes
			(thermal_gap 0.5)
			(thermal_bridge_width 0.5)
			(island_removal_mode 1)
			(island_area_min 10)
		)
		(polygon
			(pts
				(xy 242.750677 152.9875) (xy 242.681236 152.982682) (xy 242.629913 152.96896) (xy 242.554371 152.922246)
				(xy 242.542231 152.912701) (xy 242.475003 152.862919) (xy 242.349 153.05) (xy 242.475003 153.237081)
				(xy 242.542229 153.187299) (xy 242.625396 153.132894) (xy 242.678251 153.11781) (xy 242.750677 153.1125)
			)
		)
	)
	(zone
		(net 740)
		(net_name "Net-(U45C-REFCLK1+)")
		(layer "In5.Cu")
		(name "$teardrop_padvia$")
		(hatch none 0.1)
		(priority 30275)
		(attr
			(teardrop
				(type padvia)
			)
		)
		(connect_pads yes
			(clearance 0)
		)
		(min_thickness 0.0254)
		(filled_areas_thickness no)
		(fill yes
			(thermal_gap 0.5)
			(thermal_bridge_width 0.5)
			(island_removal_mode 1)
			(island_area_min 10)
		)
		(polygon
			(pts
				(xy 126.940873 130.487515) (xy 126.993382 130.441819) (xy 127.039376 130.415231) (xy 127.125824 130.394847)
				(xy 127.14116 130.393011) (xy 127.223895 130.380677) (xy 127.180707 130.159293) (xy 126.959323 130.116105)
				(xy 126.946988 130.198841) (xy 126.926651 130.296119) (xy 126.899943 130.344159) (xy 126.852485 130.399127)
			)
		)
	)
	(zone
		(net 65)
		(net_name "+12V")
		(layer "In5.Cu")
		(name "$teardrop_padvia$")
		(hatch none 0.1)
		(priority 30022)
		(attr
			(teardrop
				(type padvia)
			)
		)
		(connect_pads yes
			(clearance 0)
		)
		(min_thickness 0.0254)
		(filled_areas_thickness no)
		(fill yes
			(thermal_gap 0.5)
			(thermal_bridge_width 0.5)
			(island_removal_mode 1)
			(island_area_min 10)
		)
		(polygon
			(pts
				(xy 193.92122 73.748132) (xy 193.862796 73.799891) (xy 193.812046 73.832273) (xy 193.717909 73.866871)
				(xy 193.62749 73.896904) (xy 193.707903 74.10287) (xy 193.913867 74.183284) (xy 193.9439 74.092866)
				(xy 193.979372 73.997052) (xy 194.011589 73.947048) (xy 194.062641 73.889553)
			)
		)
	)
	(zone
		(net 722)
		(net_name "/2xSFP+/KR to SFI #1/TDI")
		(layer "In5.Cu")
		(name "$teardrop_padvia$")
		(hatch none 0.1)
		(priority 30230)
		(attr
			(teardrop
				(type padvia)
			)
		)
		(connect_pads yes
			(clearance 0)
		)
		(min_thickness 0.0254)
		(filled_areas_thickness no)
		(fill yes
			(thermal_gap 0.5)
			(thermal_bridge_width 0.5)
			(island_removal_mode 1)
			(island_area_min 10)
		)
		(polygon
			(pts
				(xy 154.689127 138.532485) (xy 154.636618 138.578181) (xy 154.590623 138.604768) (xy 154.504174 138.625152)
				(xy 154.488841 138.626988) (xy 154.406105 138.639323) (xy 154.449293 138.860707) (xy 154.670677 138.903895)
				(xy 154.683011 138.82116) (xy 154.703349 138.723881) (xy 154.730057 138.675841) (xy 154.777515 138.620873)
			)
		)
	)
	(zone
		(net 372)
		(net_name "/Com Express 7 MGMT/I2C.SDA")
		(layer "In5.Cu")
		(name "$teardrop_padvia$")
		(hatch none 0.1)
		(priority 30254)
		(attr
			(teardrop
				(type padvia)
			)
		)
		(connect_pads yes
			(clearance 0)
		)
		(min_thickness 0.0254)
		(filled_areas_thickness no)
		(fill yes
			(thermal_gap 0.5)
			(thermal_bridge_width 0.5)
			(island_removal_mode 1)
			(island_area_min 10)
		)
		(polygon
			(pts
				(xy 302.497485 94.450873) (xy 302.543181 94.503382) (xy 302.569768 94.549376) (xy 302.590152 94.635825)
				(xy 302.591988 94.651158) (xy 302.604323 94.733895) (xy 302.825707 94.690707) (xy 302.868895 94.469323)
				(xy 302.786158 94.456988) (xy 302.68888 94.436651) (xy 302.64084 94.409943) (xy 302.585873 94.362485)
			)
		)
	)
	(zone
		(net 16)
		(net_name "/Com Express 7 Interfaces/PCIe_{B1x2}.RX0-")
		(layer "In5.Cu")
		(name "$teardrop_padvia$")
		(hatch none 0.1)
		(priority 30098)
		(attr
			(teardrop
				(type padvia)
			)
		)
		(connect_pads yes
			(clearance 0)
		)
		(min_thickness 0.0254)
		(filled_areas_thickness no)
		(fill yes
			(thermal_gap 0.5)
			(thermal_bridge_width 0.5)
			(island_removal_mode 1)
			(island_area_min 10)
		)
		(polygon
			(pts
				(xy 206.276 131.756084) (xy 206.280759 131.713152) (xy 206.294072 131.681738) (xy 206.338959 131.642447)
				(xy 206.378471 131.623424) (xy 206.448003 131.587081) (xy 206.323 131.399) (xy 206.102323 131.40947)
				(xy 206.101698 131.589597) (xy 206.098 131.756084)
			)
		)
	)
	(zone
		(net 754)
		(net_name "Net-(U45A-LOSA)")
		(layer "In5.Cu")
		(name "$teardrop_padvia$")
		(hatch none 0.1)
		(priority 30128)
		(attr
			(teardrop
				(type padvia)
			)
		)
		(connect_pads yes
			(clearance 0)
		)
		(min_thickness 0.0254)
		(filled_areas_thickness no)
		(fill yes
			(thermal_gap 0.5)
			(thermal_bridge_width 0.5)
			(island_removal_mode 1)
			(island_area_min 10)
		)
		(polygon
			(pts
				(xy 133.954985 139.628373) (xy 133.998576 139.678586) (xy 134.025537 139.723616) (xy 134.052715 139.821806)
				(xy 134.064424 139.879432) (xy 134.087012 139.946601) (xy 134.290707 139.860707) (xy 134.333895 139.639323)
				(xy 134.239643 139.627421) (xy 134.144708 139.610844) (xy 134.097162 139.585747) (xy 134.043373 139.539985)
			)
		)
	)
	(zone
		(net 52)
		(net_name "+5V")
		(layer "In5.Cu")
		(name "$teardrop_padvia$")
		(hatch none 0.1)
		(priority 30212)
		(attr
			(teardrop
				(type padvia)
			)
		)
		(connect_pads yes
			(clearance 0)
		)
		(min_thickness 0.0254)
		(filled_areas_thickness no)
		(fill yes
			(thermal_gap 0.5)
			(thermal_bridge_width 0.5)
			(island_removal_mode 1)
			(island_area_min 10)
		)
		(polygon
			(pts
				(xy 262.973208 76.160677) (xy 262.978026 76.091236) (xy 262.991748 76.039912) (xy 263.038463 75.96437)
				(xy 263.048007 75.952229) (xy 263.097789 75.885003) (xy 262.910708 75.759) (xy 262.723627 75.885003)
				(xy 262.773409 75.952231) (xy 262.827814 76.035397) (xy 262.842898 76.088251) (xy 262.848208 76.160677)
			)
		)
	)
	(zone
		(net 755)
		(net_name "Net-(U45A-LS_OK_{IN_A})")
		(layer "In5.Cu")
		(name "$teardrop_padvia$")
		(hatch none 0.1)
		(priority 30114)
		(attr
			(teardrop
				(type padvia)
			)
		)
		(connect_pads yes
			(clearance 0)
		)
		(min_thickness 0.0254)
		(filled_areas_thickness no)
		(fill yes
			(thermal_gap 0.5)
			(thermal_bridge_width 0.5)
			(island_removal_mode 1)
			(island_area_min 10)
		)
		(polygon
			(pts
				(xy 137.546627 140.549985) (xy 137.499997 140.589893) (xy 137.457988 140.613136) (xy 137.378777 140.628343)
				(xy 137.352754 140.629237) (xy 137.246105 140.639323) (xy 137.289293 140.860707) (xy 137.490161 140.953422)
				(xy 137.53019 140.83079) (xy 137.55884 140.740549) (xy 137.587806 140.692595) (xy 137.635015 140.638373)
			)
		)
	)
	(zone
		(net 734)
		(net_name "Net-(U43A-LOSA)")
		(layer "In5.Cu")
		(name "$teardrop_padvia$")
		(hatch none 0.1)
		(priority 30266)
		(attr
			(teardrop
				(type padvia)
			)
		)
		(connect_pads yes
			(clearance 0)
		)
		(min_thickness 0.0254)
		(filled_areas_thickness no)
		(fill yes
			(thermal_gap 0.5)
			(thermal_bridge_width 0.5)
			(island_removal_mode 1)
			(island_area_min 10)
		)
		(polygon
			(pts
				(xy 152.122485 139.620873) (xy 152.168181 139.673382) (xy 152.194768 139.719376) (xy 152.215152 139.805825)
				(xy 152.216988 139.821158) (xy 152.229323 139.903895) (xy 152.450707 139.860707) (xy 152.493895 139.639323)
				(xy 152.411158 139.626988) (xy 152.31388 139.606651) (xy 152.26584 139.579943) (xy 152.210873 139.532485)
			)
		)
	)
	(zone
		(net 296)
		(net_name "/2xUSB3.0+RJ45/GbE.CTREF")
		(layer "In5.Cu")
		(name "$teardrop_padvia$")
		(hatch none 0.1)
		(priority 30030)
		(attr
			(teardrop
				(type padvia)
			)
		)
		(connect_pads yes
			(clearance 0)
		)
		(min_thickness 0.0254)
		(filled_areas_thickness no)
		(fill yes
			(thermal_gap 0.5)
			(thermal_bridge_width 0.5)
			(island_removal_mode 1)
			(island_area_min 10)
		)
		(polygon
			(pts
				(xy 182.145969 169.68739) (xy 182.197728 169.745814) (xy 182.230111 169.796564) (xy 182.264709 169.890702)
				(xy 182.294742 169.98112) (xy 182.500707 169.900707) (xy 182.58112 169.694742) (xy 182.490702 169.664709)
				(xy 182.394888 169.629237) (xy 182.344885 169.597021) (xy 182.28739 169.545969)
			)
		)
	)
	(zone
		(net 62)
		(net_name "+12V_AON")
		(layer "In5.Cu")
		(name "$teardrop_padvia$")
		(hatch none 0.1)
		(priority 30017)
		(attr
			(teardrop
				(type padvia)
			)
		)
		(connect_pads yes
			(clearance 0)
		)
		(min_thickness 0.0254)
		(filled_areas_thickness no)
		(fill yes
			(thermal_gap 0.5)
			(thermal_bridge_width 0.5)
			(island_removal_mode 1)
			(island_area_min 10)
		)
		(polygon
			(pts
				(xy 314.364501 93.235823) (xy 314.359788 93.313734) (xy 314.346801 93.372518) (xy 314.3047 93.463548)
				(xy 314.262001 93.548721) (xy 314.464501 93.6375) (xy 314.667001 93.548721) (xy 314.624302 93.46355)
				(xy 314.581634 93.370717) (xy 314.569057 93.312578) (xy 314.564501 93.235823)
			)
		)
	)
	(zone
		(net 739)
		(net_name "Net-(U43B-LS_OK_{OUT_B})")
		(layer "In5.Cu")
		(name "$teardrop_padvia$")
		(hatch none 0.1)
		(priority 30195)
		(attr
			(teardrop
				(type padvia)
			)
		)
		(connect_pads yes
			(clearance 0)
		)
		(min_thickness 0.0254)
		(filled_areas_thickness no)
		(fill yes
			(thermal_gap 0.5)
			(thermal_bridge_width 0.5)
			(island_removal_mode 1)
			(island_area_min 10)
		)
		(polygon
			(pts
				(xy 147.3125 130.910677) (xy 147.317318 130.841236) (xy 147.33104 130.789912) (xy 147.377755 130.71437)
				(xy 147.387299 130.702229) (xy 147.437081 130.635003) (xy 147.25 130.509) (xy 147.062919 130.635003)
				(xy 147.112701 130.702231) (xy 147.167106 130.785397) (xy 147.18219 130.838251) (xy 147.1875 130.910677)
			)
		)
	)
	(zone
		(net 429)
		(net_name "/2xSFP+/MDIO1.MDC")
		(layer "In5.Cu")
		(name "$teardrop_padvia$")
		(hatch none 0.1)
		(priority 30226)
		(attr
			(teardrop
				(type padvia)
			)
		)
		(connect_pads yes
			(clearance 0)
		)
		(min_thickness 0.0254)
		(filled_areas_thickness no)
		(fill yes
			(thermal_gap 0.5)
			(thermal_bridge_width 0.5)
			(island_removal_mode 1)
			(island_area_min 10)
		)
		(polygon
			(pts
				(xy 167.500677 142.7625) (xy 167.431236 142.757682) (xy 167.379913 142.74396) (xy 167.304371 142.697246)
				(xy 167.292231 142.687701) (xy 167.225003 142.637919) (xy 167.099 142.825) (xy 167.225003 143.012081)
				(xy 167.292229 142.962299) (xy 167.375396 142.907894) (xy 167.428251 142.89281) (xy 167.500677 142.8875)
			)
		)
	)
	(zone
		(net 344)
		(net_name "/Com Express 7 MGMT/SER0.TX")
		(layer "In5.Cu")
		(name "$teardrop_padvia$")
		(hatch none 0.1)
		(priority 30172)
		(attr
			(teardrop
				(type padvia)
			)
		)
		(connect_pads yes
			(clearance 0)
		)
		(min_thickness 0.0254)
		(filled_areas_thickness no)
		(fill yes
			(thermal_gap 0.5)
			(thermal_bridge_width 0.5)
			(island_removal_mode 1)
			(island_area_min 10)
		)
		(polygon
			(pts
				(xy 224.1375 169.899323) (xy 224.132682 169.968763) (xy 224.11896 170.020087) (xy 224.072245 170.095628)
				(xy 224.062702 170.107768) (xy 224.012919 170.174997) (xy 224.2 170.301) (xy 224.387081 170.174997)
				(xy 224.337299 170.107769) (xy 224.282894 170.024603) (xy 224.26781 169.971748) (xy 224.2625 169.899323)
			)
		)
	)
	(zone
		(net 344)
		(net_name "/Com Express 7 MGMT/SER0.TX")
		(layer "In5.Cu")
		(name "$teardrop_padvia$")
		(hatch none 0.1)
		(priority 30294)
		(attr
			(teardrop
				(type padvia)
			)
		)
		(connect_pads yes
			(clearance 0)
		)
		(min_thickness 0.0254)
		(filled_areas_thickness no)
		(fill yes
			(thermal_gap 0.5)
			(thermal_bridge_width 0.5)
			(island_removal_mode 1)
			(island_area_min 10)
		)
		(polygon
			(pts
				(xy 217.042084 145.3375) (xy 217.002022 145.332738) (xy 216.973671 145.319405) (xy 216.94222 145.275526)
				(xy 216.927243 145.226588) (xy 216.912171 145.175867) (xy 216.887081 145.124997) (xy 216.699 145.25)
				(xy 216.743895 145.470677) (xy 216.830907 145.458172) (xy 216.899613 145.457731) (xy 216.926992 145.459075)
				(xy 217.042084 145.4625)
			)
		)
	)
	(zone
		(net 651)
		(net_name "/2xSFP+/KR to SFI #1/MDC")
		(layer "In5.Cu")
		(name "$teardrop_padvia$")
		(hatch none 0.1)
		(priority 30245)
		(attr
			(teardrop
				(type padvia)
			)
		)
		(connect_pads yes
			(clearance 0)
		)
		(min_thickness 0.0254)
		(filled_areas_thickness no)
		(fill yes
			(thermal_gap 0.5)
			(thermal_bridge_width 0.5)
			(island_removal_mode 1)
			(island_area_min 10)
		)
		(polygon
			(pts
				(xy 144.089127 142.782485) (xy 144.036618 142.828181) (xy 143.990623 142.854768) (xy 143.904174 142.875152)
				(xy 143.888841 142.876988) (xy 143.806105 142.889323) (xy 143.849293 143.110707) (xy 144.070677 143.153895)
				(xy 144.083011 143.07116) (xy 144.103349 142.973881) (xy 144.130057 142.925841) (xy 144.177515 142.870873)
			)
		)
	)
	(zone
		(net 741)
		(net_name "Net-(U45C-REFCLK1-)")
		(layer "In5.Cu")
		(name "$teardrop_padvia$")
		(hatch none 0.1)
		(priority 30265)
		(attr
			(teardrop
				(type padvia)
			)
		)
		(connect_pads yes
			(clearance 0)
		)
		(min_thickness 0.0254)
		(filled_areas_thickness no)
		(fill yes
			(thermal_gap 0.5)
			(thermal_bridge_width 0.5)
			(island_removal_mode 1)
			(island_area_min 10)
		)
		(polygon
			(pts
				(xy 128.962485 140.620873) (xy 129.008181 140.673382) (xy 129.034768 140.719376) (xy 129.055152 140.805825)
				(xy 129.056988 140.821158) (xy 129.069323 140.903895) (xy 129.290707 140.860707) (xy 129.333895 140.639323)
				(xy 129.251158 140.626988) (xy 129.15388 140.606651) (xy 129.10584 140.579943) (xy 129.050873 140.532485)
			)
		)
	)
	(zone
		(net 164)
		(net_name "/2xSFP+/SDA0")
		(layer "In5.Cu")
		(name "$teardrop_padvia$")
		(hatch none 0.1)
		(priority 30001)
		(attr
			(teardrop
				(type padvia)
			)
		)
		(connect_pads yes
			(clearance 0)
		)
		(min_thickness 0.0254)
		(filled_areas_thickness no)
		(fill yes
			(thermal_gap 0.5)
			(thermal_bridge_width 0.5)
			(island_removal_mode 1)
			(island_area_min 10)
		)
		(polygon
			(pts
				(xy 144.817264 160.546236) (xy 144.642918 160.728781) (xy 144.531717 160.869098) (xy 144.444979 160.995152)
				(xy 144.395397 161.068175) (xy 144.749293 161.310707) (xy 145.107532 161.071105) (xy 145.023402 160.972745)
				(xy 144.975458 160.927073) (xy 144.904801 160.857437) (xy 144.858101 160.788912) (xy 144.849131 160.753459)
				(xy 144.852628 160.716355) (xy 144.870749 160.676958) (xy 144.905653 160.634625)
			)
		)
	)
	(zone
		(net 371)
		(net_name "/Com Express 7 MGMT/I2C.SCL")
		(layer "In5.Cu")
		(name "$teardrop_padvia$")
		(hatch none 0.1)
		(priority 30250)
		(attr
			(teardrop
				(type padvia)
			)
		)
		(connect_pads yes
			(clearance 0)
		)
		(min_thickness 0.0254)
		(filled_areas_thickness no)
		(fill yes
			(thermal_gap 0.5)
			(thermal_bridge_width 0.5)
			(island_removal_mode 1)
			(island_area_min 10)
		)
		(polygon
			(pts
				(xy 304.199485 151.000873) (xy 304.245181 151.053382) (xy 304.271768 151.099376) (xy 304.292152 151.185825)
				(xy 304.293988 151.201158) (xy 304.306323 151.283895) (xy 304.527707 151.240707) (xy 304.570895 151.019323)
				(xy 304.488158 151.006988) (xy 304.39088 150.986651) (xy 304.34284 150.959943) (xy 304.287873 150.912485)
			)
		)
	)
	(zone
		(net 357)
		(net_name "/Com Express 7 MGMT/SMBus.SCL")
		(layer "In5.Cu")
		(name "$teardrop_padvia$")
		(hatch none 0.1)
		(priority 30221)
		(attr
			(teardrop
				(type padvia)
			)
		)
		(connect_pads yes
			(clearance 0)
		)
		(min_thickness 0.0254)
		(filled_areas_thickness no)
		(fill yes
			(thermal_gap 0.5)
			(thermal_bridge_width 0.5)
			(island_removal_mode 1)
			(island_area_min 10)
		)
		(polygon
			(pts
				(xy 167.175677 163.8375) (xy 167.106236 163.832682) (xy 167.054913 163.81896) (xy 166.979371 163.772246)
				(xy 166.967231 163.762701) (xy 166.900003 163.712919) (xy 166.774 163.9) (xy 166.900003 164.087081)
				(xy 166.967229 164.037299) (xy 167.050396 163.982894) (xy 167.103251 163.96781) (xy 167.175677 163.9625)
			)
		)
	)
	(zone
		(net 944)
		(net_name "/GPIO expander/GPIOEX2")
		(layer "In5.Cu")
		(name "$teardrop_padvia$")
		(hatch none 0.1)
		(priority 30262)
		(attr
			(teardrop
				(type padvia)
			)
		)
		(connect_pads yes
			(clearance 0)
		)
		(min_thickness 0.0254)
		(filled_areas_thickness no)
		(fill yes
			(thermal_gap 0.5)
			(thermal_bridge_width 0.5)
			(island_removal_mode 1)
			(island_area_min 10)
		)
		(polygon
			(pts
				(xy 125.617485 84.820874) (xy 125.663181 84.873383) (xy 125.689768 84.919377) (xy 125.710152 85.005826)
				(xy 125.711988 85.021159) (xy 125.724323 85.103896) (xy 125.945707 85.060708) (xy 125.988895 84.839324)
				(xy 125.906158 84.826989) (xy 125.80888 84.806652) (xy 125.76084 84.779944) (xy 125.705873 84.732486)
			)
		)
	)
	(zone
		(net 595)
		(net_name "/Misc/PWM_{SRCSEL}")
		(layer "In5.Cu")
		(name "$teardrop_padvia$")
		(hatch none 0.1)
		(priority 30255)
		(attr
			(teardrop
				(type padvia)
			)
		)
		(connect_pads yes
			(clearance 0)
		)
		(min_thickness 0.0254)
		(filled_areas_thickness no)
		(fill yes
			(thermal_gap 0.5)
			(thermal_bridge_width 0.5)
			(island_removal_mode 1)
			(island_area_min 10)
		)
		(polygon
			(pts
				(xy 257.223192 76.945873) (xy 257.268888 76.998382) (xy 257.295475 77.044376) (xy 257.315859 77.130825)
				(xy 257.317695 77.146158) (xy 257.33003 77.228895) (xy 257.551414 77.185707) (xy 257.594602 76.964323)
				(xy 257.511865 76.951988) (xy 257.414587 76.931651) (xy 257.366547 76.904943) (xy 257.31158 76.857485)
			)
		)
	)
	(zone
		(net 724)
		(net_name "/2xSFP+/KR to SFI #1/TMS")
		(layer "In5.Cu")
		(name "$teardrop_padvia$")
		(hatch none 0.1)
		(priority 30159)
		(attr
			(teardrop
				(type padvia)
			)
		)
		(connect_pads yes
			(clearance 0)
		)
		(min_thickness 0.0254)
		(filled_areas_thickness no)
		(fill yes
			(thermal_gap 0.5)
			(thermal_bridge_width 0.5)
			(island_removal_mode 1)
			(island_area_min 10)
		)
		(polygon
			(pts
				(xy 155.427498 138.424114) (xy 155.38185 138.476266) (xy 155.352958 138.522406) (xy 155.323204 138.601095)
				(xy 155.301796 138.662965) (xy 155.262919 138.734997) (xy 155.449293 138.860707) (xy 155.637081 138.734997)
				(xy 155.578336 138.673155) (xy 155.558875 138.656944) (xy 155.520196 138.623352) (xy 155.494034 138.58986)
				(xy 155.489546 138.5538) (xy 155.515886 138.512502)
			)
		)
	)
	(zone
		(net 378)
		(net_name "/Com Express 7 Interfaces/USB1.D+")
		(layer "In5.Cu")
		(name "$teardrop_padvia$")
		(hatch none 0.1)
		(priority 30119)
		(attr
			(teardrop
				(type padvia)
			)
		)
		(connect_pads yes
			(clearance 0)
		)
		(min_thickness 0.0254)
		(filled_areas_thickness no)
		(fill yes
			(thermal_gap 0.5)
			(thermal_bridge_width 0.5)
			(island_removal_mode 1)
			(island_area_min 10)
		)
		(polygon
			(pts
				(xy 204.911 142.596584) (xy 204.915756 142.555895) (xy 204.929046 142.526665) (xy 204.973378 142.492239)
				(xy 205.016411 142.475787) (xy 205.102003 142.437081) (xy 204.977 142.249) (xy 204.756323 142.251749)
				(xy 204.754515 142.415835) (xy 204.752 142.596584)
			)
		)
	)
	(zone
		(net 77)
		(net_name "+5V_AON")
		(layer "In5.Cu")
		(name "$teardrop_padvia$")
		(hatch none 0.1)
		(priority 30023)
		(attr
			(teardrop
				(type padvia)
			)
		)
		(connect_pads yes
			(clearance 0)
		)
		(min_thickness 0.0254)
		(filled_areas_thickness no)
		(fill yes
			(thermal_gap 0.5)
			(thermal_bridge_width 0.5)
			(island_removal_mode 1)
			(island_area_min 10)
		)
		(polygon
			(pts
				(xy 188.92122 73.748132) (xy 188.862796 73.799891) (xy 188.812046 73.832273) (xy 188.717909 73.866871)
				(xy 188.62749 73.896904) (xy 188.707903 74.10287) (xy 188.913867 74.183284) (xy 188.9439 74.092866)
				(xy 188.979372 73.997052) (xy 189.011589 73.947048) (xy 189.062641 73.889553)
			)
		)
	)
	(zone
		(net 943)
		(net_name "/GPIO expander/GPIOEX1")
		(layer "In5.Cu")
		(name "$teardrop_padvia$")
		(hatch none 0.1)
		(priority 30185)
		(attr
			(teardrop
				(type padvia)
			)
		)
		(connect_pads yes
			(clearance 0)
		)
		(min_thickness 0.0254)
		(filled_areas_thickness no)
		(fill yes
			(thermal_gap 0.5)
			(thermal_bridge_width 0.5)
			(island_removal_mode 1)
			(island_area_min 10)
		)
		(polygon
			(pts
				(xy 125.544323 84.122501) (xy 125.613764 84.127319) (xy 125.665088 84.141041) (xy 125.740629 84.187756)
				(xy 125.752769 84.1973) (xy 125.819997 84.247082) (xy 125.946 84.060001) (xy 125.819997 83.87292)
				(xy 125.752768 83.922703) (xy 125.669602 83.977107) (xy 125.616748 83.992191) (xy 125.544323 83.997501)
			)
		)
	)
	(zone
		(net 262)
		(net_name "/Com Express 7 Interfaces/PCIe_{B2Bx4}.RX0-")
		(layer "In5.Cu")
		(name "$teardrop_padvia$")
		(hatch none 0.1)
		(priority 30084)
		(attr
			(teardrop
				(type padvia)
			)
		)
		(connect_pads yes
			(clearance 0)
		)
		(min_thickness 0.0254)
		(filled_areas_thickness no)
		(fill yes
			(thermal_gap 0.5)
			(thermal_bridge_width 0.5)
			(island_removal_mode 1)
			(island_area_min 10)
		)
		(polygon
			(pts
				(xy 195.373 161.139416) (xy 195.379896 161.276751) (xy 195.384276 161.357939) (xy 195.372823 161.456105)
				(xy 195.5935 161.501) (xy 195.753189 161.347605) (xy 195.685691 161.298527) (xy 195.65719 161.284188)
				(xy 195.616571 161.262889) (xy 195.582738 161.236198) (xy 195.559583 161.197309) (xy 195.551 161.139416)
			)
		)
	)
	(zone
		(net 430)
		(net_name "/2xSFP+/MDIO0.MDC")
		(layer "In5.Cu")
		(name "$teardrop_padvia$")
		(hatch none 0.1)
		(priority 30267)
		(attr
			(teardrop
				(type padvia)
			)
		)
		(connect_pads yes
			(clearance 0)
		)
		(min_thickness 0.0254)
		(filled_areas_thickness no)
		(fill yes
			(thermal_gap 0.5)
			(thermal_bridge_width 0.5)
			(island_removal_mode 1)
			(island_area_min 10)
		)
		(polygon
			(pts
				(xy 166.747485 144.160873) (xy 166.793181 144.213382) (xy 166.819768 144.259376) (xy 166.840152 144.345825)
				(xy 166.841988 144.361158) (xy 166.854323 144.443895) (xy 167.075707 144.400707) (xy 167.118895 144.179323)
				(xy 167.036158 144.166988) (xy 166.93888 144.146651) (xy 166.89084 144.119943) (xy 166.835873 144.072485)
			)
		)
	)
	(zone
		(net 527)
		(net_name "/Backplane/GPIO")
		(layer "In5.Cu")
		(name "$teardrop_padvia$")
		(hatch none 0.1)
		(priority 30160)
		(attr
			(teardrop
				(type padvia)
			)
		)
		(connect_pads yes
			(clearance 0)
		)
		(min_thickness 0.0254)
		(filled_areas_thickness no)
		(fill yes
			(thermal_gap 0.5)
			(thermal_bridge_width 0.5)
			(island_removal_mode 1)
			(island_area_min 10)
		)
		(polygon
			(pts
				(xy 130.693627 75.95594) (xy 130.658694 75.951165) (xy 130.636161 75.937739) (xy 130.619024 75.8958)
				(xy 130.621197 75.824245) (xy 130.624703 75.770069) (xy 130.620677 75.716105) (xy 130.399 75.76)
				(xy 130.356105 75.980677) (xy 130.465772 76.017486) (xy 130.493118 76.031112) (xy 130.574001 76.065724)
				(xy 130.693627 76.08094)
			)
		)
	)
	(zone
		(net 721)
		(net_name "Net-(U43C-REFCLK1-)")
		(layer "In5.Cu")
		(name "$teardrop_padvia$")
		(hatch none 0.1)
		(priority 30136)
		(attr
			(teardrop
				(type padvia)
			)
		)
		(connect_pads yes
			(clearance 0)
		)
		(min_thickness 0.0254)
		(filled_areas_thickness no)
		(fill yes
			(thermal_gap 0.5)
			(thermal_bridge_width 0.5)
			(island_removal_mode 1)
			(island_area_min 10)
		)
		(polygon
			(pts
				(xy 144.7875 130.844047) (xy 144.783335 130.701353) (xy 144.772402 130.598414) (xy 144.760677 130.497347)
				(xy 144.54 130.519) (xy 144.414997 130.707081) (xy 144.485432 130.735025) (xy 144.541474 130.743295)
				(xy 144.588212 130.750037) (xy 144.626722 130.763969) (xy 144.652865 130.792752) (xy 144.6625 130.844047)
			)
		)
	)
	(zone
		(net 746)
		(net_name "/2xSFP+/KR to SFI #2/~{TRST}")
		(layer "In5.Cu")
		(name "$teardrop_padvia$")
		(hatch none 0.1)
		(priority 30199)
		(attr
			(teardrop
				(type padvia)
			)
		)
		(connect_pads yes
			(clearance 0)
		)
		(min_thickness 0.0254)
		(filled_areas_thickness no)
		(fill yes
			(thermal_gap 0.5)
			(thermal_bridge_width 0.5)
			(island_removal_mode 1)
			(island_area_min 10)
		)
		(polygon
			(pts
				(xy 133.0525 130.910677) (xy 133.057318 130.841236) (xy 133.07104 130.789912) (xy 133.117755 130.71437)
				(xy 133.127299 130.702229) (xy 133.177081 130.635003) (xy 132.99 130.509) (xy 132.802919 130.635003)
				(xy 132.852701 130.702231) (xy 132.907106 130.785397) (xy 132.92219 130.838251) (xy 132.9275 130.910677)
			)
		)
	)
	(zone
		(net 723)
		(net_name "/2xSFP+/KR to SFI #1/TDO")
		(layer "In5.Cu")
		(name "$teardrop_padvia$")
		(hatch none 0.1)
		(priority 30148)
		(attr
			(teardrop
				(type padvia)
			)
		)
		(connect_pads yes
			(clearance 0)
		)
		(min_thickness 0.0254)
		(filled_areas_thickness no)
		(fill yes
			(thermal_gap 0.5)
			(thermal_bridge_width 0.5)
			(island_removal_mode 1)
			(island_area_min 10)
		)
		(polygon
			(pts
				(xy 153.406285 136.415328) (xy 153.366226 136.46193) (xy 153.34126 136.504419) (xy 153.315967 136.593269)
				(xy 153.300119 136.659645) (xy 153.262919 136.734997) (xy 153.449293 136.860707) (xy 153.637081 136.734997)
				(xy 153.578848 136.675239) (xy 153.544778 136.649316) (xy 153.502321 136.616146) (xy 153.473374 136.582824)
				(xy 153.467603 136.546347) (xy 153.494672 136.503715)
			)
		)
	)
	(zone
		(net 374)
		(net_name "/2xUSB3.0+RJ45/USB_2.D-")
		(layer "In5.Cu")
		(name "$teardrop_padvia$")
		(hatch none 0.1)
		(priority 30118)
		(attr
			(teardrop
				(type padvia)
			)
		)
		(connect_pads yes
			(clearance 0)
		)
		(min_thickness 0.0254)
		(filled_areas_thickness no)
		(fill yes
			(thermal_gap 0.5)
			(thermal_bridge_width 0.5)
			(island_removal_mode 1)
			(island_area_min 10)
		)
		(polygon
			(pts
				(xy 155.361 123.346584) (xy 155.365756 123.305895) (xy 155.379046 123.276665) (xy 155.423378 123.242239)
				(xy 155.466411 123.225787) (xy 155.552003 123.187081) (xy 155.427 122.999) (xy 155.206323 123.001749)
				(xy 155.204515 123.165835) (xy 155.202 123.346584)
			)
		)
	)
	(zone
		(net 267)
		(net_name "/Com Express 7 Interfaces/PCIe_{B2Bx4}.TX0-")
		(layer "In5.Cu")
		(name "$teardrop_padvia$")
		(hatch none 0.1)
		(priority 30068)
		(attr
			(teardrop
				(type padvia)
			)
		)
		(connect_pads yes
			(clearance 0)
		)
		(min_thickness 0.0254)
		(filled_areas_thickness no)
		(fill yes
			(thermal_gap 0.5)
			(thermal_bridge_width 0.5)
			(island_removal_mode 1)
			(island_area_min 10)
		)
		(polygon
			(pts
				(xy 173.879416 104.886) (xy 173.924146 104.890741) (xy 173.957611 104.903931) (xy 174.001124 104.948694)
				(xy 174.024188 104.99219) (xy 174.050165 105.041127) (xy 174.087605 105.088189) (xy 174.241 104.9285)
				(xy 174.196105 104.707823) (xy 174.11904 104.718447) (xy 174.057337 104.718182) (xy 174.016751 104.714896)
				(xy 173.879416 104.708)
			)
		)
	)
	(zone
		(net 365)
		(net_name "/Com Express 7 MGMT/PWR_OK")
		(layer "In5.Cu")
		(name "$teardrop_padvia$")
		(hatch none 0.1)
		(priority 30182)
		(attr
			(teardrop
				(type padvia)
			)
		)
		(connect_pads yes
			(clearance 0)
		)
		(min_thickness 0.0254)
		(filled_areas_thickness no)
		(fill yes
			(thermal_gap 0.5)
			(thermal_bridge_width 0.5)
			(island_removal_mode 1)
			(island_area_min 10)
		)
		(polygon
			(pts
				(xy 276.299323 129.1625) (xy 276.368764 129.167318) (xy 276.420088 129.18104) (xy 276.495629 129.227755)
				(xy 276.507769 129.237299) (xy 276.574997 129.287081) (xy 276.701 129.1) (xy 276.574997 128.912919)
				(xy 276.507768 128.962702) (xy 276.424602 129.017106) (xy 276.371748 129.03219) (xy 276.299323 129.0375)
			)
		)
	)
	(zone
		(net 735)
		(net_name "Net-(U43A-LS_OK_{IN_A})")
		(layer "In5.Cu")
		(name "$teardrop_padvia$")
		(hatch none 0.1)
		(priority 30162)
		(attr
			(teardrop
				(type padvia)
			)
		)
		(connect_pads yes
			(clearance 0)
		)
		(min_thickness 0.0254)
		(filled_areas_thickness no)
		(fill yes
			(thermal_gap 0.5)
			(thermal_bridge_width 0.5)
			(island_removal_mode 1)
			(island_area_min 10)
		)
		(polygon
			(pts
				(xy 156.132957 130.844569) (xy 156.078393 130.796497) (xy 156.03072 130.76598) (xy 155.955804 130.735198)
				(xy 155.895655 130.712147) (xy 155.825003 130.672919) (xy 155.699293 130.859293) (xy 155.825003 131.047081)
				(xy 155.900327 130.973541) (xy 155.934099 130.936097) (xy 155.967687 130.910856) (xy 156.003656 130.906811)
				(xy 156.044569 130.932957)
			)
		)
	)
	(zone
		(net 322)
		(net_name "/Com Express 7 Interfaces/SDIO.DAT1")
		(layer "In5.Cu")
		(name "$teardrop_padvia$")
		(hatch none 0.1)
		(priority 30041)
		(attr
			(teardrop
				(type padvia)
			)
		)
		(connect_pads yes
			(clearance 0)
		)
		(min_thickness 0.0254)
		(filled_areas_thickness no)
		(fill yes
			(thermal_gap 0.5)
			(thermal_bridge_width 0.5)
			(island_removal_mode 1)
			(island_area_min 10)
		)
		(polygon
			(pts
				(xy 164.461879 159.07148) (xy 164.506901 159.123136) (xy 164.534795 159.169182) (xy 164.563406 159.266971)
				(xy 164.594742 159.38112) (xy 164.800707 159.300707) (xy 164.88112 159.094742) (xy 164.766971 159.063406)
				(xy 164.674573 159.0373) (xy 164.626086 159.009044) (xy 164.57148 158.961879)
			)
		)
	)
	(zone
		(net 78)
		(net_name "+1V8")
		(layer "In5.Cu")
		(name "$teardrop_padvia$")
		(hatch none 0.1)
		(priority 30029)
		(attr
			(teardrop
				(type padvia)
			)
		)
		(connect_pads yes
			(clearance 0)
		)
		(min_thickness 0.0254)
		(filled_areas_thickness no)
		(fill yes
			(thermal_gap 0.5)
			(thermal_bridge_width 0.5)
			(island_removal_mode 1)
			(island_area_min 10)
		)
		(polygon
			(pts
				(xy 203.254579 75.589553) (xy 203.306338 75.647977) (xy 203.338721 75.698727) (xy 203.373319 75.792865)
				(xy 203.403352 75.883283) (xy 203.609317 75.80287) (xy 203.68973 75.596905) (xy 203.599312 75.566872)
				(xy 203.503498 75.5314) (xy 203.453495 75.499184) (xy 203.396 75.448132)
			)
		)
	)
	(zone
		(net 374)
		(net_name "/2xUSB3.0+RJ45/USB_2.D-")
		(layer "In5.Cu")
		(name "$teardrop_padvia$")
		(hatch none 0.1)
		(priority 30145)
		(attr
			(teardrop
				(type padvia)
			)
		)
		(connect_pads yes
			(clearance 0)
		)
		(min_thickness 0.0254)
		(filled_areas_thickness no)
		(fill yes
			(thermal_gap 0.5)
			(thermal_bridge_width 0.5)
			(island_removal_mode 1)
			(island_area_min 10)
		)
		(polygon
			(pts
				(xy 196.673 161.851084) (xy 196.666226 161.718309) (xy 196.661923 161.639838) (xy 196.673177 161.543895)
				(xy 196.4525 161.499) (xy 196.327497 161.687081) (xy 196.409042 161.725803) (xy 196.449848 161.742581)
				(xy 196.483215 161.764567) (xy 196.505736 161.79849) (xy 196.514 161.851084)
			)
		)
	)
	(zone
		(net 262)
		(net_name "/Com Express 7 Interfaces/PCIe_{B2Bx4}.RX0-")
		(layer "In5.Cu")
		(name "$teardrop_padvia$")
		(hatch none 0.1)
		(priority 30097)
		(attr
			(teardrop
				(type padvia)
			)
		)
		(connect_pads yes
			(clearance 0)
		)
		(min_thickness 0.0254)
		(filled_areas_thickness no)
		(fill yes
			(thermal_gap 0.5)
			(thermal_bridge_width 0.5)
			(island_removal_mode 1)
			(island_area_min 10)
		)
		(polygon
			(pts
				(xy 187.156084 122.524) (xy 187.113152 122.519241) (xy 187.081738 122.505928) (xy 187.042448 122.461041)
				(xy 187.023424 122.421529) (xy 186.987081 122.351997) (xy 186.799 122.477) (xy 186.80947 122.697677)
				(xy 186.989599 122.698302) (xy 187.156084 122.702)
			)
		)
	)
	(zone
		(net 336)
		(net_name "/Com Express 7 Interfaces/PCIE_{REF}.CK+")
		(layer "In5.Cu")
		(name "$teardrop_padvia$")
		(hatch none 0.1)
		(priority 30070)
		(attr
			(teardrop
				(type padvia)
			)
		)
		(connect_pads yes
			(clearance 0)
		)
		(min_thickness 0.0254)
		(filled_areas_thickness no)
		(fill yes
			(thermal_gap 0.5)
			(thermal_bridge_width 0.5)
			(island_removal_mode 1)
			(island_area_min 10)
		)
		(polygon
			(pts
				(xy 215.555 122.960584) (xy 215.559741 122.915854) (xy 215.572931 122.882389) (xy 215.617694 122.838875)
				(xy 215.66119 122.815811) (xy 215.710128 122.789834) (xy 215.757189 122.752394) (xy 215.5975 122.599)
				(xy 215.376823 122.643895) (xy 215.387447 122.720959) (xy 215.387182 122.782662) (xy 215.383896 122.823248)
				(xy 215.377 122.960584)
			)
		)
	)
	(zone
		(net 2)
		(net_name "+3V3")
		(layer "In5.Cu")
		(name "$teardrop_padvia$")
		(hatch none 0.1)
		(priority 30006)
		(attr
			(teardrop
				(type padvia)
			)
		)
		(connect_pads yes
			(clearance 0)
		)
		(min_thickness 0.0254)
		(filled_areas_thickness no)
		(fill yes
			(thermal_gap 0.5)
			(thermal_bridge_width 0.5)
			(island_removal_mode 1)
			(island_area_min 10)
		)
		(polygon
			(pts
				(xy 142.782745 139.029387) (xy 142.899071 138.922864) (xy 142.999522 138.862752) (xy 143.04112 138.845257)
				(xy 142.960707 138.639293) (xy 142.754742 138.558879) (xy 142.711141 138.651105) (xy 142.649861 138.733905)
				(xy 142.570613 138.817255)
			)
		)
	)
	(zone
		(net 322)
		(net_name "/Com Express 7 Interfaces/SDIO.DAT1")
		(layer "In5.Cu")
		(name "$teardrop_padvia$")
		(hatch none 0.1)
		(priority 30036)
		(attr
			(teardrop
				(type padvia)
			)
		)
		(connect_pads yes
			(clearance 0)
		)
		(min_thickness 0.0254)
		(filled_areas_thickness no)
		(fill yes
			(thermal_gap 0.5)
			(thermal_bridge_width 0.5)
			(island_removal_mode 1)
			(island_area_min 10)
		)
		(polygon
			(pts
				(xy 114.450677 132.0825) (xy 114.382314 132.077809) (xy 114.33003 132.064974) (xy 114.240652 132.016057)
				(xy 114.137778 131.9575) (xy 114.049 132.16) (xy 114.137778 132.3625) (xy 114.240651 132.303943)
				(xy 114.324447 132.257067) (xy 114.378713 132.242761) (xy 114.450677 132.2375)
			)
		)
	)
	(zone
		(net 326)
		(net_name "/Com Express 7 Interfaces/PCIe_{B2Ax4}.TX1+")
		(layer "In5.Cu")
		(name "$teardrop_padvia$")
		(hatch none 0.1)
		(priority 30082)
		(attr
			(teardrop
				(type padvia)
			)
		)
		(connect_pads yes
			(clearance 0)
		)
		(min_thickness 0.0254)
		(filled_areas_thickness no)
		(fill yes
			(thermal_gap 0.5)
			(thermal_bridge_width 0.5)
			(island_removal_mode 1)
			(island_area_min 10)
		)
		(polygon
			(pts
				(xy 229.552 145.360584) (xy 229.545104 145.223248) (xy 229.540724 145.142061) (xy 229.552177 145.043895)
				(xy 229.3315 144.999) (xy 229.17181 145.152394) (xy 229.239306 145.201472) (xy 229.267809 145.215811)
				(xy 229.308428 145.23711) (xy 229.342262 145.263802) (xy 229.365417 145.302691) (xy 229.374 145.360584)
			)
		)
	)
	(zone
		(net 201)
		(net_name "/OCuLink/~{CPRSNT_D0}")
		(layer "In5.Cu")
		(name "$teardrop_padvia$")
		(hatch none 0.1)
		(priority 30177)
		(attr
			(teardrop
				(type padvia)
			)
		)
		(connect_pads yes
			(clearance 0)
		)
		(min_thickness 0.0254)
		(filled_areas_thickness no)
		(fill yes
			(thermal_gap 0.5)
			(thermal_bridge_width 0.5)
			(island_removal_mode 1)
			(island_area_min 10)
		)
		(polygon
			(pts
				(xy 119.949323 161.6225) (xy 120.018764 161.627318) (xy 120.070088 161.64104) (xy 120.145629 161.687755)
				(xy 120.157769 161.697299) (xy 120.224997 161.747081) (xy 120.351 161.56) (xy 120.224997 161.372919)
				(xy 120.157768 161.422702) (xy 120.074602 161.477106) (xy 120.021748 161.49219) (xy 119.949323 161.4975)
			)
		)
	)
	(zone
		(net 269)
		(net_name "/Com Express 7 Interfaces/PCIe_{B2Bx4}.TX0+")
		(layer "In5.Cu")
		(name "$teardrop_padvia$")
		(hatch none 0.1)
		(priority 30077)
		(attr
			(teardrop
				(type padvia)
			)
		)
		(connect_pads yes
			(clearance 0)
		)
		(min_thickness 0.0254)
		(filled_areas_thickness no)
		(fill yes
			(thermal_gap 0.5)
			(thermal_bridge_width 0.5)
			(island_removal_mode 1)
			(island_area_min 10)
		)
		(polygon
			(pts
				(xy 173.879416 104.512) (xy 174.016751 104.505104) (xy 174.097939 104.500724) (xy 174.196105 104.512177)
				(xy 174.241 104.2915) (xy 174.087605 104.13181) (xy 174.038527 104.199306) (xy 174.024187 104.22781)
				(xy 174.002888 104.268429) (xy 173.976197 104.302262) (xy 173.937308 104.325417) (xy 173.879416 104.334)
			)
		)
	)
	(zone
		(net 526)
		(net_name "/Backplane/~{PRSNT}")
		(layer "In5.Cu")
		(name "$teardrop_padvia$")
		(hatch none 0.1)
		(priority 30166)
		(attr
			(teardrop
				(type padvia)
			)
		)
		(connect_pads yes
			(clearance 0)
		)
		(min_thickness 0.0254)
		(filled_areas_thickness no)
		(fill yes
			(thermal_gap 0.5)
			(thermal_bridge_width 0.5)
			(island_removal_mode 1)
			(island_area_min 10)
		)
		(polygon
			(pts
				(xy 208.6375 126.099323) (xy 208.632682 126.168763) (xy 208.61896 126.220087) (xy 208.572245 126.295628)
				(xy 208.562702 126.307768) (xy 208.512919 126.374997) (xy 208.7 126.501) (xy 208.887081 126.374997)
				(xy 208.837299 126.307769) (xy 208.782894 126.224603) (xy 208.76781 126.171748) (xy 208.7625 126.099323)
			)
		)
	)
	(zone
		(net 78)
		(net_name "+1V8")
		(layer "In5.Cu")
		(name "$teardrop_padvia$")
		(hatch none 0.1)
		(priority 30009)
		(attr
			(teardrop
				(type padvia)
			)
		)
		(connect_pads yes
			(clearance 0)
		)
		(min_thickness 0.0254)
		(filled_areas_thickness no)
		(fill yes
			(thermal_gap 0.5)
			(thermal_bridge_width 0.5)
			(island_removal_mode 1)
			(island_area_min 10)
		)
		(polygon
			(pts
				(xy 251.789175 89.455693) (xy 251.867087 89.460406) (xy 251.925872 89.473393) (xy 252.016903 89.515495)
				(xy 252.102074 89.558193) (xy 252.190852 89.355693) (xy 252.102074 89.153193) (xy 252.016902 89.195892)
				(xy 251.924069 89.23856) (xy 251.86593 89.251137) (xy 251.789175 89.255693)
			)
		)
	)
	(zone
		(net 587)
		(net_name "/M.2 key E/SUSCLK")
		(layer "In5.Cu")
		(name "$teardrop_padvia$")
		(hatch none 0.1)
		(priority 30243)
		(attr
			(teardrop
				(type padvia)
			)
		)
		(connect_pads yes
			(clearance 0)
		)
		(min_thickness 0.0254)
		(filled_areas_thickness no)
		(fill yes
			(thermal_gap 0.5)
			(thermal_bridge_width 0.5)
			(island_removal_mode 1)
			(island_area_min 10)
		)
		(polygon
			(pts
				(xy 248.359835 79.932485) (xy 248.307326 79.978181) (xy 248.261331 80.004768) (xy 248.174882 80.025152)
				(xy 248.159549 80.026988) (xy 248.076813 80.039323) (xy 248.120001 80.260707) (xy 248.341385 80.303895)
				(xy 248.353719 80.22116) (xy 248.374057 80.123881) (xy 248.400765 80.075841) (xy 248.448223 80.020873)
			)
		)
	)
	(zone
		(net 330)
		(net_name "/Com Express 7 Interfaces/PCIe_{B2Ax4}.TX3+")
		(layer "In5.Cu")
		(name "$teardrop_padvia$")
		(hatch none 0.1)
		(priority 30080)
		(attr
			(teardrop
				(type padvia)
			)
		)
		(connect_pads yes
			(clearance 0)
		)
		(min_thickness 0.0254)
		(filled_areas_thickness no)
		(fill yes
			(thermal_gap 0.5)
			(thermal_bridge_width 0.5)
			(island_removal_mode 1)
			(island_area_min 10)
		)
		(polygon
			(pts
				(xy 216.177 167.410584) (xy 216.170104 167.273248) (xy 216.165724 167.192061) (xy 216.177177 167.093895)
				(xy 215.9565 167.049) (xy 215.79681 167.202394) (xy 215.864306 167.251472) (xy 215.892809 167.265811)
				(xy 215.933428 167.28711) (xy 215.967262 167.313802) (xy 215.990417 167.352691) (xy 215.999 167.410584)
			)
		)
	)
	(zone
		(net 527)
		(net_name "/Backplane/GPIO")
		(layer "In5.Cu")
		(name "$teardrop_padvia$")
		(hatch none 0.1)
		(priority 30233)
		(attr
			(teardrop
				(type padvia)
			)
		)
		(connect_pads yes
			(clearance 0)
		)
		(min_thickness 0.0254)
		(filled_areas_thickness no)
		(fill yes
			(thermal_gap 0.5)
			(thermal_bridge_width 0.5)
			(island_removal_mode 1)
			(island_area_min 10)
		)
		(polygon
			(pts
				(xy 311.589127 165.382485) (xy 311.536618 165.428181) (xy 311.490623 165.454768) (xy 311.404174 165.475152)
				(xy 311.388841 165.476988) (xy 311.306105 165.489323) (xy 311.349293 165.710707) (xy 311.570677 165.753895)
				(xy 311.583011 165.67116) (xy 311.603349 165.573881) (xy 311.630057 165.525841) (xy 311.677515 165.470873)
			)
		)
	)
	(zone
		(net 651)
		(net_name "/2xSFP+/KR to SFI #1/MDC")
		(layer "In5.Cu")
		(name "$teardrop_padvia$")
		(hatch none 0.1)
		(priority 30293)
		(attr
			(teardrop
				(type padvia)
			)
		)
		(connect_pads yes
			(clearance 0)
		)
		(min_thickness 0.0254)
		(filled_areas_thickness no)
		(fill yes
			(thermal_gap 0.5)
			(thermal_bridge_width 0.5)
			(island_removal_mode 1)
			(island_area_min 10)
		)
		(polygon
			(pts
				(xy 148.537099 139.198711) (xy 148.516029 139.170896) (xy 148.509496 139.145431) (xy 148.526442 139.102324)
				(xy 148.572829 139.054509) (xy 148.637081 138.985003) (xy 148.449293 138.859293) (xy 148.262919 138.985003)
				(xy 148.328069 139.108253) (xy 148.368721 139.189592) (xy 148.448711 139.287099)
			)
		)
	)
	(zone
		(net 735)
		(net_name "Net-(U43A-LS_OK_{IN_A})")
		(layer "In5.Cu")
		(name "$teardrop_padvia$")
		(hatch none 0.1)
		(priority 30238)
		(attr
			(teardrop
				(type padvia)
			)
		)
		(connect_pads yes
			(clearance 0)
		)
		(min_thickness 0.0254)
		(filled_areas_thickness no)
		(fill yes
			(thermal_gap 0.5)
			(thermal_bridge_width 0.5)
			(island_removal_mode 1)
			(island_area_min 10)
		)
		(polygon
			(pts
				(xy 155.689127 140.532485) (xy 155.636618 140.578181) (xy 155.590623 140.604768) (xy 155.504174 140.625152)
				(xy 155.488841 140.626988) (xy 155.406105 140.639323) (xy 155.449293 140.860707) (xy 155.670677 140.903895)
				(xy 155.683011 140.82116) (xy 155.703349 140.723881) (xy 155.730057 140.675841) (xy 155.777515 140.620873)
			)
		)
	)
	(zone
		(net 257)
		(net_name "/Com Express 7 Interfaces/PCIe_{B2Bx4}.TX1-")
		(layer "In5.Cu")
		(name "$teardrop_padvia$")
		(hatch none 0.1)
		(priority 30075)
		(attr
			(teardrop
				(type padvia)
			)
		)
		(connect_pads yes
			(clearance 0)
		)
		(min_thickness 0.0254)
		(filled_areas_thickness no)
		(fill yes
			(thermal_gap 0.5)
			(thermal_bridge_width 0.5)
			(island_removal_mode 1)
			(island_area_min 10)
		)
		(polygon
			(pts
				(xy 189.639416 166.302) (xy 189.776751 166.295104) (xy 189.857939 166.290724) (xy 189.956105 166.302177)
				(xy 190.001 166.0815) (xy 189.847605 165.92181) (xy 189.798527 165.989306) (xy 189.784187 166.01781)
				(xy 189.762888 166.058429) (xy 189.736197 166.092262) (xy 189.697308 166.115417) (xy 189.639416 166.124)
			)
		)
	)
	(zone
		(net 649)
		(net_name "/2xSFP+/KR to SFI #1/MDIO")
		(layer "In5.Cu")
		(name "$teardrop_padvia$")
		(hatch none 0.1)
		(priority 30278)
		(attr
			(teardrop
				(type padvia)
			)
		)
		(connect_pads yes
			(clearance 0)
		)
		(min_thickness 0.0254)
		(filled_areas_thickness no)
		(fill yes
			(thermal_gap 0.5)
			(thermal_bridge_width 0.5)
			(island_removal_mode 1)
			(island_area_min 10)
		)
		(polygon
			(pts
				(xy 148.210873 138.187515) (xy 148.263382 138.141819) (xy 148.309376 138.115231) (xy 148.395824 138.094847)
				(xy 148.41116 138.093011) (xy 148.493895 138.080677) (xy 148.450707 137.859293) (xy 148.229323 137.816105)
				(xy 148.216988 137.898841) (xy 148.196651 137.996119) (xy 148.169943 138.044159) (xy 148.122485 138.099127)
			)
		)
	)
	(zone
		(net 330)
		(net_name "/Com Express 7 Interfaces/PCIe_{B2Ax4}.TX3+")
		(layer "In5.Cu")
		(name "$teardrop_padvia$")
		(hatch none 0.1)
		(priority 30095)
		(attr
			(teardrop
				(type padvia)
			)
		)
		(connect_pads yes
			(clearance 0)
		)
		(min_thickness 0.0254)
		(filled_areas_thickness no)
		(fill yes
			(thermal_gap 0.5)
			(thermal_bridge_width 0.5)
			(island_removal_mode 1)
			(island_area_min 10)
		)
		(polygon
			(pts
				(xy 232.543916 149.076) (xy 232.586847 149.080759) (xy 232.618261 149.094072) (xy 232.657552 149.138959)
				(xy 232.676575 149.17847) (xy 232.712919 149.248003) (xy 232.901 149.123) (xy 232.89053 148.902323)
				(xy 232.710402 148.901698) (xy 232.543916 148.898)
			)
		)
	)
	(zone
		(net 759)
		(net_name "Net-(U45B-LS_OK_{OUT_B})")
		(layer "In5.Cu")
		(name "$teardrop_padvia$")
		(hatch none 0.1)
		(priority 30131)
		(attr
			(teardrop
				(type padvia)
			)
		)
		(connect_pads yes
			(clearance 0)
		)
		(min_thickness 0.0254)
		(filled_areas_thickness no)
		(fill yes
			(thermal_gap 0.5)
			(thermal_bridge_width 0.5)
			(island_removal_mode 1)
			(island_area_min 10)
		)
		(polygon
			(pts
				(xy 131.188759 139.527147) (xy 131.212014 139.557157) (xy 131.220358 139.584496) (xy 131.206091 139.630084)
				(xy 131.158681 139.68335) (xy 131.110334 139.735708) (xy 131.076416 139.798979) (xy 131.290707 139.860707)
				(xy 131.476206 139.734122) (xy 131.410128 139.620813) (xy 131.362801 139.5389) (xy 131.277147 139.438759)
			)
		)
	)
	(zone
		(net 339)
		(net_name "/Com Express 7 Interfaces/SDIO.CLK")
		(layer "In5.Cu")
		(name "$teardrop_padvia$")
		(hatch none 0.1)
		(priority 30051)
		(attr
			(teardrop
				(type padvia)
			)
		)
		(connect_pads yes
			(clearance 0)
		)
		(min_thickness 0.0254)
		(filled_areas_thickness no)
		(fill yes
			(thermal_gap 0.5)
			(thermal_bridge_width 0.5)
			(island_removal_mode 1)
			(island_area_min 10)
		)
		(polygon
			(pts
				(xy 166.022562 160.8775) (xy 166.07139 160.88224) (xy 166.108373 160.89542) (xy 166.158512 160.940329)
				(xy 166.183911 160.97862) (xy 166.215778 161.026053) (xy 166.260146 161.07223) (xy 166.401 160.9)
				(xy 166.356105 160.679323) (xy 166.280406 160.695247) (xy 166.170759 160.715506) (xy 166.022562 160.7225)
			)
		)
	)
	(zone
		(net 750)
		(net_name "Net-(U45C-CLKOUTA+)")
		(layer "In5.Cu")
		(name "$teardrop_padvia$")
		(hatch none 0.1)
		(priority 30116)
		(attr
			(teardrop
				(type padvia)
			)
		)
		(connect_pads yes
			(clearance 0)
		)
		(min_thickness 0.0254)
		(filled_areas_thickness no)
		(fill yes
			(thermal_gap 0.5)
			(thermal_bridge_width 0.5)
			(island_removal_mode 1)
			(island_area_min 10)
		)
		(polygon
			(pts
				(xy 136.546627 139.549985) (xy 136.499997 139.589893) (xy 136.457988 139.613136) (xy 136.378777 139.628343)
				(xy 136.352754 139.629237) (xy 136.246105 139.639323) (xy 136.289293 139.860707) (xy 136.490161 139.953422)
				(xy 136.53019 139.83079) (xy 136.55884 139.740549) (xy 136.587806 139.692595) (xy 136.635015 139.638373)
			)
		)
	)
	(zone
		(net 252)
		(net_name "/Com Express 7 Interfaces/PCIe_{B2Bx4}.RX1-")
		(layer "In5.Cu")
		(name "$teardrop_padvia$")
		(hatch none 0.1)
		(priority 30094)
		(attr
			(teardrop
				(type padvia)
			)
		)
		(connect_pads yes
			(clearance 0)
		)
		(min_thickness 0.0254)
		(filled_areas_thickness no)
		(fill yes
			(thermal_gap 0.5)
			(thermal_bridge_width 0.5)
			(island_removal_mode 1)
			(island_area_min 10)
		)
		(polygon
			(pts
				(xy 194.924267 159.714326) (xy 194.832031 159.816315) (xy 194.777722 159.876819) (xy 194.700211 159.938133)
				(xy 194.824507 160.125921) (xy 195.045891 160.13037) (xy 195.032866 160.047939) (xy 195.022851 160.017647)
				(xy 195.00919 159.973864) (xy 195.004139 159.931067) (xy 195.015265 159.887196) (xy 195.050132 159.840191)
			)
		)
	)
	(zone
		(net 429)
		(net_name "/2xSFP+/MDIO1.MDC")
		(layer "In5.Cu")
		(name "$teardrop_padvia$")
		(hatch none 0.1)
		(priority 30112)
		(attr
			(teardrop
				(type padvia)
			)
		)
		(connect_pads yes
			(clearance 0)
		)
		(min_thickness 0.0254)
		(filled_areas_thickness no)
		(fill yes
			(thermal_gap 0.5)
			(thermal_bridge_width 0.5)
			(island_removal_mode 1)
			(island_area_min 10)
		)
		(polygon
			(pts
				(xy 127.212793 143.2625) (xy 127.127777 143.25789) (xy 127.065099 143.245618) (xy 126.995931 143.221603)
				(xy 126.878421 143.183268) (xy 126.824 143.4) (xy 126.956389 143.580694) (xy 127.022401 143.514237)
				(xy 127.042855 143.485714) (xy 127.070877 143.447848) (xy 127.10379 143.416589) (xy 127.148719 143.395339)
				(xy 127.212793 143.3875)
			)
		)
	)
	(zone
		(net 742)
		(net_name "/2xSFP+/KR to SFI #2/TDI")
		(layer "In5.Cu")
		(name "$teardrop_padvia$")
		(hatch none 0.1)
		(priority 30113)
		(attr
			(teardrop
				(type padvia)
			)
		)
		(connect_pads yes
			(clearance 0)
		)
		(min_thickness 0.0254)
		(filled_areas_thickness no)
		(fill yes
			(thermal_gap 0.5)
			(thermal_bridge_width 0.5)
			(island_removal_mode 1)
			(island_area_min 10)
		)
		(polygon
			(pts
				(xy 136.546627 138.549985) (xy 136.499997 138.589893) (xy 136.457988 138.613136) (xy 136.378777 138.628343)
				(xy 136.352754 138.629237) (xy 136.246105 138.639323) (xy 136.289293 138.860707) (xy 136.490161 138.953422)
				(xy 136.53019 138.83079) (xy 136.55884 138.740549) (xy 136.587806 138.692595) (xy 136.635015 138.638373)
			)
		)
	)
	(zone
		(net 757)
		(net_name "Net-(U45B-LOSB)")
		(layer "In5.Cu")
		(name "$teardrop_padvia$")
		(hatch none 0.1)
		(priority 30205)
		(attr
			(teardrop
				(type padvia)
			)
		)
		(connect_pads yes
			(clearance 0)
		)
		(min_thickness 0.0254)
		(filled_areas_thickness no)
		(fill yes
			(thermal_gap 0.5)
			(thermal_bridge_width 0.5)
			(island_removal_mode 1)
			(island_area_min 10)
		)
		(polygon
			(pts
				(xy 128.5025 130.540677) (xy 128.507318 130.471236) (xy 128.52104 130.419912) (xy 128.567755 130.34437)
				(xy 128.577299 130.332229) (xy 128.627081 130.265003) (xy 128.44 130.139) (xy 128.252919 130.265003)
				(xy 128.302701 130.332231) (xy 128.357106 130.415397) (xy 128.37219 130.468251) (xy 128.3775 130.540677)
			)
		)
	)
	(zone
		(net 372)
		(net_name "/Com Express 7 MGMT/I2C.SDA")
		(layer "In5.Cu")
		(name "$teardrop_padvia$")
		(hatch none 0.1)
		(priority 30280)
		(attr
			(teardrop
				(type padvia)
			)
		)
		(connect_pads yes
			(clearance 0)
		)
		(min_thickness 0.0254)
		(filled_areas_thickness no)
		(fill yes
			(thermal_gap 0.5)
			(thermal_bridge_width 0.5)
			(island_removal_mode 1)
			(island_area_min 10)
		)
		(polygon
			(pts
				(xy 303.152515 94.929127) (xy 303.106819 94.876618) (xy 303.080231 94.830623) (xy 303.059847 94.744175)
				(xy 303.058011 94.72884) (xy 303.045677 94.646105) (xy 302.824293 94.689293) (xy 302.781105 94.910677)
				(xy 302.86384 94.923011) (xy 302.961119 94.943349) (xy 303.009159 94.970057) (xy 303.064127 95.017515)
			)
		)
	)
	(zone
		(net 751)
		(net_name "Net-(U45C-CLKOUTA-)")
		(layer "In5.Cu")
		(name "$teardrop_padvia$")
		(hatch none 0.1)
		(priority 30201)
		(attr
			(teardrop
				(type padvia)
			)
		)
		(connect_pads yes
			(clearance 0)
		)
		(min_thickness 0.0254)
		(filled_areas_thickness no)
		(fill yes
			(thermal_gap 0.5)
			(thermal_bridge_width 0.5)
			(island_removal_mode 1)
			(island_area_min 10)
		)
		(polygon
			(pts
				(xy 130.4525 130.910677) (xy 130.457318 130.841236) (xy 130.47104 130.789912) (xy 130.517755 130.71437)
				(xy 130.527299 130.702229) (xy 130.577081 130.635003) (xy 130.39 130.509) (xy 130.202919 130.635003)
				(xy 130.252701 130.702231) (xy 130.307106 130.785397) (xy 130.32219 130.838251) (xy 130.3275 130.910677)
			)
		)
	)
	(zone
		(net 530)
		(net_name "/M.2 key M #2/~{CLKREQ}")
		(layer "In5.Cu")
		(name "$teardrop_padvia$")
		(hatch none 0.1)
		(priority 30228)
		(attr
			(teardrop
				(type padvia)
			)
		)
		(connect_pads yes
			(clearance 0)
		)
		(min_thickness 0.0254)
		(filled_areas_thickness no)
		(fill yes
			(thermal_gap 0.5)
			(thermal_bridge_width 0.5)
			(island_removal_mode 1)
			(island_area_min 10)
		)
		(polygon
			(pts
				(xy 283.489127 93.972485) (xy 283.436618 94.018181) (xy 283.390623 94.044768) (xy 283.304174 94.065152)
				(xy 283.288841 94.066988) (xy 283.206105 94.079323) (xy 283.249293 94.300707) (xy 283.470677 94.343895)
				(xy 283.483011 94.26116) (xy 283.503349 94.163881) (xy 283.530057 94.115841) (xy 283.577515 94.060873)
			)
		)
	)
	(zone
		(net 726)
		(net_name "/2xSFP+/KR to SFI #1/~{TRST}")
		(layer "In5.Cu")
		(name "$teardrop_padvia$")
		(hatch none 0.1)
		(priority 30247)
		(attr
			(teardrop
				(type padvia)
			)
		)
		(connect_pads yes
			(clearance 0)
		)
		(min_thickness 0.0254)
		(filled_areas_thickness no)
		(fill yes
			(thermal_gap 0.5)
			(thermal_bridge_width 0.5)
			(island_removal_mode 1)
			(island_area_min 10)
		)
		(polygon
			(pts
				(xy 152.689127 135.532485) (xy 152.636618 135.578181) (xy 152.590623 135.604768) (xy 152.504174 135.625152)
				(xy 152.488841 135.626988) (xy 152.406105 135.639323) (xy 152.449293 135.860707) (xy 152.670677 135.903895)
				(xy 152.683011 135.82116) (xy 152.703349 135.723881) (xy 152.730057 135.675841) (xy 152.777515 135.620873)
			)
		)
	)
	(zone
		(net 377)
		(net_name "/Com Express 7 Interfaces/USB1.D-")
		(layer "In5.Cu")
		(name "$teardrop_padvia$")
		(hatch none 0.1)
		(priority 30124)
		(attr
			(teardrop
				(type padvia)
			)
		)
		(connect_pads yes
			(clearance 0)
		)
		(min_thickness 0.0254)
		(filled_areas_thickness no)
		(fill yes
			(thermal_gap 0.5)
			(thermal_bridge_width 0.5)
			(island_removal_mode 1)
			(island_area_min 10)
		)
		(polygon
			(pts
				(xy 204.548 142.596584) (xy 204.545484 142.415841) (xy 204.543677 142.251749) (xy 204.323 142.249)
				(xy 204.197997 142.437081) (xy 204.283589 142.475787) (xy 204.324472 142.491256) (xy 204.357994 142.51208)
				(xy 204.380667 142.544958) (xy 204.389 142.596584)
			)
		)
	)
	(zone
		(net 737)
		(net_name "Net-(U43B-LOSB)")
		(layer "In5.Cu")
		(name "$teardrop_padvia$")
		(hatch none 0.1)
		(priority 30197)
		(attr
			(teardrop
				(type padvia)
			)
		)
		(connect_pads yes
			(clearance 0)
		)
		(min_thickness 0.0254)
		(filled_areas_thickness no)
		(fill yes
			(thermal_gap 0.5)
			(thermal_bridge_width 0.5)
			(island_removal_mode 1)
			(island_area_min 10)
		)
		(polygon
			(pts
				(xy 146.6625 130.540677) (xy 146.667318 130.471236) (xy 146.68104 130.419912) (xy 146.727755 130.34437)
				(xy 146.737299 130.332229) (xy 146.787081 130.265003) (xy 146.6 130.139) (xy 146.412919 130.265003)
				(xy 146.462701 130.332231) (xy 146.517106 130.415397) (xy 146.53219 130.468251) (xy 146.5375 130.540677)
			)
		)
	)
	(zone
		(net 573)
		(net_name "/GPIO expander/GPIOEX0")
		(layer "In5.Cu")
		(name "$teardrop_padvia$")
		(hatch none 0.1)
		(priority 30273)
		(attr
			(teardrop
				(type padvia)
			)
		)
		(connect_pads yes
			(clearance 0)
		)
		(min_thickness 0.0254)
		(filled_areas_thickness no)
		(fill yes
			(thermal_gap 0.5)
			(thermal_bridge_width 0.5)
			(island_removal_mode 1)
			(island_area_min 10)
		)
		(polygon
			(pts
				(xy 125.710873 83.387515) (xy 125.763382 83.341819) (xy 125.809376 83.315231) (xy 125.895824 83.294847)
				(xy 125.91116 83.293011) (xy 125.993895 83.280677) (xy 125.950707 83.059293) (xy 125.729323 83.016105)
				(xy 125.716988 83.098841) (xy 125.696651 83.196119) (xy 125.669943 83.244159) (xy 125.622485 83.299127)
			)
		)
	)
	(zone
		(net 244)
		(net_name "/Com Express 7 Interfaces/PCIe_{B2Bx4}.RX2+")
		(layer "In5.Cu")
		(name "$teardrop_padvia$")
		(hatch none 0.1)
		(priority 30060)
		(attr
			(teardrop
				(type padvia)
			)
		)
		(connect_pads yes
			(clearance 0)
		)
		(min_thickness 0.0254)
		(filled_areas_thickness no)
		(fill yes
			(thermal_gap 0.5)
			(thermal_bridge_width 0.5)
			(island_removal_mode 1)
			(island_area_min 10)
		)
		(polygon
			(pts
				(xy 192.360584 160.624) (xy 192.315854 160.619259) (xy 192.282389 160.606069) (xy 192.238876 160.561306)
				(xy 192.215811 160.517809) (xy 192.189834 160.468871) (xy 192.152394 160.42181) (xy 191.999 160.5815)
				(xy 192.043895 160.802177) (xy 192.120958 160.791552) (xy 192.18266 160.791818) (xy 192.223248 160.795104)
				(xy 192.360584 160.802)
			)
		)
	)
	(zone
		(net 738)
		(net_name "Net-(U43B-LS_OK_{IN_B})")
		(layer "In5.Cu")
		(name "$teardrop_padvia$")
		(hatch none 0.1)
		(priority 30196)
		(attr
			(teardrop
				(type padvia)
			)
		)
		(connect_pads yes
			(clearance 0)
		)
		(min_thickness 0.0254)
		(filled_areas_thickness no)
		(fill yes
			(thermal_gap 0.5)
			(thermal_bridge_width 0.5)
			(island_removal_mode 1)
			(island_area_min 10)
		)
		(polygon
			(pts
				(xy 146.0125 130.910677) (xy 146.017318 130.841236) (xy 146.03104 130.789912) (xy 146.077755 130.71437)
				(xy 146.087299 130.702229) (xy 146.137081 130.635003) (xy 145.95 130.509) (xy 145.762919 130.635003)
				(xy 145.812701 130.702231) (xy 145.867106 130.785397) (xy 145.88219 130.838251) (xy 145.8875 130.910677)
			)
		)
	)
	(zone
		(net 544)
		(net_name "Net-(Q10-E)")
		(layer "In5.Cu")
		(name "$teardrop_padvia$")
		(hatch none 0.1)
		(priority 30203)
		(attr
			(teardrop
				(type padvia)
			)
		)
		(connect_pads yes
			(clearance 0)
		)
		(min_thickness 0.0254)
		(filled_areas_thickness no)
		(fill yes
			(thermal_gap 0.5)
			(thermal_bridge_width 0.5)
			(island_removal_mode 1)
			(island_area_min 10)
		)
		(polygon
			(pts
				(xy 255.8125 85.500677) (xy 255.817318 85.431236) (xy 255.83104 85.379912) (xy 255.877755 85.30437)
				(xy 255.887299 85.292229) (xy 255.937081 85.225003) (xy 255.75 85.099) (xy 255.562919 85.225003)
				(xy 255.612701 85.292231) (xy 255.667106 85.375397) (xy 255.68219 85.428251) (xy 255.6875 85.500677)
			)
		)
	)
	(zone
		(net 244)
		(net_name "/Com Express 7 Interfaces/PCIe_{B2Bx4}.RX2+")
		(layer "In5.Cu")
		(name "$teardrop_padvia$")
		(hatch none 0.1)
		(priority 30103)
		(attr
			(teardrop
				(type padvia)
			)
		)
		(connect_pads yes
			(clearance 0)
		)
		(min_thickness 0.0254)
		(filled_areas_thickness no)
		(fill yes
			(thermal_gap 0.5)
			(thermal_bridge_width 0.5)
			(island_removal_mode 1)
			(island_area_min 10)
		)
		(polygon
			(pts
				(xy 187.156084 125.898) (xy 186.989597 125.901698) (xy 186.80947 125.902323) (xy 186.799 126.123)
				(xy 186.987081 126.248003) (xy 187.023424 126.178471) (xy 187.042701 126.138505) (xy 187.066786 126.105942)
				(xy 187.102356 126.084026) (xy 187.156084 126.076)
			)
		)
	)
	(zone
		(net 264)
		(net_name "/Com Express 7 Interfaces/PCIe_{B2Bx4}.RX0+")
		(layer "In5.Cu")
		(name "$teardrop_padvia$")
		(hatch none 0.1)
		(priority 30104)
		(attr
			(teardrop
				(type padvia)
			)
		)
		(connect_pads yes
			(clearance 0)
		)
		(min_thickness 0.0254)
		(filled_areas_thickness no)
		(fill yes
			(thermal_gap 0.5)
			(thermal_bridge_width 0.5)
			(island_removal_mode 1)
			(island_area_min 10)
		)
		(polygon
			(pts
				(xy 187.156084 122.898) (xy 186.989597 122.901698) (xy 186.80947 122.902323) (xy 186.799 123.123)
				(xy 186.987081 123.248003) (xy 187.023424 123.178471) (xy 187.042701 123.138505) (xy 187.066786 123.105942)
				(xy 187.102356 123.084026) (xy 187.156084 123.076)
			)
		)
	)
	(zone
		(net 200)
		(net_name "/OCuLink/~{PERST_D0}")
		(layer "In5.Cu")
		(name "$teardrop_padvia$")
		(hatch none 0.1)
		(priority 30258)
		(attr
			(teardrop
				(type padvia)
			)
		)
		(connect_pads yes
			(clearance 0)
		)
		(min_thickness 0.0254)
		(filled_areas_thickness no)
		(fill yes
			(thermal_gap 0.5)
			(thermal_bridge_width 0.5)
			(island_removal_mode 1)
			(island_area_min 10)
		)
		(polygon
			(pts
				(xy 120.022485 162.320873) (xy 120.068181 162.373382) (xy 120.094768 162.419376) (xy 120.115152 162.505825)
				(xy 120.116988 162.521158) (xy 120.129323 162.603895) (xy 120.350707 162.560707) (xy 120.393895 162.339323)
				(xy 120.311158 162.326988) (xy 120.21388 162.306651) (xy 120.16584 162.279943) (xy 120.110873 162.232485)
			)
		)
	)
	(zone
		(net 324)
		(net_name "/Com Express 7 Interfaces/PCIe_{B2Ax4}.TX0+")
		(layer "In5.Cu")
		(name "$teardrop_padvia$")
		(hatch none 0.1)
		(priority 30055)
		(attr
			(teardrop
				(type padvia)
			)
		)
		(connect_pads yes
			(clearance 0)
		)
		(min_thickness 0.0254)
		(filled_areas_thickness no)
		(fill yes
			(thermal_gap 0.5)
			(thermal_bridge_width 0.5)
			(island_removal_mode 1)
			(island_area_min 10)
		)
		(polygon
			(pts
				(xy 210.999 166.639416) (xy 210.994259 166.684146) (xy 210.981069 166.71761) (xy 210.936306 166.761123)
				(xy 210.89281 166.784187) (xy 210.843872 166.810164) (xy 210.79681 166.847605) (xy 210.9565 167.001)
				(xy 211.177177 166.956105) (xy 211.166552 166.879042) (xy 211.166818 166.817339) (xy 211.170104 166.776751)
				(xy 211.177 166.639416)
			)
		)
	)
	(zone
		(net 434)
		(net_name "/Com Express 7 MGMT/~{TYPE1}")
		(layer "In5.Cu")
		(name "$teardrop_padvia$")
		(hatch none 0.1)
		(priority 30241)
		(attr
			(teardrop
				(type padvia)
			)
		)
		(connect_pads yes
			(clearance 0)
		)
		(min_thickness 0.0254)
		(filled_areas_thickness no)
		(fill yes
			(thermal_gap 0.5)
			(thermal_bridge_width 0.5)
			(island_removal_mode 1)
			(island_area_min 10)
		)
		(polygon
			(pts
				(xy 245.939127 149.272485) (xy 245.886618 149.318181) (xy 245.840623 149.344768) (xy 245.754174 149.365152)
				(xy 245.738841 149.366988) (xy 245.656105 149.379323) (xy 245.699293 149.600707) (xy 245.920677 149.643895)
				(xy 245.933011 149.56116) (xy 245.953349 149.463881) (xy 245.980057 149.415841) (xy 246.027515 149.360873)
			)
		)
	)
	(zone
		(net 490)
		(net_name "/2xSFP+/MDIO1.MDIO")
		(layer "In5.Cu")
		(name "$teardrop_padvia$")
		(hatch none 0.1)
		(priority 30290)
		(attr
			(teardrop
				(type padvia)
			)
		)
		(connect_pads yes
			(clearance 0)
		)
		(min_thickness 0.0254)
		(filled_areas_thickness no)
		(fill yes
			(thermal_gap 0.5)
			(thermal_bridge_width 0.5)
			(island_removal_mode 1)
			(island_area_min 10)
		)
		(polygon
			(pts
				(xy 126.009515 152.751127) (xy 125.963819 152.698618) (xy 125.937231 152.652623) (xy 125.916847 152.566175)
				(xy 125.915011 152.55084) (xy 125.902677 152.468105) (xy 125.681293 152.511293) (xy 125.638105 152.732677)
				(xy 125.72084 152.745011) (xy 125.818119 152.765349) (xy 125.866159 152.792057) (xy 125.921127 152.839515)
			)
		)
	)
	(zone
		(net 321)
		(net_name "/Com Express 7 Interfaces/SDIO.DAT0")
		(layer "In5.Cu")
		(name "$teardrop_padvia$")
		(hatch none 0.1)
		(priority 30044)
		(attr
			(teardrop
				(type padvia)
			)
		)
		(connect_pads yes
			(clearance 0)
		)
		(min_thickness 0.0254)
		(filled_areas_thickness no)
		(fill yes
			(thermal_gap 0.5)
			(thermal_bridge_width 0.5)
			(island_removal_mode 1)
			(island_area_min 10)
		)
		(polygon
			(pts
				(xy 166.001852 159.9275) (xy 166.059889 159.932238) (xy 166.104072 159.945401) (xy 166.167897 159.990465)
				(xy 166.189909 160.012727) (xy 166.274997 160.087081) (xy 166.401 159.9) (xy 166.33577 159.687745)
				(xy 166.230712 159.7264) (xy 166.136854 159.759204) (xy 166.001852 159.7725)
			)
		)
	)
	(zone
		(net 327)
		(net_name "/Com Express 7 Interfaces/PCIe_{B2Ax4}.TX1-")
		(layer "In5.Cu")
		(name "$teardrop_padvia$")
		(hatch none 0.1)
		(priority 30071)
		(attr
			(teardrop
				(type padvia)
			)
		)
		(connect_pads yes
			(clearance 0)
		)
		(min_thickness 0.0254)
		(filled_areas_thickness no)
		(fill yes
			(thermal_gap 0.5)
			(thermal_bridge_width 0.5)
			(island_removal_mode 1)
			(island_area_min 10)
		)
		(polygon
			(pts
				(xy 229.926 145.360584) (xy 229.930741 145.315854) (xy 229.943931 145.282389) (xy 229.988694 145.238875)
				(xy 230.03219 145.215811) (xy 230.081128 145.189834) (xy 230.128189 145.152394) (xy 229.9685 144.999)
				(xy 229.747823 145.043895) (xy 229.758447 145.120959) (xy 229.758182 145.182662) (xy 229.754896 145.223248)
				(xy 229.748 145.360584)
			)
		)
	)
	(zone
		(net 874)
		(net_name "/2xSFP+/SDA1")
		(layer "In5.Cu")
		(name "$teardrop_padvia$")
		(hatch none 0.1)
		(priority 30175)
		(attr
			(teardrop
				(type padvia)
			)
		)
		(connect_pads yes
			(clearance 0)
		)
		(min_thickness 0.0254)
		(filled_areas_thickness no)
		(fill yes
			(thermal_gap 0.5)
			(thermal_bridge_width 0.5)
			(island_removal_mode 1)
			(island_area_min 10)
		)
		(polygon
			(pts
				(xy 165.199323 144.4625) (xy 165.268764 144.467318) (xy 165.320088 144.48104) (xy 165.395629 144.527755)
				(xy 165.407769 144.537299) (xy 165.474997 144.587081) (xy 165.601 144.4) (xy 165.474997 144.212919)
				(xy 165.407768 144.262702) (xy 165.324602 144.317106) (xy 165.271748 144.33219) (xy 165.199323 144.3375)
			)
		)
	)
	(zone
		(net 328)
		(net_name "/Com Express 7 Interfaces/PCIe_{B2Ax4}.TX2+")
		(layer "In5.Cu")
		(name "$teardrop_padvia$")
		(hatch none 0.1)
		(priority 30053)
		(attr
			(teardrop
				(type padvia)
			)
		)
		(connect_pads yes
			(clearance 0)
		)
		(min_thickness 0.0254)
		(filled_areas_thickness no)
		(fill yes
			(thermal_gap 0.5)
			(thermal_bridge_width 0.5)
			(island_removal_mode 1)
			(island_area_min 10)
		)
		(polygon
			(pts
				(xy 213.999 166.639416) (xy 213.994259 166.684146) (xy 213.981069 166.71761) (xy 213.936306 166.761123)
				(xy 213.89281 166.784187) (xy 213.843872 166.810164) (xy 213.79681 166.847605) (xy 213.9565 167.001)
				(xy 214.177177 166.956105) (xy 214.166552 166.879042) (xy 214.166818 166.817339) (xy 214.170104 166.776751)
				(xy 214.177 166.639416)
			)
		)
	)
	(zone
		(net 543)
		(net_name "Net-(Q10-B)")
		(layer "In5.Cu")
		(name "$teardrop_padvia$")
		(hatch none 0.1)
		(priority 30180)
		(attr
			(teardrop
				(type padvia)
			)
		)
		(connect_pads yes
			(clearance 0)
		)
		(min_thickness 0.0254)
		(filled_areas_thickness no)
		(fill yes
			(thermal_gap 0.5)
			(thermal_bridge_width 0.5)
			(island_removal_mode 1)
			(island_area_min 10)
		)
		(polygon
			(pts
				(xy 315.599323 111.7715) (xy 315.668764 111.776318) (xy 315.720088 111.79004) (xy 315.795629 111.836755)
				(xy 315.807769 111.846299) (xy 315.874997 111.896081) (xy 316.001 111.709) (xy 315.874997 111.521919)
				(xy 315.807768 111.571702) (xy 315.724602 111.626106) (xy 315.671748 111.64119) (xy 315.599323 111.6465)
			)
		)
	)
	(zone
		(net 741)
		(net_name "Net-(U45C-REFCLK1-)")
		(layer "In5.Cu")
		(name "$teardrop_padvia$")
		(hatch none 0.1)
		(priority 30133)
		(attr
			(teardrop
				(type padvia)
			)
		)
		(connect_pads yes
			(clearance 0)
		)
		(min_thickness 0.0254)
		(filled_areas_thickness no)
		(fill yes
			(thermal_gap 0.5)
			(thermal_bridge_width 0.5)
			(island_removal_mode 1)
			(island_area_min 10)
		)
		(polygon
			(pts
				(xy 126.6275 130.988692) (xy 126.622969 130.883055) (xy 126.611254 130.807674) (xy 126.600621 130.761394)
				(xy 126.575677 130.639877) (xy 126.355 130.674) (xy 126.23976 130.866125) (xy 126.310477 130.889935)
				(xy 126.374855 130.895018) (xy 126.424104 130.898455) (xy 126.464726 130.909813) (xy 126.492324 130.937193)
				(xy 126.5025 130.988692)
			)
		)
	)
	(zone
		(net 165)
		(net_name "/2xSFP+/SCL0")
		(layer "In5.Cu")
		(name "$teardrop_padvia$")
		(hatch none 0.1)
		(priority 30184)
		(attr
			(teardrop
				(type padvia)
			)
		)
		(connect_pads yes
			(clearance 0)
		)
		(min_thickness 0.0254)
		(filled_areas_thickness no)
		(fill yes
			(thermal_gap 0.5)
			(thermal_bridge_width 0.5)
			(island_removal_mode 1)
			(island_area_min 10)
		)
		(polygon
			(pts
				(xy 165.099323 147.7625) (xy 165.168764 147.767318) (xy 165.220088 147.78104) (xy 165.295629 147.827755)
				(xy 165.307769 147.837299) (xy 165.374997 147.887081) (xy 165.501 147.7) (xy 165.374997 147.512919)
				(xy 165.307768 147.562702) (xy 165.224602 147.617106) (xy 165.171748 147.63219) (xy 165.099323 147.6375)
			)
		)
	)
	(zone
		(net 345)
		(net_name "/Com Express 7 MGMT/SER0.RX")
		(layer "In5.Cu")
		(name "$teardrop_padvia$")
		(hatch none 0.1)
		(priority 30174)
		(attr
			(teardrop
				(type padvia)
			)
		)
		(connect_pads yes
			(clearance 0)
		)
		(min_thickness 0.0254)
		(filled_areas_thickness no)
		(fill yes
			(thermal_gap 0.5)
			(thermal_bridge_width 0.5)
			(island_removal_mode 1)
			(island_area_min 10)
		)
		(polygon
			(pts
				(xy 215.9375 145.799323) (xy 215.932682 145.868763) (xy 215.91896 145.920087) (xy 215.872245 145.995628)
				(xy 215.862702 146.007768) (xy 215.812919 146.074997) (xy 216 146.201) (xy 216.187081 146.074997)
				(xy 216.137299 146.007769) (xy 216.082894 145.924603) (xy 216.06781 145.871748) (xy 216.0625 145.799323)
			)
		)
	)
	(zone
		(net 378)
		(net_name "/Com Express 7 Interfaces/USB1.D+")
		(layer "In5.Cu")
		(name "$teardrop_padvia$")
		(hatch none 0.1)
		(priority 30147)
		(attr
			(teardrop
				(type padvia)
			)
		)
		(connect_pads yes
			(clearance 0)
		)
		(min_thickness 0.0254)
		(filled_areas_thickness no)
		(fill yes
			(thermal_gap 0.5)
			(thermal_bridge_width 0.5)
			(island_removal_mode 1)
			(island_area_min 10)
		)
		(polygon
			(pts
				(xy 197.770379 164.923871) (xy 197.681282 165.022548) (xy 197.628838 165.081078) (xy 197.553039 165.140961)
				(xy 197.677335 165.328749) (xy 197.898719 165.284147) (xy 197.868438 165.199103) (xy 197.851448 165.158386)
				(xy 197.8434 165.119246) (xy 197.851463 165.079334) (xy 197.882809 165.036301)
			)
		)
	)
	(zone
		(net 78)
		(net_name "+1V8")
		(layer "In5.Cu")
		(name "$teardrop_padvia$")
		(hatch none 0.1)
		(priority 30015)
		(attr
			(teardrop
				(type padvia)
			)
		)
		(connect_pads yes
			(clearance 0)
		)
		(min_thickness 0.0254)
		(filled_areas_thickness no)
		(fill yes
			(thermal_gap 0.5)
			(thermal_bridge_width 0.5)
			(island_removal_mode 1)
			(island_area_min 10)
		)
		(polygon
			(pts
				(xy 252.590529 89.255693) (xy 252.512617 89.25098) (xy 252.453833 89.237993) (xy 252.362801 89.195891)
				(xy 252.27763 89.153193) (xy 252.188852 89.355693) (xy 252.27763 89.558193) (xy 252.362799 89.515495)
				(xy 252.455634 89.472826) (xy 252.513773 89.460249) (xy 252.590529 89.455693)
			)
		)
	)
	(zone
		(net 296)
		(net_name "/2xUSB3.0+RJ45/GbE.CTREF")
		(layer "In5.Cu")
		(name "$teardrop_padvia$")
		(hatch none 0.1)
		(priority 30026)
		(attr
			(teardrop
				(type padvia)
			)
		)
		(connect_pads yes
			(clearance 0)
		)
		(min_thickness 0.0254)
		(filled_areas_thickness no)
		(fill yes
			(thermal_gap 0.5)
			(thermal_bridge_width 0.5)
			(island_removal_mode 1)
			(island_area_min 10)
		)
		(polygon
			(pts
				(xy 148.654031 123.01261) (xy 148.602272 122.954186) (xy 148.569889 122.903436) (xy 148.53529 122.809297)
				(xy 148.505257 122.718879) (xy 148.299293 122.799293) (xy 148.218879 123.005257) (xy 148.309297 123.03529)
				(xy 148.405111 123.070762) (xy 148.455114 123.102979) (xy 148.51261 123.154031)
			)
		)
	)
	(zone
		(net 745)
		(net_name "/2xSFP+/KR to SFI #2/TCK")
		(layer "In5.Cu")
		(name "$teardrop_padvia$")
		(hatch none 0.1)
		(priority 30115)
		(attr
			(teardrop
				(type padvia)
			)
		)
		(connect_pads yes
			(clearance 0)
		)
		(min_thickness 0.0254)
		(filled_areas_thickness no)
		(fill yes
			(thermal_gap 0.5)
			(thermal_bridge_width 0.5)
			(island_removal_mode 1)
			(island_area_min 10)
		)
		(polygon
			(pts
				(xy 135.546627 138.549985) (xy 135.499997 138.589893) (xy 135.457988 138.613136) (xy 135.378777 138.628343)
				(xy 135.352754 138.629237) (xy 135.246105 138.639323) (xy 135.289293 138.860707) (xy 135.490161 138.953422)
				(xy 135.53019 138.83079) (xy 135.55884 138.740549) (xy 135.587806 138.692595) (xy 135.635015 138.638373)
			)
		)
	)
	(zone
		(net 371)
		(net_name "/Com Express 7 MGMT/I2C.SCL")
		(layer "In5.Cu")
		(name "$teardrop_padvia$")
		(hatch none 0.1)
		(priority 30209)
		(attr
			(teardrop
				(type padvia)
			)
		)
		(connect_pads yes
			(clearance 0)
		)
		(min_thickness 0.0254)
		(filled_areas_thickness no)
		(fill yes
			(thermal_gap 0.5)
			(thermal_bridge_width 0.5)
			(island_removal_mode 1)
			(island_area_min 10)
		)
		(polygon
			(pts
				(xy 302.2395 108.640677) (xy 302.244318 108.571236) (xy 302.25804 108.519912) (xy 302.304755 108.44437)
				(xy 302.314299 108.432229) (xy 302.364081 108.365003) (xy 302.177 108.239) (xy 301.989919 108.365003)
				(xy 302.039701 108.432231) (xy 302.094106 108.515397) (xy 302.10919 108.568251) (xy 302.1145 108.640677)
			)
		)
	)
	(zone
		(net 371)
		(net_name "/Com Express 7 MGMT/I2C.SCL")
		(layer "In5.Cu")
		(name "$teardrop_padvia$")
		(hatch none 0.1)
		(priority 30284)
		(attr
			(teardrop
				(type padvia)
			)
		)
		(connect_pads yes
			(clearance 0)
		)
		(min_thickness 0.0254)
		(filled_areas_thickness no)
		(fill yes
			(thermal_gap 0.5)
			(thermal_bridge_width 0.5)
			(island_removal_mode 1)
			(island_area_min 10)
		)
		(polygon
			(pts
				(xy 259.467515 89.149126) (xy 259.421819 89.096617) (xy 259.395231 89.050622) (xy 259.374847 88.964174)
				(xy 259.373011 88.948839) (xy 259.360677 88.866104) (xy 259.139293 88.909292) (xy 259.096105 89.130676)
				(xy 259.17884 89.14301) (xy 259.276119 89.163348) (xy 259.324159 89.190056) (xy 259.379127 89.237514)
			)
		)
	)
	(zone
		(net 267)
		(net_name "/Com Express 7 Interfaces/PCIe_{B2Bx4}.TX0-")
		(layer "In5.Cu")
		(name "$teardrop_padvia$")
		(hatch none 0.1)
		(priority 30074)
		(attr
			(teardrop
				(type padvia)
			)
		)
		(connect_pads yes
			(clearance 0)
		)
		(min_thickness 0.0254)
		(filled_areas_thickness no)
		(fill yes
			(thermal_gap 0.5)
			(thermal_bridge_width 0.5)
			(island_removal_mode 1)
			(island_area_min 10)
		)
		(polygon
			(pts
				(xy 190.789416 165.002) (xy 190.926751 164.995104) (xy 191.007939 164.990724) (xy 191.106105 165.002177)
				(xy 191.151 164.7815) (xy 190.997605 164.62181) (xy 190.948527 164.689306) (xy 190.934187 164.71781)
				(xy 190.912888 164.758429) (xy 190.886197 164.792262) (xy 190.847308 164.815417) (xy 190.789416 164.824)
			)
		)
	)
	(zone
		(net 375)
		(net_name "/2xUSB3.0+RJ45/USB_2.D+")
		(layer "In5.Cu")
		(name "$teardrop_padvia$")
		(hatch none 0.1)
		(priority 30156)
		(attr
			(teardrop
				(type padvia)
			)
		)
		(connect_pads yes
			(clearance 0)
		)
		(min_thickness 0.0254)
		(filled_areas_thickness no)
		(fill yes
			(thermal_gap 0.5)
			(thermal_bridge_width 0.5)
			(island_removal_mode 1)
			(island_area_min 10)
		)
		(polygon
			(pts
				(xy 197.036 161.851084) (xy 197.040758 161.809513) (xy 197.054064 161.779455) (xy 197.098576 161.743353)
				(xy 197.140958 161.725803) (xy 197.222503 161.687081) (xy 197.0975 161.499) (xy 196.876823 161.543895)
				(xy 196.887325 161.620315) (xy 196.886886 161.680935) (xy 196.883774 161.718309) (xy 196.877 161.851084)
			)
		)
	)
	(zone
		(net 333)
		(net_name "/Com Express 7 Interfaces/SDIO.DAT3")
		(layer "In5.Cu")
		(name "$teardrop_padvia$")
		(hatch none 0.1)
		(priority 30040)
		(attr
			(teardrop
				(type padvia)
			)
		)
		(connect_pads yes
			(clearance 0)
		)
		(min_thickness 0.0254)
		(filled_areas_thickness no)
		(fill yes
			(thermal_gap 0.5)
			(thermal_bridge_width 0.5)
			(island_removal_mode 1)
			(island_area_min 10)
		)
		(polygon
			(pts
				(xy 113.900677 137.3325) (xy 113.832314 137.327809) (xy 113.78003 137.314974) (xy 113.690652 137.266057)
				(xy 113.587778 137.2075) (xy 113.499 137.41) (xy 113.587778 137.6125) (xy 113.690651 137.553943)
				(xy 113.774447 137.507067) (xy 113.828713 137.492761) (xy 113.900677 137.4875)
			)
		)
	)
	(zone
		(net 730)
		(net_name "Net-(U43C-CLKOUTA+)")
		(layer "In5.Cu")
		(name "$teardrop_padvia$")
		(hatch none 0.1)
		(priority 30211)
		(attr
			(teardrop
				(type padvia)
			)
		)
		(connect_pads yes
			(clearance 0)
		)
		(min_thickness 0.0254)
		(filled_areas_thickness no)
		(fill yes
			(thermal_gap 0.5)
			(thermal_bridge_width 0.5)
			(island_removal_mode 1)
			(island_area_min 10)
		)
		(polygon
			(pts
				(xy 155.1125 130.910677) (xy 155.117318 130.841236) (xy 155.13104 130.789912) (xy 155.177755 130.71437)
				(xy 155.187299 130.702229) (xy 155.237081 130.635003) (xy 155.05 130.509) (xy 154.862919 130.635003)
				(xy 154.912701 130.702231) (xy 154.967106 130.785397) (xy 154.98219 130.838251) (xy 154.9875 130.910677)
			)
		)
	)
	(zone
		(net 758)
		(net_name "Net-(U45B-LS_OK_{IN_B})")
		(layer "In5.Cu")
		(name "$teardrop_padvia$")
		(hatch none 0.1)
		(priority 30292)
		(attr
			(teardrop
				(type padvia)
			)
		)
		(connect_pads yes
			(clearance 0)
		)
		(min_thickness 0.0254)
		(filled_areas_thickness no)
		(fill yes
			(thermal_gap 0.5)
			(thermal_bridge_width 0.5)
			(island_removal_mode 1)
			(island_area_min 10)
		)
		(polygon
			(pts
				(xy 127.859972 138.86836) (xy 127.917349 138.919257) (xy 127.966778 138.951616) (xy 128.037691 138.983136)
				(xy 128.095953 139.007672) (xy 128.164997 139.047081) (xy 128.290707 138.860707) (xy 128.164997 138.672919)
				(xy 128.092514 138.741809) (xy 128.058538 138.778033) (xy 128.024828 138.80236) (xy 127.988922 138.805951)
				(xy 127.94836 138.779972)
			)
		)
	)
	(zone
		(net 757)
		(net_name "Net-(U45B-LOSB)")
		(layer "In5.Cu")
		(name "$teardrop_padvia$")
		(hatch none 0.1)
		(priority 30253)
		(attr
			(teardrop
				(type padvia)
			)
		)
		(connect_pads yes
			(clearance 0)
		)
		(min_thickness 0.0254)
		(filled_areas_thickness no)
		(fill yes
			(thermal_gap 0.5)
			(thermal_bridge_width 0.5)
			(island_removal_mode 1)
			(island_area_min 10)
		)
		(polygon
			(pts
				(xy 128.962485 138.620873) (xy 129.008181 138.673382) (xy 129.034768 138.719376) (xy 129.055152 138.805825)
				(xy 129.056988 138.821158) (xy 129.069323 138.903895) (xy 129.290707 138.860707) (xy 129.333895 138.639323)
				(xy 129.251158 138.626988) (xy 129.15388 138.606651) (xy 129.10584 138.579943) (xy 129.050873 138.532485)
			)
		)
	)
	(zone
		(net 434)
		(net_name "/Com Express 7 MGMT/~{TYPE1}")
		(layer "In5.Cu")
		(name "$teardrop_padvia$")
		(hatch none 0.1)
		(priority 30219)
		(attr
			(teardrop
				(type padvia)
			)
		)
		(connect_pads yes
			(clearance 0)
		)
		(min_thickness 0.0254)
		(filled_areas_thickness no)
		(fill yes
			(thermal_gap 0.5)
			(thermal_bridge_width 0.5)
			(island_removal_mode 1)
			(island_area_min 10)
		)
		(polygon
			(pts
				(xy 249.5375 134.175677) (xy 249.542318 134.106236) (xy 249.55604 134.054912) (xy 249.602755 133.97937)
				(xy 249.612299 133.967229) (xy 249.662081 133.900003) (xy 249.475 133.774) (xy 249.287919 133.900003)
				(xy 249.337701 133.967231) (xy 249.392106 134.050397) (xy 249.40719 134.103251) (xy 249.4125 134.175677)
			)
		)
	)
	(zone
		(net 371)
		(net_name "/Com Express 7 MGMT/I2C.SCL")
		(layer "In5.Cu")
		(name "$teardrop_padvia$")
		(hatch none 0.1)
		(priority 30169)
		(attr
			(teardrop
				(type padvia)
			)
		)
		(connect_pads yes
			(clearance 0)
		)
		(min_thickness 0.0254)
		(filled_areas_thickness no)
		(fill yes
			(thermal_gap 0.5)
			(thermal_bridge_width 0.5)
			(island_removal_mode 1)
			(island_area_min 10)
		)
		(polygon
			(pts
				(xy 302.1145 107.839323) (xy 302.109682 107.908763) (xy 302.09596 107.960087) (xy 302.049245 108.035628)
				(xy 302.039702 108.047768) (xy 301.989919 108.114997) (xy 302.177 108.241) (xy 302.364081 108.114997)
				(xy 302.314299 108.047769) (xy 302.259894 107.964603) (xy 302.24481 107.911748) (xy 302.2395 107.839323)
			)
		)
	)
	(zone
		(net 385)
		(net_name "/Com Express 7 Interfaces/SDIO.CMD")
		(layer "In5.Cu")
		(name "$teardrop_padvia$")
		(hatch none 0.1)
		(priority 30042)
		(attr
			(teardrop
				(type padvia)
			)
		)
		(connect_pads yes
			(clearance 0)
		)
		(min_thickness 0.0254)
		(filled_areas_thickness no)
		(fill yes
			(thermal_gap 0.5)
			(thermal_bridge_width 0.5)
			(island_removal_mode 1)
			(island_area_min 10)
		)
		(polygon
			(pts
				(xy 165.261879 161.77148) (xy 165.306901 161.823136) (xy 165.334795 161.869182) (xy 165.363406 161.966971)
				(xy 165.394742 162.08112) (xy 165.600707 162.000707) (xy 165.68112 161.794742) (xy 165.566971 161.763406)
				(xy 165.474573 161.7373) (xy 165.426086 161.709044) (xy 165.37148 161.661879)
			)
		)
	)
	(zone
		(net 62)
		(net_name "+12V_AON")
		(layer "In5.Cu")
		(name "$teardrop_padvia$")
		(hatch none 0.1)
		(priority 30008)
		(attr
			(teardrop
				(type padvia)
			)
		)
		(connect_pads yes
			(clearance 0)
		)
		(min_thickness 0.0254)
		(filled_areas_thickness no)
		(fill yes
			(thermal_gap 0.5)
			(thermal_bridge_width 0.5)
			(island_removal_mode 1)
			(island_area_min 10)
		)
		(polygon
			(pts
				(xy 198.332933 69.652163) (xy 198.410845 69.656876) (xy 198.46963 69.669863) (xy 198.560661 69.711965)
				(xy 198.645832 69.754663) (xy 198.73461 69.552163) (xy 198.645832 69.349663) (xy 198.56066 69.392362)
				(xy 198.467827 69.43503) (xy 198.409688 69.447607) (xy 198.332933 69.452163)
			)
		)
	)
	(zone
		(net 77)
		(net_name "+5V_AON")
		(layer "In5.Cu")
		(name "$teardrop_padvia$")
		(hatch none 0.1)
		(priority 30028)
		(attr
			(teardrop
				(type padvia)
			)
		)
		(connect_pads yes
			(clearance 0)
		)
		(min_thickness 0.0254)
		(filled_areas_thickness no)
		(fill yes
			(thermal_gap 0.5)
			(thermal_bridge_width 0.5)
			(island_removal_mode 1)
			(island_area_min 10)
		)
		(polygon
			(pts
				(xy 299.83739 96.164031) (xy 299.895813 96.112272) (xy 299.946563 96.079889) (xy 300.040703 96.04529)
				(xy 300.131121 96.015257) (xy 300.050707 95.809293) (xy 299.844741 95.72888) (xy 299.814708 95.819299)
				(xy 299.779237 95.915112) (xy 299.74702 95.965115) (xy 299.695969 96.02261)
			)
		)
	)
	(zone
		(net 53)
		(net_name "/2xSFP+/SH")
		(layer "In5.Cu")
		(hatch edge 0.5)
		(priority 1)
		(connect_pads
			(clearance 0.3)
		)
		(min_thickness 0.22)
		(filled_areas_thickness no)
		(fill yes
			(thermal_gap 0.2)
			(thermal_bridge_width 0.5)
			(smoothing fillet)
			(radius 0.5)
		)
		(polygon
			(pts
				(xy 99.6 170.31) (xy 152.95 170.31) (xy 152.95 154.31) (xy 99.6 154.31)
			)
		)
	)
	(zone
		(net 204)
		(net_name "/Backplane/USB.D-")
		(layer "In5.Cu")
		(name "$teardrop_padvia$")
		(hatch none 0.1)
		(priority 30122)
		(attr
			(teardrop
				(type padvia)
			)
		)
		(connect_pads yes
			(clearance 0)
		)
		(min_thickness 0.0254)
		(filled_areas_thickness no)
		(fill yes
			(thermal_gap 0.5)
			(thermal_bridge_width 0.5)
			(island_removal_mode 1)
			(island_area_min 10)
		)
		(polygon
			(pts
				(xy 212.648 149.446584) (xy 212.645484 149.265841) (xy 212.643677 149.101749) (xy 212.423 149.099)
				(xy 212.297997 149.287081) (xy 212.383589 149.325787) (xy 212.424472 149.341256) (xy 212.457994 149.36208)
				(xy 212.480667 149.394958) (xy 212.489 149.446584)
			)
		)
	)
	(zone
		(net 166)
		(net_name "Net-(J2A-MOD_{ABS})")
		(layer "In5.Cu")
		(name "$teardrop_padvia$")
		(hatch none 0.1)
		(priority 30186)
		(attr
			(teardrop
				(type padvia)
			)
		)
		(connect_pads yes
			(clearance 0)
		)
		(min_thickness 0.0254)
		(filled_areas_thickness no)
		(fill yes
			(thermal_gap 0.5)
			(thermal_bridge_width 0.5)
			(island_removal_mode 1)
			(island_area_min 10)
		)
		(polygon
			(pts
				(xy 164.799323 148.3625) (xy 164.868764 148.367318) (xy 164.920088 148.38104) (xy 164.995629 148.427755)
				(xy 165.007769 148.437299) (xy 165.074997 148.487081) (xy 165.201 148.3) (xy 165.074997 148.112919)
				(xy 165.007768 148.162702) (xy 164.924602 148.217106) (xy 164.871748 148.23219) (xy 164.799323 148.2375)
			)
		)
	)
	(zone
		(net 358)
		(net_name "/Com Express 7 MGMT/SMBus.SDA")
		(layer "In5.Cu")
		(name "$teardrop_padvia$")
		(hatch none 0.1)
		(priority 30246)
		(attr
			(teardrop
				(type padvia)
			)
		)
		(connect_pads yes
			(clearance 0)
		)
		(min_thickness 0.0254)
		(filled_areas_thickness no)
		(fill yes
			(thermal_gap 0.5)
			(thermal_bridge_width 0.5)
			(island_removal_mode 1)
			(island_area_min 10)
		)
		(polygon
			(pts
				(xy 167.414127 163.122485) (xy 167.361618 163.168181) (xy 167.315623 163.194768) (xy 167.229174 163.215152)
				(xy 167.213841 163.216988) (xy 167.131105 163.229323) (xy 167.174293 163.450707) (xy 167.395677 163.493895)
				(xy 167.408011 163.41116) (xy 167.428349 163.313881) (xy 167.455057 163.265841) (xy 167.502515 163.210873)
			)
		)
	)
	(zone
		(net 527)
		(net_name "/Backplane/GPIO")
		(layer "In5.Cu")
		(name "$teardrop_padvia$")
		(hatch none 0.1)
		(priority 30277)
		(attr
			(teardrop
				(type padvia)
			)
		)
		(connect_pads yes
			(clearance 0)
		)
		(min_thickness 0.0254)
		(filled_areas_thickness no)
		(fill yes
			(thermal_gap 0.5)
			(thermal_bridge_width 0.5)
			(island_removal_mode 1)
			(island_area_min 10)
		)
		(polygon
			(pts
				(xy 130.160873 78.387515) (xy 130.213382 78.341819) (xy 130.259376 78.315231) (xy 130.345824 78.294847)
				(xy 130.36116 78.293011) (xy 130.443895 78.280677) (xy 130.400707 78.059293) (xy 130.179323 78.016105)
				(xy 130.166988 78.098841) (xy 130.146651 78.196119) (xy 130.119943 78.244159) (xy 130.072485 78.299127)
			)
		)
	)
	(zone
		(net 720)
		(net_name "Net-(U43C-REFCLK1+)")
		(layer "In5.Cu")
		(name "$teardrop_padvia$")
		(hatch none 0.1)
		(priority 30135)
		(attr
			(teardrop
				(type padvia)
			)
		)
		(connect_pads yes
			(clearance 0)
		)
		(min_thickness 0.0254)
		(filled_areas_thickness no)
		(fill yes
			(thermal_gap 0.5)
			(thermal_bridge_width 0.5)
			(island_removal_mode 1)
			(island_area_min 10)
		)
		(polygon
			(pts
				(xy 145.0625 130.467834) (xy 145.067271 130.429745) (xy 145.080664 130.403817) (xy 145.123428 130.379349)
				(xy 145.187591 130.37135) (xy 145.254714 130.363805) (xy 145.319679 130.339286) (xy 145.2 130.149)
				(xy 144.979323 130.11972) (xy 144.959585 130.23613) (xy 144.94387 130.332192) (xy 144.9375 130.467834)
			)
		)
	)
	(zone
		(net 750)
		(net_name "Net-(U45C-CLKOUTA+)")
		(layer "In5.Cu")
		(name "$teardrop_padvia$")
		(hatch none 0.1)
		(priority 30137)
		(attr
			(teardrop
				(type padvia)
			)
		)
		(connect_pads yes
			(clearance 0)
		)
		(min_thickness 0.0254)
		(filled_areas_thickness no)
		(fill yes
			(thermal_gap 0.5)
			(thermal_bridge_width 0.5)
			(island_removal_mode 1)
			(island_area_min 10)
		)
		(polygon
			(pts
				(xy 137.054881 130.816492) (xy 137.030678 130.785554) (xy 137.020872 130.756887) (xy 137.031367 130.705871)
				(xy 137.059402 130.659825) (xy 137.089614 130.610987) (xy 137.110677 130.553895) (xy 136.889293 130.509293)
				(xy 136.726689 130.658773) (xy 136.896227 130.83494) (xy 136.966492 130.904881)
			)
		)
	)
	(zone
		(net 257)
		(net_name "/Com Express 7 Interfaces/PCIe_{B2Bx4}.TX1-")
		(layer "In5.Cu")
		(name "$teardrop_padvia$")
		(hatch none 0.1)
		(priority 30065)
		(attr
			(teardrop
				(type padvia)
			)
		)
		(connect_pads yes
			(clearance 0)
		)
		(min_thickness 0.0254)
		(filled_areas_thickness no)
		(fill yes
			(thermal_gap 0.5)
			(thermal_bridge_width 0.5)
			(island_removal_mode 1)
			(island_area_min 10)
		)
		(polygon
			(pts
				(xy 173.939416 101.886) (xy 173.984146 101.890741) (xy 174.017611 101.903931) (xy 174.061124 101.948694)
				(xy 174.084188 101.99219) (xy 174.110165 102.041127) (xy 174.147605 102.088189) (xy 174.301 101.9285)
				(xy 174.256105 101.707823) (xy 174.17904 101.718447) (xy 174.117337 101.718182) (xy 174.076751 101.714896)
				(xy 173.939416 101.708)
			)
		)
	)
	(zone
		(net 337)
		(net_name "/Com Express 7 Interfaces/PCIE_{REF}.CK-")
		(layer "In5.Cu")
		(name "$teardrop_padvia$")
		(hatch none 0.1)
		(priority 30081)
		(attr
			(teardrop
				(type padvia)
			)
		)
		(connect_pads yes
			(clearance 0)
		)
		(min_thickness 0.0254)
		(filled_areas_thickness no)
		(fill yes
			(thermal_gap 0.5)
			(thermal_bridge_width 0.5)
			(island_removal_mode 1)
			(island_area_min 10)
		)
		(polygon
			(pts
				(xy 215.181 122.960584) (xy 215.174104 122.823248) (xy 215.169724 122.742061) (xy 215.181177 122.643895)
				(xy 214.9605 122.599) (xy 214.80081 122.752394) (xy 214.868306 122.801472) (xy 214.896809 122.815811)
				(xy 214.937428 122.83711) (xy 214.971262 122.863802) (xy 214.994417 122.902691) (xy 215.003 122.960584)
			)
		)
	)
	(zone
		(net 313)
		(net_name "/2xUSB3.0+RJ45/USB_1.D+")
		(layer "In5.Cu")
		(name "$teardrop_padvia$")
		(hatch none 0.1)
		(priority 30123)
		(attr
			(teardrop
				(type padvia)
			)
		)
		(connect_pads yes
			(clearance 0)
		)
		(min_thickness 0.0254)
		(filled_areas_thickness no)
		(fill yes
			(thermal_gap 0.5)
			(thermal_bridge_width 0.5)
			(island_removal_mode 1)
			(island_area_min 10)
		)
		(polygon
			(pts
				(xy 153.248 123.346584) (xy 153.245484 123.165841) (xy 153.243677 123.001749) (xy 153.023 122.999)
				(xy 152.897997 123.187081) (xy 152.983589 123.225787) (xy 153.024472 123.241256) (xy 153.057994 123.26208)
				(xy 153.080667 123.294958) (xy 153.089 123.346584)
			)
		)
	)
	(zone
		(net 720)
		(net_name "Net-(U43C-REFCLK1+)")
		(layer "In5.Cu")
		(name "$teardrop_padvia$")
		(hatch none 0.1)
		(priority 30270)
		(attr
			(teardrop
				(type padvia)
			)
		)
		(connect_pads yes
			(clearance 0)
		)
		(min_thickness 0.0254)
		(filled_areas_thickness no)
		(fill yes
			(thermal_gap 0.5)
			(thermal_bridge_width 0.5)
			(island_removal_mode 1)
			(island_area_min 10)
		)
		(polygon
			(pts
				(xy 147.122485 139.620873) (xy 147.168181 139.673382) (xy 147.194768 139.719376) (xy 147.215152 139.805825)
				(xy 147.216988 139.821158) (xy 147.229323 139.903895) (xy 147.450707 139.860707) (xy 147.493895 139.639323)
				(xy 147.411158 139.626988) (xy 147.31388 139.606651) (xy 147.26584 139.579943) (xy 147.210873 139.532485)
			)
		)
	)
	(zone
		(net 247)
		(net_name "/Com Express 7 Interfaces/PCIe_{B2Bx4}.TX2-")
		(layer "In5.Cu")
		(name "$teardrop_padvia$")
		(hatch none 0.1)
		(priority 30085)
		(attr
			(teardrop
				(type padvia)
			)
		)
		(connect_pads yes
			(clearance 0)
		)
		(min_thickness 0.0254)
		(filled_areas_thickness no)
		(fill yes
			(thermal_gap 0.5)
			(thermal_bridge_width 0.5)
			(island_removal_mode 1)
			(island_area_min 10)
		)
		(polygon
			(pts
				(xy 188.373 166.639416) (xy 188.379896 166.776751) (xy 188.384276 166.857939) (xy 188.372823 166.956105)
				(xy 188.5935 167.001) (xy 188.753189 166.847605) (xy 188.685691 166.798527) (xy 188.65719 166.784188)
				(xy 188.616571 166.762889) (xy 188.582738 166.736198) (xy 188.559583 166.697309) (xy 188.551 166.639416)
			)
		)
	)
	(zone
		(net 372)
		(net_name "/Com Express 7 MGMT/I2C.SDA")
		(layer "In5.Cu")
		(name "$teardrop_padvia$")
		(hatch none 0.1)
		(priority 30170)
		(attr
			(teardrop
				(type padvia)
			)
		)
		(connect_pads yes
			(clearance 0)
		)
		(min_thickness 0.0254)
		(filled_areas_thickness no)
		(fill yes
			(thermal_gap 0.5)
			(thermal_bridge_width 0.5)
			(island_removal_mode 1)
			(island_area_min 10)
		)
		(polygon
			(pts
				(xy 302.7625 107.839323) (xy 302.757682 107.908763) (xy 302.74396 107.960087) (xy 302.697245 108.035628)
				(xy 302.687702 108.047768) (xy 302.637919 108.114997) (xy 302.825 108.241) (xy 303.012081 108.114997)
				(xy 302.962299 108.047769) (xy 302.907894 107.964603) (xy 302.89281 107.911748) (xy 302.8875 107.839323)
			)
		)
	)
	(zone
		(net 161)
		(net_name "/2xUSB3.0+RJ45/USBSS_2.RX+")
		(layer "In5.Cu")
		(name "$teardrop_padvia$")
		(hatch none 0.1)
		(priority 30155)
		(attr
			(teardrop
				(type padvia)
			)
		)
		(connect_pads yes
			(clearance 0)
		)
		(min_thickness 0.0254)
		(filled_areas_thickness no)
		(fill yes
			(thermal_gap 0.5)
			(thermal_bridge_width 0.5)
			(island_removal_mode 1)
			(island_area_min 10)
		)
		(polygon
			(pts
				(xy 182.036 158.676084) (xy 182.040758 158.634513) (xy 182.054064 158.604455) (xy 182.098576 158.568353)
				(xy 182.140958 158.550803) (xy 182.222503 158.512081) (xy 182.0975 158.324) (xy 181.876823 158.368895)
				(xy 181.887325 158.445315) (xy 181.886886 158.505935) (xy 181.883774 158.543309) (xy 181.877 158.676084)
			)
		)
	)
	(zone
		(net 9)
		(net_name "/Com Express 7 Interfaces/PCIe_{B1x2}.TX0+")
		(layer "In5.Cu")
		(name "$teardrop_padvia$")
		(hatch none 0.1)
		(priority 30050)
		(attr
			(teardrop
				(type padvia)
			)
		)
		(connect_pads yes
			(clearance 0)
		)
		(min_thickness 0.0254)
		(filled_areas_thickness no)
		(fill yes
			(thermal_gap 0.5)
			(thermal_bridge_width 0.5)
			(island_removal_mode 1)
			(island_area_min 10)
		)
		(polygon
			(pts
				(xy 204.082076 124.53764) (xy 203.988949 124.450085) (xy 203.924099 124.38815) (xy 203.858685 124.303393)
				(xy 203.670897 124.427689) (xy 203.661437 124.649073) (xy 203.746802 124.638206) (xy 203.774896 124.630164)
				(xy 203.819652 124.618253) (xy 203.863357 124.61482) (xy 203.908161 124.627394) (xy 203.956211 124.663505)
			)
		)
	)
	(zone
		(net 748)
		(net_name "Net-(U45C-AMUXA)")
		(layer "In5.Cu")
		(name "$teardrop_padvia$")
		(hatch none 0.1)
		(priority 30269)
		(attr
			(teardrop
				(type padvia)
			)
		)
		(connect_pads yes
			(clearance 0)
		)
		(min_thickness 0.0254)
		(filled_areas_thickness no)
		(fill yes
			(thermal_gap 0.5)
			(thermal_bridge_width 0.5)
			(island_removal_mode 1)
			(island_area_min 10)
		)
		(polygon
			(pts
				(xy 135.962485 141.620873) (xy 136.008181 141.673382) (xy 136.034768 141.719376) (xy 136.055152 141.805825)
				(xy 136.056988 141.821158) (xy 136.069323 141.903895) (xy 136.290707 141.860707) (xy 136.333895 141.639323)
				(xy 136.251158 141.626988) (xy 136.15388 141.606651) (xy 136.10584 141.579943) (xy 136.050873 141.532485)
			)
		)
	)
	(zone
		(net 74)
		(net_name "+1V0")
		(layer "In5.Cu")
		(name "$teardrop_padvia$")
		(hatch none 0.1)
		(priority 30014)
		(attr
			(teardrop
				(type padvia)
			)
		)
		(connect_pads yes
			(clearance 0)
		)
		(min_thickness 0.0254)
		(filled_areas_thickness no)
		(fill yes
			(thermal_gap 0.5)
			(thermal_bridge_width 0.5)
			(island_removal_mode 1)
			(island_area_min 10)
		)
		(polygon
			(pts
				(xy 252.585676 88.349999) (xy 252.507764 88.345286) (xy 252.44898 88.332299) (xy 252.357948 88.290197)
				(xy 252.272777 88.247499) (xy 252.183999 88.449999) (xy 252.272777 88.652499) (xy 252.357946 88.609801)
				(xy 252.450781 88.567132) (xy 252.50892 88.554555) (xy 252.585676 88.549999)
			)
		)
	)
	(zone
		(net 726)
		(net_name "/2xSFP+/KR to SFI #1/~{TRST}")
		(layer "In5.Cu")
		(name "$teardrop_padvia$")
		(hatch none 0.1)
		(priority 30217)
		(attr
			(teardrop
				(type padvia)
			)
		)
		(connect_pads yes
			(clearance 0)
		)
		(min_thickness 0.0254)
		(filled_areas_thickness no)
		(fill yes
			(thermal_gap 0.5)
			(thermal_bridge_width 0.5)
			(island_removal_mode 1)
			(island_area_min 10)
		)
		(polygon
			(pts
				(xy 151.2125 130.910677) (xy 151.217318 130.841236) (xy 151.23104 130.789912) (xy 151.277755 130.71437)
				(xy 151.287299 130.702229) (xy 151.337081 130.635003) (xy 151.15 130.509) (xy 150.962919 130.635003)
				(xy 151.012701 130.702231) (xy 151.067106 130.785397) (xy 151.08219 130.838251) (xy 151.0875 130.910677)
			)
		)
	)
	(zone
		(net 400)
		(net_name "/Com Express 7 MGMT/FAN_PWM")
		(layer "In5.Cu")
		(name "$teardrop_padvia$")
		(hatch none 0.1)
		(priority 30234)
		(attr
			(teardrop
				(type padvia)
			)
		)
		(connect_pads yes
			(clearance 0)
		)
		(min_thickness 0.0254)
		(filled_areas_thickness no)
		(fill yes
			(thermal_gap 0.5)
			(thermal_bridge_width 0.5)
			(island_removal_mode 1)
			(island_area_min 10)
		)
		(polygon
			(pts
				(xy 234.309835 78.744485) (xy 234.257326 78.790181) (xy 234.211331 78.816768) (xy 234.124882 78.837152)
				(xy 234.109549 78.838988) (xy 234.026813 78.851323) (xy 234.070001 79.072707) (xy 234.291385 79.115895)
				(xy 234.303719 79.03316) (xy 234.324057 78.935881) (xy 234.350765 78.887841) (xy 234.398223 78.832873)
			)
		)
	)
	(zone
		(net 65)
		(net_name "+12V")
		(layer "In5.Cu")
		(name "$teardrop_padvia$")
		(hatch none 0.1)
		(priority 30033)
		(attr
			(teardrop
				(type padvia)
			)
		)
		(connect_pads yes
			(clearance 0)
		)
		(min_thickness 0.0254)
		(filled_areas_thickness no)
		(fill yes
			(thermal_gap 0.5)
			(thermal_bridge_width 0.5)
			(island_removal_mode 1)
			(island_area_min 10)
		)
		(polygon
			(pts
				(xy 251.83097 87.237389) (xy 251.882729 87.295813) (xy 251.915112 87.346563) (xy 251.94971 87.440701)
				(xy 251.979743 87.531119) (xy 252.185708 87.450706) (xy 252.266121 87.244741) (xy 252.175703 87.214708)
				(xy 252.079889 87.179236) (xy 252.029886 87.14702) (xy 251.972391 87.095968)
			)
		)
	)
	(zone
		(net 166)
		(net_name "Net-(J2A-MOD_{ABS})")
		(layer "In5.Cu")
		(name "$teardrop_padvia$")
		(hatch none 0.1)
		(priority 30004)
		(attr
			(teardrop
				(type padvia)
			)
		)
		(connect_pads yes
			(clearance 0)
		)
		(min_thickness 0.0254)
		(filled_areas_thickness no)
		(fill yes
			(thermal_gap 0.5)
			(thermal_bridge_width 0.5)
			(island_removal_mode 1)
			(island_area_min 10)
		)
		(polygon
			(pts
				(xy 145.515738 162.8475) (xy 145.428809 162.842676) (xy 145.358458 162.828909) (xy 145.257033 162.78189)
				(xy 145.154123 162.692049) (xy 145.082217 162.624253) (xy 144.988895 162.552468) (xy 144.749 162.91)
				(xy 144.988895 163.267532) (xy 145.115854 163.165051) (xy 145.154123 163.127951) (xy 145.220156 163.066205)
				(xy 145.29256 163.016931) (xy 145.386149 162.984304) (xy 145.515738 162.9725)
			)
		)
	)
	(zone
		(net 725)
		(net_name "/2xSFP+/KR to SFI #1/TCK")
		(layer "In5.Cu")
		(name "$teardrop_padvia$")
		(hatch none 0.1)
		(priority 30218)
		(attr
			(teardrop
				(type padvia)
			)
		)
		(connect_pads yes
			(clearance 0)
		)
		(min_thickness 0.0254)
		(filled_areas_thickness no)
		(fill yes
			(thermal_gap 0.5)
			(thermal_bridge_width 0.5)
			(island_removal_mode 1)
			(island_area_min 10)
		)
		(polygon
			(pts
				(xy 152.5125 130.910677) (xy 152.517318 130.841236) (xy 152.53104 130.789912) (xy 152.577755 130.71437)
				(xy 152.587299 130.702229) (xy 152.637081 130.635003) (xy 152.45 130.509) (xy 152.262919 130.635003)
				(xy 152.312701 130.702231) (xy 152.367106 130.785397) (xy 152.38219 130.838251) (xy 152.3875 130.910677)
			)
		)
	)
	(zone
		(net 730)
		(net_name "Net-(U43C-CLKOUTA+)")
		(layer "In5.Cu")
		(name "$teardrop_padvia$")
		(hatch none 0.1)
		(priority 30237)
		(attr
			(teardrop
				(type padvia)
			)
		)
		(connect_pads yes
			(clearance 0)
		)
		(min_thickness 0.0254)
		(filled_areas_thickness no)
		(fill yes
			(thermal_gap 0.5)
			(thermal_bridge_width 0.5)
			(island_removal_mode 1)
			(island_area_min 10)
		)
		(polygon
			(pts
				(xy 154.689127 139.532485) (xy 154.636618 139.578181) (xy 154.590623 139.604768) (xy 154.504174 139.625152)
				(xy 154.488841 139.626988) (xy 154.406105 139.639323) (xy 154.449293 139.860707) (xy 154.670677 139.903895)
				(xy 154.683011 139.82116) (xy 154.703349 139.723881) (xy 154.730057 139.675841) (xy 154.777515 139.620873)
			)
		)
	)
	(zone
		(net 728)
		(net_name "Net-(U43C-AMUXA)")
		(layer "In5.Cu")
		(name "$teardrop_padvia$")
		(hatch none 0.1)
		(priority 30251)
		(attr
			(teardrop
				(type padvia)
			)
		)
		(connect_pads yes
			(clearance 0)
		)
		(min_thickness 0.0254)
		(filled_areas_thickness no)
		(fill yes
			(thermal_gap 0.5)
			(thermal_bridge_width 0.5)
			(island_removal_mode 1)
			(island_area_min 10)
		)
		(polygon
			(pts
				(xy 154.122485 141.620873) (xy 154.168181 141.673382) (xy 154.194768 141.719376) (xy 154.215152 141.805825)
				(xy 154.216988 141.821158) (xy 154.229323 141.903895) (xy 154.450707 141.860707) (xy 154.493895 141.639323)
				(xy 154.411158 141.626988) (xy 154.31388 141.606651) (xy 154.26584 141.579943) (xy 154.210873 141.532485)
			)
		)
	)
	(zone
		(net 751)
		(net_name "Net-(U45C-CLKOUTA-)")
		(layer "In5.Cu")
		(name "$teardrop_padvia$")
		(hatch none 0.1)
		(priority 30129)
		(attr
			(teardrop
				(type padvia)
			)
		)
		(connect_pads yes
			(clearance 0)
		)
		(min_thickness 0.0254)
		(filled_areas_thickness no)
		(fill yes
			(thermal_gap 0.5)
			(thermal_bridge_width 0.5)
			(island_removal_mode 1)
			(island_area_min 10)
		)
		(polygon
			(pts
				(xy 135.954985 140.628373) (xy 135.998576 140.678586) (xy 136.025537 140.723616) (xy 136.052715 140.821806)
				(xy 136.064424 140.879432) (xy 136.087012 140.946601) (xy 136.290707 140.860707) (xy 136.333895 140.639323)
				(xy 136.239643 140.627421) (xy 136.144708 140.610844) (xy 136.097162 140.585747) (xy 136.043373 140.539985)
			)
		)
	)
	(zone
		(net 430)
		(net_name "/2xSFP+/MDIO0.MDC")
		(layer "In5.Cu")
		(name "$teardrop_padvia$")
		(hatch none 0.1)
		(priority 30240)
		(attr
			(teardrop
				(type padvia)
			)
		)
		(connect_pads yes
			(clearance 0)
		)
		(min_thickness 0.0254)
		(filled_areas_thickness no)
		(fill yes
			(thermal_gap 0.5)
			(thermal_bridge_width 0.5)
			(island_removal_mode 1)
			(island_area_min 10)
		)
		(polygon
			(pts
				(xy 145.269127 146.972485) (xy 145.216618 147.018181) (xy 145.170623 147.044768) (xy 145.084174 147.065152)
				(xy 145.068841 147.066988) (xy 144.986105 147.079323) (xy 145.029293 147.300707) (xy 145.250677 147.343895)
				(xy 145.263011 147.26116) (xy 145.283349 147.163881) (xy 145.310057 147.115841) (xy 145.357515 147.060873)
			)
		)
	)
	(zone
		(net 359)
		(net_name "/Com Express 7 MGMT/SMBus.~{INT}")
		(layer "In5.Cu")
		(name "$teardrop_padvia$")
		(hatch none 0.1)
		(priority 30236)
		(attr
			(teardrop
				(type padvia)
			)
		)
		(connect_pads yes
			(clearance 0)
		)
		(min_thickness 0.0254)
		(filled_areas_thickness no)
		(fill yes
			(thermal_gap 0.5)
			(thermal_bridge_width 0.5)
			(island_removal_mode 1)
			(island_area_min 10)
		)
		(polygon
			(pts
				(xy 201.139127 121.972485) (xy 201.086618 122.018181) (xy 201.040623 122.044768) (xy 200.954174 122.065152)
				(xy 200.938841 122.066988) (xy 200.856105 122.079323) (xy 200.899293 122.300707) (xy 201.120677 122.343895)
				(xy 201.133011 122.26116) (xy 201.153349 122.163881) (xy 201.180057 122.115841) (xy 201.227515 122.060873)
			)
		)
	)
	(zone
		(net 303)
		(net_name "/Com Express 7 MGMT/~{SUS_S5}")
		(layer "In5.Cu")
		(name "$teardrop_padvia$")
		(hatch none 0.1)
		(priority 30244)
		(attr
			(teardrop
				(type padvia)
			)
		)
		(connect_pads yes
			(clearance 0)
		)
		(min_thickness 0.0254)
		(filled_areas_thickness no)
		(fill yes
			(thermal_gap 0.5)
			(thermal_bridge_width 0.5)
			(island_removal_mode 1)
			(island_area_min 10)
		)
		(polygon
			(pts
				(xy 158.789127 154.072485) (xy 158.736618 154.118181) (xy 158.690623 154.144768) (xy 158.604174 154.165152)
				(xy 158.588841 154.166988) (xy 158.506105 154.179323) (xy 158.549293 154.400707) (xy 158.770677 154.443895)
				(xy 158.783011 154.36116) (xy 158.803349 154.263881) (xy 158.830057 154.215841) (xy 158.877515 154.160873)
			)
		)
	)
	(zone
		(net 249)
		(net_name "/Com Express 7 Interfaces/PCIe_{B2Bx4}.TX2+")
		(layer "In5.Cu")
		(name "$teardrop_padvia$")
		(hatch none 0.1)
		(priority 30058)
		(attr
			(teardrop
				(type padvia)
			)
		)
		(connect_pads yes
			(clearance 0)
		)
		(min_thickness 0.0254)
		(filled_areas_thickness no)
		(fill yes
			(thermal_gap 0.5)
			(thermal_bridge_width 0.5)
			(island_removal_mode 1)
			(island_area_min 10)
		)
		(polygon
			(pts
				(xy 187.999 166.639416) (xy 187.994259 166.684146) (xy 187.981069 166.71761) (xy 187.936306 166.761123)
				(xy 187.89281 166.784187) (xy 187.843872 166.810164) (xy 187.79681 166.847605) (xy 187.9565 167.001)
				(xy 188.177177 166.956105) (xy 188.166552 166.879042) (xy 188.166818 166.817339) (xy 188.170104 166.776751)
				(xy 188.177 166.639416)
			)
		)
	)
	(zone
		(net 754)
		(net_name "Net-(U45A-LOSA)")
		(layer "In5.Cu")
		(name "$teardrop_padvia$")
		(hatch none 0.1)
		(priority 30202)
		(attr
			(teardrop
				(type padvia)
			)
		)
		(connect_pads yes
			(clearance 0)
		)
		(min_thickness 0.0254)
		(filled_areas_thickness no)
		(fill yes
			(thermal_gap 0.5)
			(thermal_bridge_width 0.5)
			(island_removal_mode 1)
			(island_area_min 10)
		)
		(polygon
			(pts
				(xy 131.7525 130.910677) (xy 131.757318 130.841236) (xy 131.77104 130.789912) (xy 131.817755 130.71437)
				(xy 131.827299 130.702229) (xy 131.877081 130.635003) (xy 131.69 130.509) (xy 131.502919 130.635003)
				(xy 131.552701 130.702231) (xy 131.607106 130.785397) (xy 131.62219 130.838251) (xy 131.6275 130.910677)
			)
		)
	)
	(zone
		(net 530)
		(net_name "/M.2 key M #2/~{CLKREQ}")
		(layer "In5.Cu")
		(name "$teardrop_padvia$")
		(hatch none 0.1)
		(priority 30176)
		(attr
			(teardrop
				(type padvia)
			)
		)
		(connect_pads yes
			(clearance 0)
		)
		(min_thickness 0.0254)
		(filled_areas_thickness no)
		(fill yes
			(thermal_gap 0.5)
			(thermal_bridge_width 0.5)
			(island_removal_mode 1)
			(island_area_min 10)
		)
		(polygon
			(pts
				(xy 290.159323 88.8625) (xy 290.228764 88.867318) (xy 290.280088 88.88104) (xy 290.355629 88.927755)
				(xy 290.367769 88.937299) (xy 290.434997 88.987081) (xy 290.561 88.8) (xy 290.434997 88.612919)
				(xy 290.367768 88.662702) (xy 290.284602 88.717106) (xy 290.231748 88.73219) (xy 290.159323 88.7375)
			)
		)
	)
	(zone
		(net 543)
		(net_name "Net-(Q10-B)")
		(layer "In5.Cu")
		(name "$teardrop_padvia$")
		(hatch none 0.1)
		(priority 30249)
		(attr
			(teardrop
				(type padvia)
			)
		)
		(connect_pads yes
			(clearance 0)
		)
		(min_thickness 0.0254)
		(filled_areas_thickness no)
		(fill yes
			(thermal_gap 0.5)
			(thermal_bridge_width 0.5)
			(island_removal_mode 1)
			(island_area_min 10)
		)
		(polygon
			(pts
				(xy 256.489127 85.402484) (xy 256.436618 85.44818) (xy 256.390623 85.474767) (xy 256.304174 85.495151)
				(xy 256.288841 85.496987) (xy 256.206105 85.509322) (xy 256.249293 85.730706) (xy 256.470677 85.773894)
				(xy 256.483011 85.691159) (xy 256.503349 85.59388) (xy 256.530057 85.54584) (xy 256.577515 85.490872)
			)
		)
	)
	(zone
		(net 723)
		(net_name "/2xSFP+/KR to SFI #1/TDO")
		(layer "In5.Cu")
		(name "$teardrop_padvia$")
		(hatch none 0.1)
		(priority 30214)
		(attr
			(teardrop
				(type padvia)
			)
		)
		(connect_pads yes
			(clearance 0)
		)
		(min_thickness 0.0254)
		(filled_areas_thickness no)
		(fill yes
			(thermal_gap 0.5)
			(thermal_bridge_width 0.5)
			(island_removal_mode 1)
			(island_area_min 10)
		)
		(polygon
			(pts
				(xy 151.8625 130.540677) (xy 151.867318 130.471236) (xy 151.88104 130.419912) (xy 151.927755 130.34437)
				(xy 151.937299 130.332229) (xy 151.987081 130.265003) (xy 151.8 130.139) (xy 151.612919 130.265003)
				(xy 151.662701 130.332231) (xy 151.717106 130.415397) (xy 151.73219 130.468251) (xy 151.7375 130.540677)
			)
		)
	)
	(zone
		(net 365)
		(net_name "/Com Express 7 MGMT/PWR_OK")
		(layer "In5.Cu")
		(name "$teardrop_padvia$")
		(hatch none 0.1)
		(priority 30165)
		(attr
			(teardrop
				(type padvia)
			)
		)
		(connect_pads yes
			(clearance 0)
		)
		(min_thickness 0.0254)
		(filled_areas_thickness no)
		(fill yes
			(thermal_gap 0.5)
			(thermal_bridge_width 0.5)
			(island_removal_mode 1)
			(island_area_min 10)
		)
		(polygon
			(pts
				(xy 209.4875 113.749323) (xy 209.482682 113.818763) (xy 209.46896 113.870087) (xy 209.422245 113.945628)
				(xy 209.412702 113.957768) (xy 209.362919 114.024997) (xy 209.55 114.151) (xy 209.737081 114.024997)
				(xy 209.687299 113.957769) (xy 209.632894 113.874603) (xy 209.61781 113.821748) (xy 209.6125 113.749323)
			)
		)
	)
	(zone
		(net 943)
		(net_name "/GPIO expander/GPIOEX1")
		(layer "In5.Cu")
		(name "$teardrop_padvia$")
		(hatch none 0.1)
		(priority 30286)
		(attr
			(teardrop
				(type padvia)
			)
		)
		(connect_pads yes
			(clearance 0)
		)
		(min_thickness 0.0254)
		(filled_areas_thickness no)
		(fill yes
			(thermal_gap 0.5)
			(thermal_bridge_width 0.5)
			(island_removal_mode 1)
			(island_area_min 10)
		)
		(polygon
			(pts
				(xy 99.147515 78.049127) (xy 99.101819 77.996618) (xy 99.075231 77.950623) (xy 99.054847 77.864175)
				(xy 99.053011 77.84884) (xy 99.040677 77.766105) (xy 98.819293 77.809293) (xy 98.776105 78.030677)
				(xy 98.85884 78.043011) (xy 98.956119 78.063349) (xy 99.004159 78.090057) (xy 99.059127 78.137515)
			)
		)
	)
	(zone
		(net 247)
		(net_name "/Com Express 7 Interfaces/PCIe_{B2Bx4}.TX2-")
		(layer "In5.Cu")
		(name "$teardrop_padvia$")
		(hatch none 0.1)
		(priority 30067)
		(attr
			(teardrop
				(type padvia)
			)
		)
		(connect_pads yes
			(clearance 0)
		)
		(min_thickness 0.0254)
		(filled_areas_thickness no)
		(fill yes
			(thermal_gap 0.5)
			(thermal_bridge_width 0.5)
			(island_removal_mode 1)
			(island_area_min 10)
		)
		(polygon
			(pts
				(xy 173.939416 98.886) (xy 173.984146 98.890741) (xy 174.017611 98.903931) (xy 174.061124 98.948694)
				(xy 174.084188 98.99219) (xy 174.110165 99.041127) (xy 174.147605 99.088189) (xy 174.301 98.9285)
				(xy 174.256105 98.707823) (xy 174.17904 98.718447) (xy 174.117337 98.718182) (xy 174.076751 98.714896)
				(xy 173.939416 98.708)
			)
		)
	)
	(zone
		(net 746)
		(net_name "/2xSFP+/KR to SFI #2/~{TRST}")
		(layer "In5.Cu")
		(name "$teardrop_padvia$")
		(hatch none 0.1)
		(priority 30232)
		(attr
			(teardrop
				(type padvia)
			)
		)
		(connect_pads yes
			(clearance 0)
		)
		(min_thickness 0.0254)
		(filled_areas_thickness no)
		(fill yes
			(thermal_gap 0.5)
			(thermal_bridge_width 0.5)
			(island_removal_mode 1)
			(island_area_min 10)
		)
		(polygon
			(pts
				(xy 134.529127 135.532485) (xy 134.476618 135.578181) (xy 134.430623 135.604768) (xy 134.344174 135.625152)
				(xy 134.328841 135.626988) (xy 134.246105 135.639323) (xy 134.289293 135.860707) (xy 134.510677 135.903895)
				(xy 134.523011 135.82116) (xy 134.543349 135.723881) (xy 134.570057 135.675841) (xy 134.617515 135.620873)
			)
		)
	)
	(zone
		(net 73)
		(net_name "+3V3_AON")
		(layer "In5.Cu")
		(name "$teardrop_padvia$")
		(hatch none 0.1)
		(priority 30012)
		(attr
			(teardrop
				(type padvia)
			)
		)
		(connect_pads yes
			(clearance 0)
		)
		(min_thickness 0.0254)
		(filled_areas_thickness no)
		(fill yes
			(thermal_gap 0.5)
			(thermal_bridge_width 0.5)
			(island_removal_mode 1)
			(island_area_min 10)
		)
		(polygon
			(pts
				(xy 190.80861 74.50284) (xy 190.813323 74.424927) (xy 190.82631 74.366143) (xy 190.868412 74.27511)
				(xy 190.91111 74.189941) (xy 190.70861 74.101163) (xy 190.50611 74.189941) (xy 190.548808 74.275112)
				(xy 190.591477 74.367946) (xy 190.604054 74.426085) (xy 190.60861 74.50284)
			)
		)
	)
	(zone
		(net 372)
		(net_name "/Com Express 7 MGMT/I2C.SDA")
		(layer "In5.Cu")
		(name "$teardrop_padvia$")
		(hatch none 0.1)
		(priority 30257)
		(attr
			(teardrop
				(type padvia)
			)
		)
		(connect_pads yes
			(clearance 0)
		)
		(min_thickness 0.0254)
		(filled_areas_thickness no)
		(fill yes
			(thermal_gap 0.5)
			(thermal_bridge_width 0.5)
			(island_removal_mode 1)
			(island_area_min 10)
		)
		(polygon
			(pts
				(xy 304.847485 151.000873) (xy 304.893181 151.053382) (xy 304.919768 151.099376) (xy 304.940152 151.185825)
				(xy 304.941988 151.201158) (xy 304.954323 151.283895) (xy 305.175707 151.240707) (xy 305.218895 151.019323)
				(xy 305.136158 151.006988) (xy 305.03888 150.986651) (xy 304.99084 150.959943) (xy 304.935873 150.912485)
			)
		)
	)
	(zone
		(net 312)
		(net_name "/2xUSB3.0+RJ45/USB_1.D-")
		(layer "In5.Cu")
		(name "$teardrop_padvia$")
		(hatch none 0.1)
		(priority 30120)
		(attr
			(teardrop
				(type padvia)
			)
		)
		(connect_pads yes
			(clearance 0)
		)
		(min_thickness 0.0254)
		(filled_areas_thickness no)
		(fill yes
			(thermal_gap 0.5)
			(thermal_bridge_width 0.5)
			(island_removal_mode 1)
			(island_area_min 10)
		)
		(polygon
			(pts
				(xy 153.611 123.346584) (xy 153.615756 123.305895) (xy 153.629046 123.276665) (xy 153.673378 123.242239)
				(xy 153.716411 123.225787) (xy 153.802003 123.187081) (xy 153.677 122.999) (xy 153.456323 123.001749)
				(xy 153.454515 123.165835) (xy 153.452 123.346584)
			)
		)
	)
	(zone
		(net 894)
		(net_name "Net-(J2B-MOD_{ABS})")
		(layer "In5.Cu")
		(name "$teardrop_padvia$")
		(hatch none 0.1)
		(priority 30274)
		(attr
			(teardrop
				(type padvia)
			)
		)
		(connect_pads yes
			(clearance 0)
		)
		(min_thickness 0.0254)
		(filled_areas_thickness no)
		(fill yes
			(thermal_gap 0.5)
			(thermal_bridge_width 0.5)
			(island_removal_mode 1)
			(island_area_min 10)
		)
		(polygon
			(pts
				(xy 166.860873 148.027515) (xy 166.913382 147.981819) (xy 166.959376 147.955231) (xy 167.045824 147.934847)
				(xy 167.06116 147.933011) (xy 167.143895 147.920677) (xy 167.100707 147.699293) (xy 166.879323 147.656105)
				(xy 166.866988 147.738841) (xy 166.846651 147.836119) (xy 166.819943 147.884159) (xy 166.772485 147.939127)
			)
		)
	)
	(zone
		(net 528)
		(net_name "/Backplane/~{PERST}")
		(layer "In5.Cu")
		(name "$teardrop_padvia$")
		(hatch none 0.1)
		(priority 30171)
		(attr
			(teardrop
				(type padvia)
			)
		)
		(connect_pads yes
			(clearance 0)
		)
		(min_thickness 0.0254)
		(filled_areas_thickness no)
		(fill yes
			(thermal_gap 0.5)
			(thermal_bridge_width 0.5)
			(island_removal_mode 1)
			(island_area_min 10)
		)
		(polygon
			(pts
				(xy 158.4875 152.359323) (xy 158.482682 152.428763) (xy 158.46896 152.480087) (xy 158.422245 152.555628)
				(xy 158.412702 152.567768) (xy 158.362919 152.634997) (xy 158.55 152.761) (xy 158.737081 152.634997)
				(xy 158.687299 152.567769) (xy 158.632894 152.484603) (xy 158.61781 152.431748) (xy 158.6125 152.359323)
			)
		)
	)
	(zone
		(net 16)
		(net_name "/Com Express 7 Interfaces/PCIe_{B1x2}.RX0-")
		(layer "In5.Cu")
		(name "$teardrop_padvia$")
		(hatch none 0.1)
		(priority 30089)
		(attr
			(teardrop
				(type padvia)
			)
		)
		(connect_pads yes
			(clearance 0)
		)
		(min_thickness 0.0254)
		(filled_areas_thickness no)
		(fill yes
			(thermal_gap 0.5)
			(thermal_bridge_width 0.5)
			(island_removal_mode 1)
			(island_area_min 10)
		)
		(polygon
			(pts
				(xy 203.373 163.989416) (xy 203.379896 164.126751) (xy 203.384276 164.207939) (xy 203.372823 164.306105)
				(xy 203.5935 164.351) (xy 203.753189 164.197605) (xy 203.685691 164.148527) (xy 203.65719 164.134188)
				(xy 203.616571 164.112889) (xy 203.582738 164.086198) (xy 203.559583 164.047309) (xy 203.551 163.989416)
			)
		)
	)
	(zone
		(net 47)
		(net_name "/2xUSB3.0+RJ45/USBSS_1.TX-")
		(layer "In5.Cu")
		(name "$teardrop_padvia$")
		(hatch none 0.1)
		(priority 30149)
		(attr
			(teardrop
				(type padvia)
			)
		)
		(connect_pads yes
			(clearance 0)
		)
		(min_thickness 0.0254)
		(filled_areas_thickness no)
		(fill yes
			(thermal_gap 0.5)
			(thermal_bridge_width 0.5)
			(island_removal_mode 1)
			(island_area_min 10)
		)
		(polygon
			(pts
				(xy 180.014 149.198916) (xy 180.009242 149.240486) (xy 179.995936 149.270544) (xy 179.951424 149.306646)
				(xy 179.909043 149.324196) (xy 179.827497 149.362919) (xy 179.9525 149.551) (xy 180.173177 149.506105)
				(xy 180.162675 149.429686) (xy 180.163114 149.369066) (xy 180.166226 149.33169) (xy 180.173 149.198916)
			)
		)
	)
	(zone
		(net 372)
		(net_name "/Com Express 7 MGMT/I2C.SDA")
		(layer "In5.Cu")
		(name "$teardrop_padvia$")
		(hatch none 0.1)
		(priority 30164)
		(attr
			(teardrop
				(type padvia)
			)
		)
		(connect_pads yes
			(clearance 0)
		)
		(min_thickness 0.0254)
		(filled_areas_thickness no)
		(fill yes
			(thermal_gap 0.5)
			(thermal_bridge_width 0.5)
			(island_removal_mode 1)
			(island_area_min 10)
		)
		(polygon
			(pts
				(xy 258.5875 89.139322) (xy 258.582682 89.208762) (xy 258.56896 89.260086) (xy 258.522245 89.335627)
				(xy 258.512702 89.347767) (xy 258.462919 89.414996) (xy 258.65 89.540999) (xy 258.837081 89.414996)
				(xy 258.787299 89.347768) (xy 258.732894 89.264602) (xy 258.71781 89.211747) (xy 258.7125 89.139322)
			)
		)
	)
	(zone
		(net 65)
		(net_name "+12V")
		(layer "In5.Cu")
		(name "$teardrop_padvia$")
		(hatch none 0.1)
		(priority 30045)
		(attr
			(teardrop
				(type padvia)
			)
		)
		(connect_pads yes
			(clearance 0)
		)
		(min_thickness 0.0254)
		(filled_areas_thickness no)
		(fill yes
			(thermal_gap 0.5)
			(thermal_bridge_width 0.5)
			(island_removal_mode 1)
			(island_area_min 10)
		)
		(polygon
			(pts
				(xy 282.070917 85.937158) (xy 282.108524 85.941902) (xy 282.135056 85.955107) (xy 282.16465 85.999008)
				(xy 282.177617 86.043329) (xy 282.190963 86.089742) (xy 282.212919 86.135003) (xy 282.401 86.01)
				(xy 282.416097 85.789323) (xy 282.275427 85.764277) (xy 282.190616 85.745628) (xy 282.070917 85.737158)
			)
		)
	)
	(zone
		(net 11)
		(net_name "/Com Express 7 Interfaces/PCIe_{B1x2}.TX0-")
		(layer "In5.Cu")
		(name "$teardrop_padvia$")
		(hatch none 0.1)
		(priority 30049)
		(attr
			(teardrop
				(type padvia)
			)
		)
		(connect_pads yes
			(clearance 0)
		)
		(min_thickness 0.0254)
		(filled_areas_thickness no)
		(fill yes
			(thermal_gap 0.5)
			(thermal_bridge_width 0.5)
			(island_removal_mode 1)
			(island_area_min 10)
		)
		(polygon
			(pts
				(xy 204.363505 124.256211) (xy 204.334149 124.220151) (xy 204.318829 124.186184) (xy 204.317841 124.121721)
				(xy 204.330164 124.074896) (xy 204.344134 124.021576) (xy 204.349073 123.961436) (xy 204.127689 123.970897)
				(xy 204.003393 124.158685) (xy 204.074186 124.211638) (xy 204.12457 124.260809) (xy 204.150085 124.288949)
				(xy 204.23764 124.382076)
			)
		)
	)
	(zone
		(net 734)
		(net_name "Net-(U43A-LOSA)")
		(layer "In5.Cu")
		(name "$teardrop_padvia$")
		(hatch none 0.1)
		(priority 30220)
		(attr
			(teardrop
				(type padvia)
			)
		)
		(connect_pads yes
			(clearance 0)
		)
		(min_thickness 0.0254)
		(filled_areas_thickness no)
		(fill yes
			(thermal_gap 0.5)
			(thermal_bridge_width 0.5)
			(island_removal_mode 1)
			(island_area_min 10)
		)
		(polygon
			(pts
				(xy 149.9125 130.910677) (xy 149.917318 130.841236) (xy 149.93104 130.789912) (xy 149.977755 130.71437)
				(xy 149.987299 130.702229) (xy 150.037081 130.635003) (xy 149.85 130.509) (xy 149.662919 130.635003)
				(xy 149.712701 130.702231) (xy 149.767106 130.785397) (xy 149.78219 130.838251) (xy 149.7875 130.910677)
			)
		)
	)
	(zone
		(net 74)
		(net_name "+1V0")
		(layer "In5.Cu")
		(name "$teardrop_padvia$")
		(hatch none 0.1)
		(priority 30021)
		(attr
			(teardrop
				(type padvia)
			)
		)
		(connect_pads yes
			(clearance 0)
		)
		(min_thickness 0.0254)
		(filled_areas_thickness no)
		(fill yes
			(thermal_gap 0.5)
			(thermal_bridge_width 0.5)
			(island_removal_mode 1)
			(island_area_min 10)
		)
		(polygon
			(pts
				(xy 302.25261 115.085969) (xy 302.194186 115.137728) (xy 302.143436 115.17011) (xy 302.049299 115.204708)
				(xy 301.95888 115.234741) (xy 302.039293 115.440707) (xy 302.245257 115.521121) (xy 302.27529 115.430703)
				(xy 302.310762 115.334889) (xy 302.342979 115.284885) (xy 302.394031 115.22739)
			)
		)
	)
	(zone
		(net 77)
		(net_name "+5V_AON")
		(layer "In5.Cu")
		(name "$teardrop_padvia$")
		(hatch none 0.1)
		(priority 30027)
		(attr
			(teardrop
				(type padvia)
			)
		)
		(connect_pads yes
			(clearance 0)
		)
		(min_thickness 0.0254)
		(filled_areas_thickness no)
		(fill yes
			(thermal_gap 0.5)
			(thermal_bridge_width 0.5)
			(island_removal_mode 1)
			(island_area_min 10)
		)
		(polygon
			(pts
				(xy 188.496 74.456194) (xy 188.554423 74.404435) (xy 188.605173 74.372052) (xy 188.699313 74.337453)
				(xy 188.789731 74.30742) (xy 188.709317 74.101456) (xy 188.503351 74.021043) (xy 188.473318 74.111462)
				(xy 188.437847 74.207275) (xy 188.40563 74.257278) (xy 188.354579 74.314773)
			)
		)
	)
	(zone
		(net 875)
		(net_name "/2xSFP+/SCL1")
		(layer "In5.Cu")
		(name "$teardrop_padvia$")
		(hatch none 0.1)
		(priority 30200)
		(attr
			(teardrop
				(type padvia)
			)
		)
		(connect_pads yes
			(clearance 0)
		)
		(min_thickness 0.0254)
		(filled_areas_thickness no)
		(fill yes
			(thermal_gap 0.5)
			(thermal_bridge_width 0.5)
			(island_removal_mode 1)
			(island_area_min 10)
		)
		(polygon
			(pts
				(xy 167.9625 148.700677) (xy 167.967318 148.631236) (xy 167.98104 148.579912) (xy 168.027755 148.50437)
				(xy 168.037299 148.492229) (xy 168.087081 148.425003) (xy 167.9 148.299) (xy 167.712919 148.425003)
				(xy 167.762701 148.492231) (xy 167.817106 148.575397) (xy 167.83219 148.628251) (xy 167.8375 148.700677)
			)
		)
	)
	(zone
		(net 587)
		(net_name "/M.2 key E/SUSCLK")
		(layer "In5.Cu")
		(name "$teardrop_padvia$")
		(hatch none 0.1)
		(priority 30256)
		(attr
			(teardrop
				(type padvia)
			)
		)
		(connect_pads yes
			(clearance 0)
		)
		(min_thickness 0.0254)
		(filled_areas_thickness no)
		(fill yes
			(thermal_gap 0.5)
			(thermal_bridge_width 0.5)
			(island_removal_mode 1)
			(island_area_min 10)
		)
		(polygon
			(pts
				(xy 302.622485 84.250873) (xy 302.668181 84.303382) (xy 302.694768 84.349376) (xy 302.715152 84.435825)
				(xy 302.716988 84.451158) (xy 302.729323 84.533895) (xy 302.950707 84.490707) (xy 302.993895 84.269323)
				(xy 302.911158 84.256988) (xy 302.81388 84.236651) (xy 302.76584 84.209943) (xy 302.710873 84.162485)
			)
		)
	)
	(zone
		(net 744)
		(net_name "/2xSFP+/KR to SFI #2/TMS")
		(layer "In5.Cu")
		(name "$teardrop_padvia$")
		(hatch none 0.1)
		(priority 30138)
		(attr
			(teardrop
				(type padvia)
			)
		)
		(connect_pads yes
			(clearance 0)
		)
		(min_thickness 0.0254)
		(filled_areas_thickness no)
		(fill yes
			(thermal_gap 0.5)
			(thermal_bridge_width 0.5)
			(island_removal_mode 1)
			(island_area_min 10)
		)
		(polygon
			(pts
				(xy 137.295176 138.431437) (xy 137.238145 138.494936) (xy 137.201859 138.548222) (xy 137.169218 138.613337)
				(xy 137.102919 138.734997) (xy 137.289293 138.860707) (xy 137.477081 138.734997) (xy 137.417088 138.667769)
				(xy 137.382686 138.632397) (xy 137.359823 138.597482) (xy 137.357211 138.560724) (xy 137.383563 138.519824)
			)
		)
	)
	(zone
		(net 237)
		(net_name "/Com Express 7 Interfaces/PCIe_{B2Bx4}.RX3-")
		(layer "In5.Cu")
		(name "$teardrop_padvia$")
		(hatch none 0.1)
		(priority 30061)
		(attr
			(teardrop
				(type padvia)
			)
		)
		(connect_pads yes
			(clearance 0)
		)
		(min_thickness 0.0254)
		(filled_areas_thickness no)
		(fill yes
			(thermal_gap 0.5)
			(thermal_bridge_width 0.5)
			(island_removal_mode 1)
			(island_area_min 10)
		)
		(polygon
			(pts
				(xy 187.160584 127.124) (xy 187.115854 127.119259) (xy 187.082389 127.106069) (xy 187.038876 127.061306)
				(xy 187.015811 127.017809) (xy 186.989834 126.968871) (xy 186.952394 126.92181) (xy 186.799 127.0815)
				(xy 186.843895 127.302177) (xy 186.920958 127.291552) (xy 186.98266 127.291818) (xy 187.023248 127.295104)
				(xy 187.160584 127.302)
			)
		)
	)
	(zone
		(net 377)
		(net_name "/Com Express 7 Interfaces/USB1.D-")
		(layer "In5.Cu")
		(name "$teardrop_padvia$")
		(hatch none 0.1)
		(priority 30157)
		(attr
			(teardrop
				(type padvia)
			)
		)
		(connect_pads yes
			(clearance 0)
		)
		(min_thickness 0.0254)
		(filled_areas_thickness no)
		(fill yes
			(thermal_gap 0.5)
			(thermal_bridge_width 0.5)
			(island_removal_mode 1)
			(island_area_min 10)
		)
		(polygon
			(pts
				(xy 197.513699 164.667191) (xy 197.480939 164.693221) (xy 197.450276 164.705067) (xy 197.393274 164.699119)
				(xy 197.350897 164.681562) (xy 197.265853 164.651281) (xy 197.221251 164.872665) (xy 197.409039 164.996961)
				(xy 197.455648 164.935499) (xy 197.498822 164.892946) (xy 197.527454 164.868715) (xy 197.626129 164.779621)
			)
		)
	)
	(zone
		(net 531)
		(net_name "/Com Express 7 Interfaces/SD_CD")
		(layer "In5.Cu")
		(name "$teardrop_padvia$")
		(hatch none 0.1)
		(priority 30287)
		(attr
			(teardrop
				(type padvia)
			)
		)
		(connect_pads yes
			(clearance 0)
		)
		(min_thickness 0.0254)
		(filled_areas_thickness no)
		(fill yes
			(thermal_gap 0.5)
			(thermal_bridge_width 0.5)
			(island_removal_mode 1)
			(island_area_min 10)
		)
		(polygon
			(pts
				(xy 113.827515 139.599127) (xy 113.781819 139.546618) (xy 113.755231 139.500623) (xy 113.734847 139.414175)
				(xy 113.733011 139.39884) (xy 113.720677 139.316105) (xy 113.499293 139.359293) (xy 113.456105 139.580677)
				(xy 113.53884 139.593011) (xy 113.636119 139.613349) (xy 113.684159 139.640057) (xy 113.739127 139.687515)
			)
		)
	)
	(zone
		(net 321)
		(net_name "/Com Express 7 Interfaces/SDIO.DAT0")
		(layer "In5.Cu")
		(name "$teardrop_padvia$")
		(hatch none 0.1)
		(priority 30035)
		(attr
			(teardrop
				(type padvia)
			)
		)
		(connect_pads yes
			(clearance 0)
		)
		(min_thickness 0.0254)
		(filled_areas_thickness no)
		(fill yes
			(thermal_gap 0.5)
			(thermal_bridge_width 0.5)
			(island_removal_mode 1)
			(island_area_min 10)
		)
		(polygon
			(pts
				(xy 114.080677 132.9725) (xy 114.012314 132.967809) (xy 113.96003 132.954974) (xy 113.870652 132.906057)
				(xy 113.767778 132.8475) (xy 113.679 133.05) (xy 113.767778 133.2525) (xy 113.870651 133.193943)
				(xy 113.954447 133.147067) (xy 114.008713 133.132761) (xy 114.080677 133.1275)
			)
		)
	)
	(zone
		(net 748)
		(net_name "Net-(U45C-AMUXA)")
		(layer "In5.Cu")
		(name "$teardrop_padvia$")
		(hatch none 0.1)
		(priority 30193)
		(attr
			(teardrop
				(type padvia)
			)
		)
		(connect_pads yes
			(clearance 0)
		)
		(min_thickness 0.0254)
		(filled_areas_thickness no)
		(fill yes
			(thermal_gap 0.5)
			(thermal_bridge_width 0.5)
			(island_removal_mode 1)
			(island_area_min 10)
		)
		(polygon
			(pts
				(xy 129.8025 130.540677) (xy 129.807318 130.471236) (xy 129.82104 130.419912) (xy 129.867755 130.34437)
				(xy 129.877299 130.332229) (xy 129.927081 130.265003) (xy 129.74 130.139) (xy 129.552919 130.265003)
				(xy 129.602701 130.332231) (xy 129.657106 130.415397) (xy 129.67219 130.468251) (xy 129.6775 130.540677)
			)
		)
	)
	(zone
		(net 160)
		(net_name "/2xUSB3.0+RJ45/USBSS_2.RX-")
		(layer "In5.Cu")
		(name "$teardrop_padvia$")
		(hatch none 0.1)
		(priority 30150)
		(attr
			(teardrop
				(type padvia)
			)
		)
		(connect_pads yes
			(clearance 0)
		)
		(min_thickness 0.0254)
		(filled_areas_thickness no)
		(fill yes
			(thermal_gap 0.5)
			(thermal_bridge_width 0.5)
			(island_removal_mode 1)
			(island_area_min 10)
		)
		(polygon
			(pts
				(xy 127.564 107.398916) (xy 127.559242 107.440486) (xy 127.545936 107.470544) (xy 127.501424 107.506646)
				(xy 127.459043 107.524196) (xy 127.377497 107.562919) (xy 127.5025 107.751) (xy 127.723177 107.706105)
				(xy 127.712675 107.629686) (xy 127.713114 107.569066) (xy 127.716226 107.53169) (xy 127.723 107.398916)
			)
		)
	)
	(zone
		(net 755)
		(net_name "Net-(U45A-LS_OK_{IN_A})")
		(layer "In5.Cu")
		(name "$teardrop_padvia$")
		(hatch none 0.1)
		(priority 30204)
		(attr
			(teardrop
				(type padvia)
			)
		)
		(connect_pads yes
			(clearance 0)
		)
		(min_thickness 0.0254)
		(filled_areas_thickness no)
		(fill yes
			(thermal_gap 0.5)
			(thermal_bridge_width 0.5)
			(island_removal_mode 1)
			(island_area_min 10)
		)
		(polygon
			(pts
				(xy 137.6025 130.540677) (xy 137.607318 130.471236) (xy 137.62104 130.419912) (xy 137.667755 130.34437)
				(xy 137.677299 130.332229) (xy 137.727081 130.265003) (xy 137.54 130.139) (xy 137.352919 130.265003)
				(xy 137.402701 130.332231) (xy 137.457106 130.415397) (xy 137.47219 130.468251) (xy 137.4775 130.540677)
			)
		)
	)
	(zone
		(net 725)
		(net_name "/2xSFP+/KR to SFI #1/TCK")
		(layer "In5.Cu")
		(name "$teardrop_padvia$")
		(hatch none 0.1)
		(priority 30239)
		(attr
			(teardrop
				(type padvia)
			)
		)
		(connect_pads yes
			(clearance 0)
		)
		(min_thickness 0.0254)
		(filled_areas_thickness no)
		(fill yes
			(thermal_gap 0.5)
			(thermal_bridge_width 0.5)
			(island_removal_mode 1)
			(island_area_min 10)
		)
		(polygon
			(pts
				(xy 153.689127 138.532485) (xy 153.636618 138.578181) (xy 153.590623 138.604768) (xy 153.504174 138.625152)
				(xy 153.488841 138.626988) (xy 153.406105 138.639323) (xy 153.449293 138.860707) (xy 153.670677 138.903895)
				(xy 153.683011 138.82116) (xy 153.703349 138.723881) (xy 153.730057 138.675841) (xy 153.777515 138.620873)
			)
		)
	)
	(zone
		(net 531)
		(net_name "/Com Express 7 Interfaces/SD_CD")
		(layer "In5.Cu")
		(name "$teardrop_padvia$")
		(hatch none 0.1)
		(priority 30224)
		(attr
			(teardrop
				(type padvia)
			)
		)
		(connect_pads yes
			(clearance 0)
		)
		(min_thickness 0.0254)
		(filled_areas_thickness no)
		(fill yes
			(thermal_gap 0.5)
			(thermal_bridge_width 0.5)
			(island_removal_mode 1)
			(island_area_min 10)
		)
		(polygon
			(pts
				(xy 145.650677 148.7875) (xy 145.581236 148.782682) (xy 145.529913 148.76896) (xy 145.454371 148.722246)
				(xy 145.442231 148.712701) (xy 145.375003 148.662919) (xy 145.249 148.85) (xy 145.375003 149.037081)
				(xy 145.442229 148.987299) (xy 145.525396 148.932894) (xy 145.578251 148.91781) (xy 145.650677 148.9125)
			)
		)
	)
	(zone
		(net 737)
		(net_name "Net-(U43B-LOSB)")
		(layer "In5.Cu")
		(name "$teardrop_padvia$")
		(hatch none 0.1)
		(priority 30260)
		(attr
			(teardrop
				(type padvia)
			)
		)
		(connect_pads yes
			(clearance 0)
		)
		(min_thickness 0.0254)
		(filled_areas_thickness no)
		(fill yes
			(thermal_gap 0.5)
			(thermal_bridge_width 0.5)
			(island_removal_mode 1)
			(island_area_min 10)
		)
		(polygon
			(pts
				(xy 147.122485 138.620873) (xy 147.168181 138.673382) (xy 147.194768 138.719376) (xy 147.215152 138.805825)
				(xy 147.216988 138.821158) (xy 147.229323 138.903895) (xy 147.450707 138.860707) (xy 147.493895 138.639323)
				(xy 147.411158 138.626988) (xy 147.31388 138.606651) (xy 147.26584 138.579943) (xy 147.210873 138.532485)
			)
		)
	)
	(zone
		(net 241)
		(net_name "/Com Express 7 Interfaces/PCIe_{B2Bx4}.TX3-")
		(layer "In5.Cu")
		(name "$teardrop_padvia$")
		(hatch none 0.1)
		(priority 30083)
		(attr
			(teardrop
				(type padvia)
			)
		)
		(connect_pads yes
			(clearance 0)
		)
		(min_thickness 0.0254)
		(filled_areas_thickness no)
		(fill yes
			(thermal_gap 0.5)
			(thermal_bridge_width 0.5)
			(island_removal_mode 1)
			(island_area_min 10)
		)
		(polygon
			(pts
				(xy 186.873 166.639416) (xy 186.879896 166.776751) (xy 186.884276 166.857939) (xy 186.872823 166.956105)
				(xy 187.0935 167.001) (xy 187.253189 166.847605) (xy 187.185691 166.798527) (xy 187.15719 166.784188)
				(xy 187.116571 166.762889) (xy 187.082738 166.736198) (xy 187.059583 166.697309) (xy 187.051 166.639416)
			)
		)
	)
	(zone
		(net 731)
		(net_name "Net-(U43C-CLKOUTA-)")
		(layer "In5.Cu")
		(name "$teardrop_padvia$")
		(hatch none 0.1)
		(priority 30268)
		(attr
			(teardrop
				(type padvia)
			)
		)
		(connect_pads yes
			(clearance 0)
		)
		(min_thickness 0.0254)
		(filled_areas_thickness no)
		(fill yes
			(thermal_gap 0.5)
			(thermal_bridge_width 0.5)
			(island_removal_mode 1)
			(island_area_min 10)
		)
		(polygon
			(pts
				(xy 154.122485 140.620873) (xy 154.168181 140.673382) (xy 154.194768 140.719376) (xy 154.215152 140.805825)
				(xy 154.216988 140.821158) (xy 154.229323 140.903895) (xy 154.450707 140.860707) (xy 154.493895 140.639323)
				(xy 154.411158 140.626988) (xy 154.31388 140.606651) (xy 154.26584 140.579943) (xy 154.210873 140.532485)
			)
		)
	)
	(zone
		(net 324)
		(net_name "/Com Express 7 Interfaces/PCIe_{B2Ax4}.TX0+")
		(layer "In5.Cu")
		(name "$teardrop_padvia$")
		(hatch none 0.1)
		(priority 30105)
		(attr
			(teardrop
				(type padvia)
			)
		)
		(connect_pads yes
			(clearance 0)
		)
		(min_thickness 0.0254)
		(filled_areas_thickness no)
		(fill yes
			(thermal_gap 0.5)
			(thermal_bridge_width 0.5)
			(island_removal_mode 1)
			(island_area_min 10)
		)
		(polygon
			(pts
				(xy 228.202 143.756084) (xy 228.198302 143.589599) (xy 228.197677 143.40947) (xy 227.977 143.399)
				(xy 227.851997 143.587081) (xy 227.921529 143.623424) (xy 227.961495 143.642701) (xy 227.994058 143.666786)
				(xy 228.015974 143.702356) (xy 228.024 143.756084)
			)
		)
	)
	(zone
		(net 239)
		(net_name "/Com Express 7 Interfaces/PCIe_{B2Bx4}.RX3+")
		(layer "In5.Cu")
		(name "$teardrop_padvia$")
		(hatch none 0.1)
		(priority 30092)
		(attr
			(teardrop
				(type padvia)
			)
		)
		(connect_pads yes
			(clearance 0)
		)
		(min_thickness 0.0254)
		(filled_areas_thickness no)
		(fill yes
			(thermal_gap 0.5)
			(thermal_bridge_width 0.5)
			(island_removal_mode 1)
			(island_area_min 10)
		)
		(polygon
			(pts
				(xy 187.160584 127.498) (xy 187.023248 127.504896) (xy 186.942061 127.509276) (xy 186.843895 127.497823)
				(xy 186.799 127.7185) (xy 186.952394 127.878189) (xy 187.001472 127.810692) (xy 187.015811 127.78219)
				(xy 187.03711 127.741571) (xy 187.063802 127.707738) (xy 187.102691 127.684583) (xy 187.160584 127.676)
			)
		)
	)
	(zone
		(net 721)
		(net_name "Net-(U43C-REFCLK1-)")
		(layer "In5.Cu")
		(name "$teardrop_padvia$")
		(hatch none 0.1)
		(priority 30271)
		(attr
			(teardrop
				(type padvia)
			)
		)
		(connect_pads yes
			(clearance 0)
		)
		(min_thickness 0.0254)
		(filled_areas_thickness no)
		(fill yes
			(thermal_gap 0.5)
			(thermal_bridge_width 0.5)
			(island_removal_mode 1)
			(island_area_min 10)
		)
		(polygon
			(pts
				(xy 147.122485 140.620873) (xy 147.168181 140.673382) (xy 147.194768 140.719376) (xy 147.215152 140.805825)
				(xy 147.216988 140.821158) (xy 147.229323 140.903895) (xy 147.450707 140.860707) (xy 147.493895 140.639323)
				(xy 147.411158 140.626988) (xy 147.31388 140.606651) (xy 147.26584 140.579943) (xy 147.210873 140.532485)
			)
		)
	)
	(zone
		(net 243)
		(net_name "/Com Express 7 Interfaces/PCIe_{B2Bx4}.RX2-")
		(layer "In5.Cu")
		(name "$teardrop_padvia$")
		(hatch none 0.1)
		(priority 30096)
		(attr
			(teardrop
				(type padvia)
			)
		)
		(connect_pads yes
			(clearance 0)
		)
		(min_thickness 0.0254)
		(filled_areas_thickness no)
		(fill yes
			(thermal_gap 0.5)
			(thermal_bridge_width 0.5)
			(island_removal_mode 1)
			(island_area_min 10)
		)
		(polygon
			(pts
				(xy 187.156084 125.524) (xy 187.113152 125.519241) (xy 187.081738 125.505928) (xy 187.042448 125.461041)
				(xy 187.023424 125.421529) (xy 186.987081 125.351997) (xy 186.799 125.477) (xy 186.80947 125.697677)
				(xy 186.989599 125.698302) (xy 187.156084 125.702)
			)
		)
	)
	(zone
		(net 78)
		(net_name "+1V8")
		(layer "In5.Cu")
		(name "$teardrop_padvia$")
		(hatch none 0.1)
		(priority 30025)
		(attr
			(teardrop
				(type padvia)
			)
		)
		(connect_pads yes
			(clearance 0)
		)
		(min_thickness 0.0254)
		(filled_areas_thickness no)
		(fill yes
			(thermal_gap 0.5)
			(thermal_bridge_width 0.5)
			(island_removal_mode 1)
			(island_area_min 10)
		)
		(polygon
			(pts
				(xy 200.962641 73.014773) (xy 200.910882 72.956349) (xy 200.878499 72.905599) (xy 200.8439 72.81146)
				(xy 200.813867 72.721042) (xy 200.607903 72.801456) (xy 200.527489 73.00742) (xy 200.617907 73.037453)
				(xy 200.713721 73.072925) (xy 200.763724 73.105142) (xy 200.82122 73.156194)
			)
		)
	)
	(zone
		(net 528)
		(net_name "/Backplane/~{PERST}")
		(layer "In5.Cu")
		(name "$teardrop_padvia$")
		(hatch none 0.1)
		(priority 30279)
		(attr
			(teardrop
				(type padvia)
			)
		)
		(connect_pads yes
			(clearance 0)
		)
		(min_thickness 0.0254)
		(filled_areas_thickness no)
		(fill yes
			(thermal_gap 0.5)
			(thermal_bridge_width 0.5)
			(island_removal_mode 1)
			(island_area_min 10)
		)
		(polygon
			(pts
				(xy 309.077515 156.949127) (xy 309.031819 156.896618) (xy 309.005231 156.850623) (xy 308.984847 156.764175)
				(xy 308.983011 156.74884) (xy 308.970677 156.666105) (xy 308.749293 156.709293) (xy 308.706105 156.930677)
				(xy 308.78884 156.943011) (xy 308.886119 156.963349) (xy 308.934159 156.990057) (xy 308.989127 157.037515)
			)
		)
	)
	(zone
		(net 333)
		(net_name "/Com Express 7 Interfaces/SDIO.DAT3")
		(layer "In5.Cu")
		(name "$teardrop_padvia$")
		(hatch none 0.1)
		(priority 30048)
		(attr
			(teardrop
				(type padvia)
			)
		)
		(connect_pads yes
			(clearance 0)
		)
		(min_thickness 0.0254)
		(filled_areas_thickness no)
		(fill yes
			(thermal_gap 0.5)
			(thermal_bridge_width 0.5)
			(island_removal_mode 1)
			(island_area_min 10)
		)
		(polygon
			(pts
				(xy 165.574323 162.7775) (xy 165.650367 162.782173) (xy 165.707852 162.794885) (xy 165.79387 162.833821)
				(xy 165.899641 162.882644) (xy 165.976 162.675) (xy 165.849997 162.487919) (xy 165.77642 162.5449)
				(xy 165.69688 162.600639) (xy 165.645075 162.616727) (xy 165.574323 162.6225)
			)
		)
	)
	(zone
		(net 9)
		(net_name "/Com Express 7 Interfaces/PCIe_{B1x2}.TX0+")
		(layer "In5.Cu")
		(name "$teardrop_padvia$")
		(hatch none 0.1)
		(priority 30046)
		(attr
			(teardrop
				(type padvia)
			)
		)
		(connect_pads yes
			(clearance 0)
		)
		(min_thickness 0.0254)
		(filled_areas_thickness no)
		(fill yes
			(thermal_gap 0.5)
			(thermal_bridge_width 0.5)
			(island_removal_mode 1)
			(island_area_min 10)
		)
		(polygon
			(pts
				(xy 202.987 166.63064) (xy 202.98226 166.677467) (xy 202.969083 166.712822) (xy 202.92417 166.760161)
				(xy 202.88366 166.784747) (xy 202.836861 166.81328) (xy 202.7915 166.852915) (xy 202.9565 167.001)
				(xy 203.177177 166.956105) (xy 203.163065 166.860507) (xy 203.161505 166.782619) (xy 203.162627 166.747342)
				(xy 203.165 166.63064)
			)
		)
	)
	(zone
		(net 358)
		(net_name "/Com Express 7 MGMT/SMBus.SDA")
		(layer "In5.Cu")
		(name "$teardrop_padvia$")
		(hatch none 0.1)
		(priority 30281)
		(attr
			(teardrop
				(type padvia)
			)
		)
		(connect_pads yes
			(clearance 0)
		)
		(min_thickness 0.0254)
		(filled_areas_thickness no)
		(fill yes
			(thermal_gap 0.5)
			(thermal_bridge_width 0.5)
			(island_removal_mode 1)
			(island_area_min 10)
		)
		(polygon
			(pts
				(xy 159.277515 148.464127) (xy 159.231819 148.411618) (xy 159.205231 148.365623) (xy 159.184847 148.279175)
				(xy 159.183011 148.26384) (xy 159.170677 148.181105) (xy 158.949293 148.224293) (xy 158.906105 148.445677)
				(xy 158.98884 148.458011) (xy 159.086119 148.478349) (xy 159.134159 148.505057) (xy 159.189127 148.552515)
			)
		)
	)
	(zone
		(net 371)
		(net_name "/Com Express 7 MGMT/I2C.SCL")
		(layer "In5.Cu")
		(name "$teardrop_padvia$")
		(hatch none 0.1)
		(priority 30283)
		(attr
			(teardrop
				(type padvia)
			)
		)
		(connect_pads yes
			(clearance 0)
		)
		(min_thickness 0.0254)
		(filled_areas_thickness no)
		(fill yes
			(thermal_gap 0.5)
			(thermal_bridge_width 0.5)
			(island_removal_mode 1)
			(island_area_min 10)
		)
		(polygon
			(pts
				(xy 302.504515 94.929127) (xy 302.458819 94.876618) (xy 302.432231 94.830623) (xy 302.411847 94.744175)
				(xy 302.410011 94.72884) (xy 302.397677 94.646105) (xy 302.176293 94.689293) (xy 302.133105 94.910677)
				(xy 302.21584 94.923011) (xy 302.313119 94.943349) (xy 302.361159 94.970057) (xy 302.416127 95.017515)
			)
		)
	)
	(zone
		(net 331)
		(net_name "/Com Express 7 Interfaces/PCIe_{B2Ax4}.TX3-")
		(layer "In5.Cu")
		(name "$teardrop_padvia$")
		(hatch none 0.1)
		(priority 30072)
		(attr
			(teardrop
				(type padvia)
			)
		)
		(connect_pads yes
			(clearance 0)
		)
		(min_thickness 0.0254)
		(filled_areas_thickness no)
		(fill yes
			(thermal_gap 0.5)
			(thermal_bridge_width 0.5)
			(island_removal_mode 1)
			(island_area_min 10)
		)
		(polygon
			(pts
				(xy 216.551 167.410584) (xy 216.555741 167.365854) (xy 216.568931 167.332389) (xy 216.613694 167.288875)
				(xy 216.65719 167.265811) (xy 216.706128 167.239834) (xy 216.753189 167.202394) (xy 216.5935 167.049)
				(xy 216.372823 167.093895) (xy 216.383447 167.170959) (xy 216.383182 167.232662) (xy 216.379896 167.273248)
				(xy 216.373 167.410584)
			)
		)
	)
	(zone
		(net 731)
		(net_name "Net-(U43C-CLKOUTA-)")
		(layer "In5.Cu")
		(name "$teardrop_padvia$")
		(hatch none 0.1)
		(priority 30216)
		(attr
			(teardrop
				(type padvia)
			)
		)
		(connect_pads yes
			(clearance 0)
		)
		(min_thickness 0.0254)
		(filled_areas_thickness no)
		(fill yes
			(thermal_gap 0.5)
			(thermal_bridge_width 0.5)
			(island_removal_mode 1)
			(island_area_min 10)
		)
		(polygon
			(pts
				(xy 148.6125 130.910677) (xy 148.617318 130.841236) (xy 148.63104 130.789912) (xy 148.677755 130.71437)
				(xy 148.687299 130.702229) (xy 148.737081 130.635003) (xy 148.55 130.509) (xy 148.362919 130.635003)
				(xy 148.412701 130.702231) (xy 148.467106 130.785397) (xy 148.48219 130.838251) (xy 148.4875 130.910677)
			)
		)
	)
	(zone
		(net 400)
		(net_name "/Com Express 7 MGMT/FAN_PWM")
		(layer "In5.Cu")
		(name "$teardrop_padvia$")
		(hatch none 0.1)
		(priority 30288)
		(attr
			(teardrop
				(type padvia)
			)
		)
		(connect_pads yes
			(clearance 0)
		)
		(min_thickness 0.0254)
		(filled_areas_thickness no)
		(fill yes
			(thermal_gap 0.5)
			(thermal_bridge_width 0.5)
			(island_removal_mode 1)
			(island_area_min 10)
		)
		(polygon
			(pts
				(xy 241.748223 77.424127) (xy 241.702527 77.371618) (xy 241.675939 77.325623) (xy 241.655555 77.239175)
				(xy 241.653719 77.22384) (xy 241.641385 77.141105) (xy 241.420001 77.184293) (xy 241.376813 77.405677)
				(xy 241.459548 77.418011) (xy 241.556827 77.438349) (xy 241.604867 77.465057) (xy 241.659835 77.512515)
			)
		)
	)
	(zone
		(net 365)
		(net_name "/Com Express 7 MGMT/PWR_OK")
		(layer "In5.Cu")
		(name "$teardrop_padvia$")
		(hatch none 0.1)
		(priority 30168)
		(attr
			(teardrop
				(type padvia)
			)
		)
		(connect_pads yes
			(clearance 0)
		)
		(min_thickness 0.0254)
		(filled_areas_thickness no)
		(fill yes
			(thermal_gap 0.5)
			(thermal_bridge_width 0.5)
			(island_removal_mode 1)
			(island_area_min 10)
		)
		(polygon
			(pts
				(xy 102.3875 71.959323) (xy 102.382682 72.028763) (xy 102.36896 72.080087) (xy 102.322245 72.155628)
				(xy 102.312702 72.167768) (xy 102.262919 72.234997) (xy 102.45 72.361) (xy 102.637081 72.234997)
				(xy 102.587299 72.167769) (xy 102.532894 72.084603) (xy 102.51781 72.031748) (xy 102.5125 71.959323)
			)
		)
	)
	(zone
		(net 78)
		(net_name "+1V8")
		(layer "In5.Cu")
		(name "$teardrop_padvia$")
		(hatch none 0.1)
		(priority 30034)
		(attr
			(teardrop
				(type padvia)
			)
		)
		(connect_pads yes
			(clearance 0)
		)
		(min_thickness 0.0254)
		(filled_areas_thickness no)
		(fill yes
			(thermal_gap 0.5)
			(thermal_bridge_width 0.5)
			(island_removal_mode 1)
			(island_area_min 10)
		)
		(polygon
			(pts
				(xy 301.683969 134.66639) (xy 301.735728 134.724814) (xy 301.768111 134.775564) (xy 301.802709 134.869702)
				(xy 301.832742 134.96012) (xy 302.038707 134.879707) (xy 302.11912 134.673742) (xy 302.028702 134.643709)
				(xy 301.932888 134.608237) (xy 301.882885 134.576021) (xy 301.82539 134.524969)
			)
		)
	)
	(zone
		(net 756)
		(net_name "Net-(U45A-LS_OK_{OUT_A})")
		(layer "In5.Cu")
		(name "$teardrop_padvia$")
		(hatch none 0.1)
		(priority 30110)
		(attr
			(teardrop
				(type padvia)
			)
		)
		(connect_pads yes
			(clearance 0)
		)
		(min_thickness 0.0254)
		(filled_areas_thickness no)
		(fill yes
			(thermal_gap 0.5)
			(thermal_bridge_width 0.5)
			(island_removal_mode 1)
			(island_area_min 10)
		)
		(polygon
			(pts
				(xy 132.4725 130.539864) (xy 132.477117 130.456717) (xy 132.489439 130.39511) (xy 132.515505 130.32324)
				(xy 132.555849 130.205549) (xy 132.34 130.149) (xy 132.157699 130.279783) (xy 132.224195 130.347619)
				(xy 132.250898 130.367543) (xy 132.28818 130.396306) (xy 132.318922 130.429857) (xy 132.339802 130.475332)
				(xy 132.3475 130.539864)
			)
		)
	)
	(zone
		(net 204)
		(net_name "/Backplane/USB.D-")
		(layer "In5.Cu")
		(name "$teardrop_padvia$")
		(hatch none 0.1)
		(priority 30152)
		(attr
			(teardrop
				(type padvia)
			)
		)
		(connect_pads yes
			(clearance 0)
		)
		(min_thickness 0.0254)
		(filled_areas_thickness no)
		(fill yes
			(thermal_gap 0.5)
			(thermal_bridge_width 0.5)
			(island_removal_mode 1)
			(island_area_min 10)
		)
		(polygon
			(pts
				(xy 198.014 170.148916) (xy 198.009242 170.190486) (xy 197.995936 170.220544) (xy 197.951424 170.256646)
				(xy 197.909043 170.274196) (xy 197.827497 170.312919) (xy 197.9525 170.501) (xy 198.173177 170.456105)
				(xy 198.162675 170.379686) (xy 198.163114 170.319066) (xy 198.166226 170.28169) (xy 198.173 170.148916)
			)
		)
	)
	(zone
		(net 327)
		(net_name "/Com Express 7 Interfaces/PCIe_{B2Ax4}.TX1-")
		(layer "In5.Cu")
		(name "$teardrop_padvia$")
		(hatch none 0.1)
		(priority 30087)
		(attr
			(teardrop
				(type padvia)
			)
		)
		(connect_pads yes
			(clearance 0)
		)
		(min_thickness 0.0254)
		(filled_areas_thickness no)
		(fill yes
			(thermal_gap 0.5)
			(thermal_bridge_width 0.5)
			(island_removal_mode 1)
			(island_area_min 10)
		)
		(polygon
			(pts
				(xy 212.873 166.639416) (xy 212.879896 166.776751) (xy 212.884276 166.857939) (xy 212.872823 166.956105)
				(xy 213.0935 167.001) (xy 213.253189 166.847605) (xy 213.185691 166.798527) (xy 213.15719 166.784188)
				(xy 213.116571 166.762889) (xy 213.082738 166.736198) (xy 213.059583 166.697309) (xy 213.051 166.639416)
			)
		)
	)
	(zone
		(net 0)
		(net_name "")
		(layer "In6.Cu")
		(hatch edge 0.5)
		(connect_pads
			(clearance 0)
		)
		(min_thickness 0.25)
		(filled_areas_thickness no)
		(keepout
			(tracks not_allowed)
			(vias allowed)
			(pads allowed)
			(copperpour not_allowed)
			(footprints allowed)
		)
		(placement
			(enabled no)
			(sheetname "")
		)
		(fill
			(thermal_gap 0.5)
			(thermal_bridge_width 0.5)
		)
		(polygon
			(pts
				(xy 108.95 165.275) (xy 110.675 165.275) (xy 110.675 167.45) (xy 108.95 167.45)
			)
		)
	)
	(zone
		(net 0)
		(net_name "")
		(layer "In6.Cu")
		(hatch edge 0.5)
		(connect_pads
			(clearance 0)
		)
		(min_thickness 0.25)
		(filled_areas_thickness no)
		(keepout
			(tracks not_allowed)
			(vias allowed)
			(pads allowed)
			(copperpour not_allowed)
			(footprints allowed)
		)
		(placement
			(enabled no)
			(sheetname "")
		)
		(fill
			(thermal_gap 0.5)
			(thermal_bridge_width 0.5)
		)
		(polygon
			(pts
				(xy 107.025 163.775) (xy 108.75 163.775) (xy 108.75 165.95) (xy 107.025 165.95)
			)
		)
	)
	(zone
		(net 1)
		(net_name "GND")
		(layer "In6.Cu")
		(hatch edge 0.5)
		(priority 40)
		(connect_pads
			(clearance 0.15)
		)
		(min_thickness 0.15)
		(filled_areas_thickness no)
		(fill yes
			(thermal_gap 0.15)
			(thermal_bridge_width 0.5)
		)
		(polygon
			(pts
				(xy 112.72 100.41) (xy 112.72 110.17) (xy 105.57 110.17) (xy 105.54 110.14) (xy 105.54 100.41)
			)
		)
	)
	(zone
		(net 0)
		(net_name "")
		(layer "In6.Cu")
		(hatch edge 0.5)
		(connect_pads
			(clearance 0)
		)
		(min_thickness 0.25)
		(filled_areas_thickness no)
		(keepout
			(tracks not_allowed)
			(vias allowed)
			(pads allowed)
			(copperpour not_allowed)
			(footprints allowed)
		)
		(placement
			(enabled no)
			(sheetname "")
		)
		(fill
			(thermal_gap 0.5)
			(thermal_bridge_width 0.5)
		)
		(polygon
			(pts
				(xy 107.025 157.775) (xy 108.75 157.775) (xy 108.75 159.95) (xy 107.025 159.95)
			)
		)
	)
	(zone
		(net 0)
		(net_name "")
		(layer "In6.Cu")
		(hatch edge 0.5)
		(connect_pads
			(clearance 0)
		)
		(min_thickness 0.25)
		(filled_areas_thickness no)
		(keepout
			(tracks not_allowed)
			(vias allowed)
			(pads allowed)
			(copperpour not_allowed)
			(footprints allowed)
		)
		(placement
			(enabled no)
			(sheetname "")
		)
		(fill
			(thermal_gap 0.5)
			(thermal_bridge_width 0.5)
		)
		(polygon
			(pts
				(xy 108.95 159.275) (xy 110.675 159.275) (xy 110.675 161.45) (xy 108.95 161.45)
			)
		)
	)
)
